(kicad_pcb
	(version 20260206)
	(generator "pcbnew")
	(generator_version "10.0")
	(general
		(thickness 1.6)
		(legacy_teardrops no)
	)
	(paper "A4")
	(layers
		(0 "F.Cu" signal "TOP")
		(4 "In1.Cu" signal "GND")
		(6 "In2.Cu" signal "IN1")
		(8 "In3.Cu" signal "VCC")
		(10 "In4.Cu" signal "VCC1")
		(12 "In5.Cu" signal "IN2")
		(14 "In6.Cu" signal "GND1")
		(2 "B.Cu" signal "BOTTOM")
		(9 "F.Adhes" user "F.Adhesive")
		(11 "B.Adhes" user "B.Adhesive")
		(13 "F.Paste" user "Package Geometry/Pastemask Top")
		(15 "B.Paste" user "Package Geometry/Pastemask Bottom")
		(5 "F.SilkS" user "Ref Des/Silkscreen Top")
		(7 "B.SilkS" user "Ref Des/Silkscreen Bottom")
		(1 "F.Mask" user "Board Geometry/Soldermask Top")
		(3 "B.Mask" user "Board Geometry/Soldermask Bottom")
		(17 "Dwgs.User" user "User.Drawings")
		(19 "Cmts.User" user "User.Comments")
		(21 "Eco1.User" user "User.Eco1")
		(23 "Eco2.User" user "User.Eco2")
		(25 "Edge.Cuts" user "Board Geometry/Outline")
		(27 "Margin" user)
		(31 "F.CrtYd" user "Package Geometry/Place Bound Top")
		(29 "B.CrtYd" user "Package Geometry/Place Bound Bottom")
		(35 "F.Fab" user "Ref Des/Assembly Top")
		(33 "B.Fab" user "Ref Des/Assembly Bottom")
	)
	(setup
		(pad_to_mask_clearance 0)
		(allow_soldermask_bridges_in_footprints no)
		(tenting
			(front yes)
			(back yes)
		)
		(covering
			(front no)
			(back no)
		)
		(plugging
			(front no)
			(back no)
		)
		(capping no)
		(filling no)
		(pcbplotparams
			(layerselection 0x00000000_00000000_55555555_5755f5ff)
			(plot_on_all_layers_selection 0x00000000_00000000_00000000_00000000)
			(disableapertmacros no)
			(usegerberextensions no)
			(usegerberattributes yes)
			(usegerberadvancedattributes yes)
			(creategerberjobfile yes)
			(dashed_line_dash_ratio 12)
			(dashed_line_gap_ratio 3)
			(svgprecision 4)
			(plotframeref no)
			(mode 1)
			(useauxorigin no)
			(pdf_front_fp_property_popups yes)
			(pdf_back_fp_property_popups yes)
			(pdf_metadata yes)
			(pdf_single_document no)
			(dxfpolygonmode yes)
			(dxfimperialunits yes)
			(dxfusepcbnewfont yes)
			(psnegative no)
			(psa4output no)
			(plot_black_and_white yes)
			(sketchpadsonfab no)
			(plotpadnumbers no)
			(hidednponfab no)
			(sketchdnponfab yes)
			(crossoutdnponfab yes)
			(subtractmaskfromsilk no)
			(outputformat 1)
			(mirror no)
			(drillshape 1)
			(scaleselection 1)
			(outputdirectory "")
		)
	)
	(footprint ""
		(layer "F.Cu")
		(at 3.578352 -23.357332 180)
		(property "Reference" "JP4"
			(at 2.610104 -5.567934 0)
			(unlocked yes)
			(layer "F.SilkS")
			(effects
				(font
					(size 0.7874 0.5842)
					(thickness 0.1524)
				)
				(justify left)
			)
		)
		(property "Value" ""
			(at 0 0 180)
			(layer "F.Fab")
			(effects
				(font
					(size 1.27 1.27)
				)
			)
		)
		(duplicate_pad_numbers_are_jumpers no)
		(fp_line
			(start 2.54 1.27)
			(end -2.54 1.27)
			(stroke
				(width 0.1524)
				(type default)
			)
			(layer "F.SilkS")
		)
		(fp_line
			(start 2.54 -1.27)
			(end 2.54 1.27)
			(stroke
				(width 0.1524)
				(type default)
			)
			(layer "F.SilkS")
		)
		(fp_line
			(start -2.54 1.27)
			(end -2.54 -1.27)
			(stroke
				(width 0.1524)
				(type default)
			)
			(layer "F.SilkS")
		)
		(fp_line
			(start -2.54 -1.27)
			(end 2.54 -1.27)
			(stroke
				(width 0.1524)
				(type default)
			)
			(layer "F.SilkS")
		)
		(fp_poly
			(pts
				(xy -2.80035 0.82677) (xy -4.147566 1.347724) (xy -3.285236 2.2098)
			)
			(stroke
				(width 0)
				(type default)
			)
			(fill yes)
			(layer "F.SilkS")
		)
		(fp_poly
			(pts
				(xy -2.1082 -0.8382) (xy -2.1082 0.8382) (xy 2.1082 0.8382) (xy 2.1082 -0.8382)
			)
			(stroke
				(width 0)
				(type default)
			)
			(fill no)
			(layer "B.CrtYd")
		)
		(fp_rect
			(start -2.54 1.27)
			(end 2.54 -1.27)
			(stroke
				(width 0)
				(type default)
			)
			(fill no)
			(layer "F.CrtYd")
		)
		(fp_line
			(start 2.54 1.27)
			(end -2.54 1.27)
			(stroke
				(width 0.1)
				(type default)
			)
			(layer "F.Fab")
		)
		(fp_line
			(start 2.54 -1.27)
			(end 2.54 1.27)
			(stroke
				(width 0.1)
				(type default)
			)
			(layer "F.Fab")
		)
		(fp_line
			(start -2.54 1.27)
			(end -2.54 -1.27)
			(stroke
				(width 0.1)
				(type default)
			)
			(layer "F.Fab")
		)
		(fp_line
			(start -2.54 -1.27)
			(end 2.54 -1.27)
			(stroke
				(width 0.1)
				(type default)
			)
			(layer "F.Fab")
		)
		(fp_text user "2"
			(at 2.838704 2.026666 0)
			(unlocked yes)
			(layer "F.SilkS")
			(effects
				(font
					(size 0.7874 0.5842)
					(thickness 0.1524)
				)
				(justify left)
			)
		)
		(fp_text user "1"
			(at -2.698496 -0.843534 0)
			(unlocked yes)
			(layer "F.SilkS")
			(effects
				(font
					(size 0.7874 0.5842)
					(thickness 0.1524)
				)
				(justify left)
			)
		)
		(fp_text user "2"
			(at 2.381504 -0.132334 0)
			(unlocked yes)
			(layer "B.SilkS")
			(effects
				(font
					(size 0.7874 0.5842)
					(thickness 0.1524)
				)
				(justify left mirror)
			)
		)
		(fp_text user "1"
			(at -2.952496 -0.081534 0)
			(unlocked yes)
			(layer "B.SilkS")
			(effects
				(font
					(size 0.7874 0.5842)
					(thickness 0.1524)
				)
				(justify left mirror)
			)
		)
		(pad "1" thru_hole rect
			(at -1.27 0 180)
			(size 1.6764 1.6764)
			(drill 1.1684)
			(layers "*.Cu" "*.Mask")
			(remove_unused_layers no)
			(net "NODE1_EN")
			(clearance 0)
			(padstack
				(mode front_inner_back)
				(layer "Inner"
					(shape circle)
					(size 1.6764 1.6764)
					(clearance 0)
				)
				(layer "B.Cu"
					(shape rect)
					(size 1.6764 1.6764)
					(clearance 0)
				)
			)
		)
		(pad "2" thru_hole circle
			(at 1.27 0 180)
			(size 1.6764 1.6764)
			(drill 1.1684)
			(layers "*.Cu" "*.Mask")
			(remove_unused_layers no)
			(net "N39391900")
			(clearance 0)
		)
	)
	(footprint ""
		(layer "F.Cu")
		(at 128.229868 -21.750782 90)
		(property "Reference" "R58"
			(at -6.1722 -60.493148 90)
			(unlocked yes)
			(layer "F.SilkS")
			(effects
				(font
					(size 0.7874 0.5842)
					(thickness 0.1524)
				)
				(justify left)
			)
		)
		(property "Value" ""
			(at 0 0 90)
			(layer "F.Fab")
			(effects
				(font
					(size 1.27 1.27)
				)
			)
		)
		(duplicate_pad_numbers_are_jumpers no)
		(fp_line
			(start 0.7874 -0.4064)
			(end 0.7874 0.4064)
			(stroke
				(width 0.1524)
				(type default)
			)
			(layer "F.SilkS")
		)
		(fp_line
			(start -0.7874 -0.4064)
			(end 0.7874 -0.4064)
			(stroke
				(width 0.1524)
				(type default)
			)
			(layer "F.SilkS")
		)
		(fp_line
			(start 0.7874 0.4064)
			(end -0.7874 0.4064)
			(stroke
				(width 0.1524)
				(type default)
			)
			(layer "F.SilkS")
		)
		(fp_line
			(start -0.7874 0.4064)
			(end -0.7874 -0.4064)
			(stroke
				(width 0.1524)
				(type default)
			)
			(layer "F.SilkS")
		)
		(fp_poly
			(pts
				(xy -0.508 0.2794) (xy -0.508 0.2286) (xy -0.635 0.2286) (xy -0.635 -0.254) (xy -0.5334 -0.254)
				(xy -0.5334 -0.2794) (xy 0.5334 -0.2794) (xy 0.5334 -0.254) (xy 0.635 -0.254) (xy 0.635 0.254) (xy 0.5334 0.254)
				(xy 0.5334 0.2794)
			)
			(stroke
				(width 0)
				(type default)
			)
			(fill no)
			(layer "F.CrtYd")
		)
		(pad "1" smd rect
			(at 0.40005 0 90)
			(size 0.4572 0.508)
			(layers "F.Cu" "F.Mask" "F.Paste")
			(net "GND")
		)
		(pad "2" smd rect
			(at -0.40005 0 90)
			(size 0.4572 0.508)
			(layers "F.Cu" "F.Mask" "F.Paste")
			(net "SFP1_PRESENT_N")
		)
	)
	(footprint ""
		(layer "F.Cu")
		(at 312.248296 -23.367746 -90)
		(property "Reference" "C12"
			(at -1.397508 5.66674 90)
			(unlocked yes)
			(layer "F.SilkS")
			(effects
				(font
					(size 0.7874 0.5842)
					(thickness 0.1524)
				)
				(justify left)
			)
		)
		(property "Value" ""
			(at 0 0 270)
			(layer "F.Fab")
			(effects
				(font
					(size 1.27 1.27)
				)
			)
		)
		(duplicate_pad_numbers_are_jumpers no)
		(fp_line
			(start -0.7874 0.4064)
			(end -0.7874 -0.4064)
			(stroke
				(width 0.1524)
				(type default)
			)
			(layer "F.SilkS")
		)
		(fp_line
			(start 0.7874 0.4064)
			(end -0.7874 0.4064)
			(stroke
				(width 0.1524)
				(type default)
			)
			(layer "F.SilkS")
		)
		(fp_line
			(start 0 0.381)
			(end 0 -0.381)
			(stroke
				(width 0.1524)
				(type default)
			)
			(layer "F.SilkS")
		)
		(fp_line
			(start -0.7874 -0.4064)
			(end 0.7874 -0.4064)
			(stroke
				(width 0.1524)
				(type default)
			)
			(layer "F.SilkS")
		)
		(fp_line
			(start 0.7874 -0.4064)
			(end 0.7874 0.4064)
			(stroke
				(width 0.1524)
				(type default)
			)
			(layer "F.SilkS")
		)
		(fp_poly
			(pts
				(xy -0.5334 0.254) (xy -0.635 0.254) (xy -0.635 0.2286) (xy -0.635 -0.254) (xy -0.5334 -0.254) (xy -0.5334 -0.2794)
				(xy 0.5334 -0.2794) (xy 0.5334 -0.254) (xy 0.635 -0.254) (xy 0.635 0.254) (xy 0.5334 0.254) (xy 0.5334 0.2794)
				(xy -0.508 0.2794) (xy -0.5334 0.2794)
			)
			(stroke
				(width 0)
				(type default)
			)
			(fill no)
			(layer "F.CrtYd")
		)
		(pad "1" smd rect
			(at 0.40005 0 270)
			(size 0.4572 0.508)
			(layers "F.Cu" "F.Mask" "F.Paste")
			(net "P12V")
		)
		(pad "2" smd rect
			(at -0.40005 0 270)
			(size 0.4572 0.508)
			(layers "F.Cu" "F.Mask" "F.Paste")
			(net "GND")
		)
	)
	(footprint ""
		(layer "F.Cu")
		(at 349.594932 -21.561552 90)
		(property "Reference" "R71"
			(at 3.449066 -58.003948 90)
			(unlocked yes)
			(layer "F.SilkS")
			(effects
				(font
					(size 0.7874 0.5842)
					(thickness 0.1524)
				)
				(justify left)
			)
		)
		(property "Value" ""
			(at 0 0 90)
			(layer "F.Fab")
			(effects
				(font
					(size 1.27 1.27)
				)
			)
		)
		(duplicate_pad_numbers_are_jumpers no)
		(fp_line
			(start 0.7874 -0.4064)
			(end 0.7874 0.4064)
			(stroke
				(width 0.1524)
				(type default)
			)
			(layer "F.SilkS")
		)
		(fp_line
			(start -0.7874 -0.4064)
			(end 0.7874 -0.4064)
			(stroke
				(width 0.1524)
				(type default)
			)
			(layer "F.SilkS")
		)
		(fp_line
			(start 0.7874 0.4064)
			(end -0.7874 0.4064)
			(stroke
				(width 0.1524)
				(type default)
			)
			(layer "F.SilkS")
		)
		(fp_line
			(start -0.7874 0.4064)
			(end -0.7874 -0.4064)
			(stroke
				(width 0.1524)
				(type default)
			)
			(layer "F.SilkS")
		)
		(fp_poly
			(pts
				(xy -0.508 0.2794) (xy -0.508 0.2286) (xy -0.635 0.2286) (xy -0.635 -0.254) (xy -0.5334 -0.254)
				(xy -0.5334 -0.2794) (xy 0.5334 -0.2794) (xy 0.5334 -0.254) (xy 0.635 -0.254) (xy 0.635 0.254) (xy 0.5334 0.254)
				(xy 0.5334 0.2794)
			)
			(stroke
				(width 0)
				(type default)
			)
			(fill no)
			(layer "F.CrtYd")
		)
		(pad "1" smd rect
			(at 0.40005 0 90)
			(size 0.4572 0.508)
			(layers "F.Cu" "F.Mask" "F.Paste")
			(net "GND")
		)
		(pad "2" smd rect
			(at -0.40005 0 90)
			(size 0.4572 0.508)
			(layers "F.Cu" "F.Mask" "F.Paste")
			(net "SFP3_PRESENT_N")
		)
	)
	(footprint ""
		(layer "F.Cu")
		(at 340.261448 -21.147532 180)
		(property "Reference" "R73"
			(at 58.045096 4.355084 0)
			(unlocked yes)
			(layer "F.SilkS")
			(effects
				(font
					(size 0.7874 0.5842)
					(thickness 0.1524)
				)
				(justify left)
			)
		)
		(property "Value" ""
			(at 0 0 180)
			(layer "F.Fab")
			(effects
				(font
					(size 1.27 1.27)
				)
			)
		)
		(duplicate_pad_numbers_are_jumpers no)
		(fp_line
			(start 0.7874 0.4064)
			(end -0.7874 0.4064)
			(stroke
				(width 0.1524)
				(type default)
			)
			(layer "F.SilkS")
		)
		(fp_line
			(start 0.7874 -0.4064)
			(end 0.7874 0.4064)
			(stroke
				(width 0.1524)
				(type default)
			)
			(layer "F.SilkS")
		)
		(fp_line
			(start -0.7874 0.4064)
			(end -0.7874 -0.4064)
			(stroke
				(width 0.1524)
				(type default)
			)
			(layer "F.SilkS")
		)
		(fp_line
			(start -0.7874 -0.4064)
			(end 0.7874 -0.4064)
			(stroke
				(width 0.1524)
				(type default)
			)
			(layer "F.SilkS")
		)
		(fp_poly
			(pts
				(xy -0.508 0.2794) (xy -0.508 0.2286) (xy -0.635 0.2286) (xy -0.635 -0.254) (xy -0.5334 -0.254)
				(xy -0.5334 -0.2794) (xy 0.5334 -0.2794) (xy 0.5334 -0.254) (xy 0.635 -0.254) (xy 0.635 0.254) (xy 0.5334 0.254)
				(xy 0.5334 0.2794)
			)
			(stroke
				(width 0)
				(type default)
			)
			(fill no)
			(layer "F.CrtYd")
		)
		(pad "1" smd rect
			(at 0.40005 0 180)
			(size 0.4572 0.508)
			(layers "F.Cu" "F.Mask" "F.Paste")
			(net "ENET10G_4_MOD_DEF0")
		)
		(pad "2" smd rect
			(at -0.40005 0 180)
			(size 0.4572 0.508)
			(layers "F.Cu" "F.Mask" "F.Paste")
			(net "SFP4_PRESENT_N")
		)
	)
	(footprint ""
		(layer "F.Cu")
		(at 126.045468 -21.750782 -90)
		(property "Reference" "R39"
			(at 6.1722 60.395612 90)
			(unlocked yes)
			(layer "F.SilkS")
			(effects
				(font
					(size 0.7874 0.5842)
					(thickness 0.1524)
				)
				(justify left)
			)
		)
		(property "Value" ""
			(at 0 0 270)
			(layer "F.Fab")
			(effects
				(font
					(size 1.27 1.27)
				)
			)
		)
		(duplicate_pad_numbers_are_jumpers no)
		(fp_line
			(start -0.7874 0.4064)
			(end -0.7874 -0.4064)
			(stroke
				(width 0.1524)
				(type default)
			)
			(layer "F.SilkS")
		)
		(fp_line
			(start 0.7874 0.4064)
			(end -0.7874 0.4064)
			(stroke
				(width 0.1524)
				(type default)
			)
			(layer "F.SilkS")
		)
		(fp_line
			(start -0.7874 -0.4064)
			(end 0.7874 -0.4064)
			(stroke
				(width 0.1524)
				(type default)
			)
			(layer "F.SilkS")
		)
		(fp_line
			(start 0.7874 -0.4064)
			(end 0.7874 0.4064)
			(stroke
				(width 0.1524)
				(type default)
			)
			(layer "F.SilkS")
		)
		(fp_poly
			(pts
				(xy -0.508 0.2794) (xy -0.508 0.2286) (xy -0.635 0.2286) (xy -0.635 -0.254) (xy -0.5334 -0.254)
				(xy -0.5334 -0.2794) (xy 0.5334 -0.2794) (xy 0.5334 -0.254) (xy 0.635 -0.254) (xy 0.635 0.254) (xy 0.5334 0.254)
				(xy 0.5334 0.2794)
			)
			(stroke
				(width 0)
				(type default)
			)
			(fill no)
			(layer "F.CrtYd")
		)
		(pad "1" smd rect
			(at 0.40005 0 270)
			(size 0.4572 0.508)
			(layers "F.Cu" "F.Mask" "F.Paste")
			(net "SKU_PIN_BLAD1_1")
		)
		(pad "2" smd rect
			(at -0.40005 0 270)
			(size 0.4572 0.508)
			(layers "F.Cu" "F.Mask" "F.Paste")
			(net "P3V3_BLAD1")
		)
	)
	(footprint ""
		(layer "F.Cu")
		(at 154.89936 -24.165306 180)
		(property "Reference" "R3"
			(at -33.93948 -17.809464 0)
			(unlocked yes)
			(layer "F.SilkS")
			(effects
				(font
					(size 0.7874 0.5842)
					(thickness 0.1524)
				)
				(justify left)
			)
		)
		(property "Value" ""
			(at 0 0 180)
			(layer "F.Fab")
			(effects
				(font
					(size 1.27 1.27)
				)
			)
		)
		(duplicate_pad_numbers_are_jumpers no)
		(fp_line
			(start 0.7874 0.4064)
			(end -0.7874 0.4064)
			(stroke
				(width 0.1524)
				(type default)
			)
			(layer "F.SilkS")
		)
		(fp_line
			(start 0.7874 -0.4064)
			(end 0.7874 0.4064)
			(stroke
				(width 0.1524)
				(type default)
			)
			(layer "F.SilkS")
		)
		(fp_line
			(start -0.7874 0.4064)
			(end -0.7874 -0.4064)
			(stroke
				(width 0.1524)
				(type default)
			)
			(layer "F.SilkS")
		)
		(fp_line
			(start -0.7874 -0.4064)
			(end 0.7874 -0.4064)
			(stroke
				(width 0.1524)
				(type default)
			)
			(layer "F.SilkS")
		)
		(fp_poly
			(pts
				(xy -0.508 0.2794) (xy -0.508 0.2286) (xy -0.635 0.2286) (xy -0.635 -0.254) (xy -0.5334 -0.254)
				(xy -0.5334 -0.2794) (xy 0.5334 -0.2794) (xy 0.5334 -0.254) (xy 0.635 -0.254) (xy 0.635 0.254) (xy 0.5334 0.254)
				(xy 0.5334 0.2794)
			)
			(stroke
				(width 0)
				(type default)
			)
			(fill no)
			(layer "F.CrtYd")
		)
		(pad "1" smd rect
			(at 0.40005 0 180)
			(size 0.4572 0.508)
			(layers "F.Cu" "F.Mask" "F.Paste")
			(net "P3V3_BLAD1")
		)
		(pad "2" smd rect
			(at -0.40005 0 180)
			(size 0.4572 0.508)
			(layers "F.Cu" "F.Mask" "F.Paste")
			(net "ENET10G_1_TX_DIS")
		)
	)
	(footprint ""
		(layer "F.Cu")
		(at 92.305886 -37.875972 180)
		(property "Reference" "FS2"
			(at 2.846832 2.724404 0)
			(unlocked yes)
			(layer "F.SilkS")
			(effects
				(font
					(size 0.7874 0.5842)
					(thickness 0.1524)
				)
				(justify left)
			)
		)
		(property "Value" ""
			(at 0 0 180)
			(layer "F.Fab")
			(effects
				(font
					(size 1.27 1.27)
				)
			)
		)
		(duplicate_pad_numbers_are_jumpers no)
		(fp_line
			(start 3.550412 1.050036)
			(end -0.650494 1.050036)
			(stroke
				(width 0.1524)
				(type default)
			)
			(layer "F.SilkS")
		)
		(fp_line
			(start 3.550412 -1.050036)
			(end 3.550412 1.050036)
			(stroke
				(width 0.1524)
				(type default)
			)
			(layer "F.SilkS")
		)
		(fp_line
			(start -0.650494 1.050036)
			(end -0.650494 -1.050036)
			(stroke
				(width 0.1524)
				(type default)
			)
			(layer "F.SilkS")
		)
		(fp_line
			(start -0.650494 -1.050036)
			(end 3.550412 -1.050036)
			(stroke
				(width 0.1524)
				(type default)
			)
			(layer "F.SilkS")
		)
		(fp_poly
			(pts
				(xy 3.228086 -0.9652) (xy 3.228086 -1.100074) (xy -0.327914 -1.100074) (xy -0.327914 -0.9652) (xy -0.556514 -0.9652)
				(xy -0.556514 0.9652) (xy -0.327914 0.9652) (xy -0.327914 1.100074) (xy 3.228086 1.100074) (xy 3.228086 0.9652)
				(xy 3.456686 0.9652) (xy 3.456686 -0.9652)
			)
			(stroke
				(width 0)
				(type default)
			)
			(fill no)
			(layer "F.CrtYd")
		)
		(fp_text user "2"
			(at 4.256786 0.590804 0)
			(unlocked yes)
			(layer "F.SilkS")
			(effects
				(font
					(size 0.7874 0.5842)
					(thickness 0.1524)
				)
				(justify left)
			)
		)
		(fp_text user "1"
			(at -0.543814 1.632204 0)
			(unlocked yes)
			(layer "F.SilkS")
			(effects
				(font
					(size 0.7874 0.5842)
					(thickness 0.1524)
				)
				(justify left)
			)
		)
		(pad "1" smd rect
			(at 0 0 180)
			(size 1.016 1.8034)
			(layers "F.Cu" "F.Mask" "F.Paste")
			(net "P3V3_BLAD1")
		)
		(pad "2" smd rect
			(at 2.899918 0 180)
			(size 1.016 1.8034)
			(layers "F.Cu" "F.Mask" "F.Paste")
			(net "P3V3_10G_2_VCCT_L")
		)
	)
	(footprint ""
		(layer "F.Cu")
		(at 363.490256 -14.389862 180)
		(property "Reference" "U7"
			(at -5.707888 -10.577576 0)
			(unlocked yes)
			(layer "F.SilkS")
			(effects
				(font
					(size 0.7874 0.5842)
					(thickness 0.1524)
				)
				(justify left)
			)
		)
		(property "Value" ""
			(at 0 0 180)
			(layer "F.Fab")
			(effects
				(font
					(size 1.27 1.27)
				)
			)
		)
		(duplicate_pad_numbers_are_jumpers no)
		(fp_line
			(start 5.500116 3.700018)
			(end 4.191 3.700018)
			(stroke
				(width 0.1524)
				(type default)
			)
			(layer "F.SilkS")
		)
		(fp_line
			(start 5.500116 0.889)
			(end 5.500116 3.700018)
			(stroke
				(width 0.1524)
				(type default)
			)
			(layer "F.SilkS")
		)
		(fp_line
			(start 5.500116 -3.700018)
			(end 5.500116 -0.889)
			(stroke
				(width 0.1524)
				(type default)
			)
			(layer "F.SilkS")
		)
		(fp_line
			(start 3.7846 -3.700018)
			(end 5.500116 -3.700018)
			(stroke
				(width 0.1524)
				(type default)
			)
			(layer "F.SilkS")
		)
		(fp_line
			(start -3.7846 3.700018)
			(end -5.500116 3.700018)
			(stroke
				(width 0.1524)
				(type default)
			)
			(layer "F.SilkS")
		)
		(fp_line
			(start -5.500116 0.635)
			(end -5.500116 3.700018)
			(stroke
				(width 0.1524)
				(type default)
			)
			(layer "F.SilkS")
		)
		(fp_line
			(start -5.500116 -3.700018)
			(end -4.191 -3.700018)
			(stroke
				(width 0.1524)
				(type default)
			)
			(layer "F.SilkS")
		)
		(fp_line
			(start -5.500116 -3.700018)
			(end -5.500116 -0.635)
			(stroke
				(width 0.1524)
				(type default)
			)
			(layer "F.SilkS")
		)
		(fp_poly
			(pts
				(xy -3.387344 5.3848) (xy -3.946144 6.8072) (xy -2.853944 6.8072)
			)
			(stroke
				(width 0)
				(type default)
			)
			(fill yes)
			(layer "F.SilkS")
		)
		(fp_poly
			(pts
				(arc
					(start -4.064 -0.3302)
					(mid -4.8006 -1.0668)
					(end -5.5372 -0.3302)
				)
				(arc
					(start -5.5372 0.3048)
					(mid -5.314015 0.843615)
					(end -4.7752 1.0668)
				)
				(arc
					(start -4.7752 1.0668)
					(mid -4.272306 0.858494)
					(end -4.064 0.3556)
				)
			)
			(stroke
				(width 0)
				(type default)
			)
			(fill no)
			(layer "B.CrtYd")
		)
		(fp_poly
			(pts
				(arc
					(start 3.7338 0)
					(mid 5.8674 0)
					(end 3.7338 0)
				)
			)
			(stroke
				(width 0)
				(type default)
			)
			(fill no)
			(layer "B.CrtYd")
		)
		(fp_rect
			(start -5.5118 5.1308)
			(end 5.5118 -5.1308)
			(stroke
				(width 0)
				(type default)
			)
			(fill no)
			(layer "F.CrtYd")
		)
		(fp_text user "10"
			(at 4.694682 6.283706 0)
			(unlocked yes)
			(layer "F.SilkS")
			(effects
				(font
					(size 0.7874 0.5842)
					(thickness 0.1524)
				)
				(justify left)
			)
		)
		(fp_text user "11"
			(at 3.214624 -6.368288 90)
			(unlocked yes)
			(layer "F.SilkS")
			(effects
				(font
					(size 0.7874 0.5842)
					(thickness 0.1524)
				)
				(justify left)
			)
		)
		(fp_text user "1"
			(at -3.756914 5.902706 0)
			(unlocked yes)
			(layer "F.SilkS")
			(effects
				(font
					(size 0.7874 0.5842)
					(thickness 0.1524)
				)
				(justify left)
			)
		)
		(fp_text user "20"
			(at -4.498848 -8.543036 90)
			(unlocked yes)
			(layer "F.SilkS")
			(effects
				(font
					(size 0.7874 0.5842)
					(thickness 0.1524)
				)
				(justify left)
			)
		)
		(pad "" np_thru_hole oval
			(at -4.800092 0 180)
			(size 0.9652 1.6002)
			(drill oval 0.9652 1.6002)
			(layers "*.Cu" "*.Mask")
			(clearance 0.381)
			(thermal_gap 0.381)
		)
		(pad "" np_thru_hole circle
			(at 4.800092 0 180)
			(size 1.6002 1.6002)
			(drill 1.6002)
			(layers "*.Cu" "*.Mask")
			(clearance 0.381)
			(thermal_gap 0.381)
		)
		(pad "1" smd oval
			(at -3.400044 4.100068 180)
			(size 0.508 2.032)
			(layers "F.Cu" "F.Mask" "F.Paste")
			(net "GND")
		)
		(pad "2" smd oval
			(at -2.599944 4.100068 180)
			(size 0.508 2.032)
			(layers "F.Cu" "F.Mask" "F.Paste")
			(net "ENET10G_3_TX_FAULT")
		)
		(pad "3" smd oval
			(at -1.800098 4.100068 180)
			(size 0.508 2.032)
			(layers "F.Cu" "F.Mask" "F.Paste")
			(net "ENET10G_3_TX_DIS")
		)
		(pad "4" smd oval
			(at -0.999998 4.100068 180)
			(size 0.508 2.032)
			(layers "F.Cu" "F.Mask" "F.Paste")
			(net "ENET10G_3_SDA")
		)
		(pad "5" smd oval
			(at -0.199898 4.100068 180)
			(size 0.508 2.032)
			(layers "F.Cu" "F.Mask" "F.Paste")
			(net "ENET10G_3_SCL")
		)
		(pad "6" smd oval
			(at 0.599948 4.100068 180)
			(size 0.508 2.032)
			(layers "F.Cu" "F.Mask" "F.Paste")
			(net "ENET10G_3_MOD_DEF0")
		)
		(pad "7" smd oval
			(at 1.400048 4.100068 180)
			(size 0.508 2.032)
			(layers "F.Cu" "F.Mask" "F.Paste")
			(net "ENET10G_3_RS0")
		)
		(pad "8" smd oval
			(at 2.199894 4.100068 180)
			(size 0.508 2.032)
			(layers "F.Cu" "F.Mask" "F.Paste")
			(net "ENET10G_3_LOS")
		)
		(pad "9" smd oval
			(at 2.999994 4.100068 180)
			(size 0.508 2.032)
			(layers "F.Cu" "F.Mask" "F.Paste")
			(net "ENET10G_3_RS1")
		)
		(pad "10" smd oval
			(at 3.800094 4.100068 180)
			(size 0.508 2.032)
			(layers "F.Cu" "F.Mask" "F.Paste")
			(net "GND")
		)
		(pad "11" smd oval
			(at 3.400044 -4.100068 180)
			(size 0.508 2.032)
			(layers "F.Cu" "F.Mask" "F.Paste")
			(net "GND")
		)
		(pad "12" smd oval
			(at 2.599944 -4.100068 180)
			(size 0.508 2.032)
			(layers "F.Cu" "F.Mask" "F.Paste")
			(net "ENET10G_3_RDN")
		)
		(pad "13" smd oval
			(at 1.800098 -4.100068 180)
			(size 0.508 2.032)
			(layers "F.Cu" "F.Mask" "F.Paste")
			(net "ENET10G_3_RDP")
		)
		(pad "14" smd oval
			(at 0.999998 -4.100068 180)
			(size 0.508 2.032)
			(layers "F.Cu" "F.Mask" "F.Paste")
			(net "GND")
		)
		(pad "15" smd oval
			(at 0.199898 -4.100068 180)
			(size 0.508 2.032)
			(layers "F.Cu" "F.Mask" "F.Paste")
			(net "P3V3_10G_3_VCCR")
		)
		(pad "16" smd oval
			(at -0.599948 -4.100068 180)
			(size 0.508 2.032)
			(layers "F.Cu" "F.Mask" "F.Paste")
			(net "P3V3_10G_3_VCCT")
		)
		(pad "17" smd oval
			(at -1.400048 -4.100068 180)
			(size 0.508 2.032)
			(layers "F.Cu" "F.Mask" "F.Paste")
			(net "GND")
		)
		(pad "18" smd oval
			(at -2.199894 -4.100068 180)
			(size 0.508 2.032)
			(layers "F.Cu" "F.Mask" "F.Paste")
			(net "ENET10G_3_TDP")
		)
		(pad "19" smd oval
			(at -2.999994 -4.100068 180)
			(size 0.508 2.032)
			(layers "F.Cu" "F.Mask" "F.Paste")
			(net "ENET10G_3_TDN")
		)
		(pad "20" smd oval
			(at -3.800094 -4.100068 180)
			(size 0.508 2.032)
			(layers "F.Cu" "F.Mask" "F.Paste")
			(net "GND")
		)
		(zone
			(layers "F.Cu" "B.Cu" "In1.Cu" "In2.Cu" "In3.Cu" "In4.Cu" "In5.Cu" "In6.Cu")
			(hatch none 0.5)
			(connect_pads
				(clearance 0)
			)
			(min_thickness 0.25)
			(keepout
				(tracks not_allowed)
				(vias allowed)
				(pads allowed)
				(copperpour not_allowed)
				(footprints allowed)
			)
			(placement
				(enabled no)
				(sheetname "")
			)
			(fill
				(thermal_gap 0.5)
				(thermal_bridge_width 0.5)
				(island_removal_mode 0)
			)
			(polygon
				(pts
					(arc
						(start 368.265456 -15.609062)
						(mid 368.912034 -15.34124)
						(end 369.179856 -14.694662)
					)
					(arc
						(start 369.179856 -14.059662)
						(mid 368.290856 -13.170662)
						(end 367.401856 -14.059662)
					)
					(arc
						(start 367.401856 -14.745462)
						(mid 367.654799 -15.356119)
						(end 368.265456 -15.609062)
					)
				)
			)
		)
		(zone
			(layers "F.Cu" "B.Cu" "In1.Cu" "In2.Cu" "In3.Cu" "In4.Cu" "In5.Cu" "In6.Cu")
			(hatch none 0.5)
			(connect_pads
				(clearance 0)
			)
			(min_thickness 0.25)
			(keepout
				(tracks not_allowed)
				(vias allowed)
				(pads allowed)
				(copperpour not_allowed)
				(footprints allowed)
			)
			(placement
				(enabled no)
				(sheetname "")
			)
			(fill
				(thermal_gap 0.5)
				(thermal_bridge_width 0.5)
				(island_removal_mode 0)
			)
			(polygon
				(pts
					(arc
						(start 359.908856 -14.389862)
						(mid 357.470456 -14.389862)
						(end 359.908856 -14.389862)
					)
				)
			)
		)
	)
	(footprint ""
		(layer "F.Cu")
		(at 123.839732 -21.750782 90)
		(property "Reference" "R56"
			(at -6.1214 -59.781948 90)
			(unlocked yes)
			(layer "F.SilkS")
			(effects
				(font
					(size 0.7874 0.5842)
					(thickness 0.1524)
				)
				(justify left)
			)
		)
		(property "Value" ""
			(at 0 0 90)
			(layer "F.Fab")
			(effects
				(font
					(size 1.27 1.27)
				)
			)
		)
		(duplicate_pad_numbers_are_jumpers no)
		(fp_line
			(start 0.7874 -0.4064)
			(end 0.7874 0.4064)
			(stroke
				(width 0.1524)
				(type default)
			)
			(layer "F.SilkS")
		)
		(fp_line
			(start -0.7874 -0.4064)
			(end 0.7874 -0.4064)
			(stroke
				(width 0.1524)
				(type default)
			)
			(layer "F.SilkS")
		)
		(fp_line
			(start 0.7874 0.4064)
			(end -0.7874 0.4064)
			(stroke
				(width 0.1524)
				(type default)
			)
			(layer "F.SilkS")
		)
		(fp_line
			(start -0.7874 0.4064)
			(end -0.7874 -0.4064)
			(stroke
				(width 0.1524)
				(type default)
			)
			(layer "F.SilkS")
		)
		(fp_poly
			(pts
				(xy -0.508 0.2794) (xy -0.508 0.2286) (xy -0.635 0.2286) (xy -0.635 -0.254) (xy -0.5334 -0.254)
				(xy -0.5334 -0.2794) (xy 0.5334 -0.2794) (xy 0.5334 -0.254) (xy 0.635 -0.254) (xy 0.635 0.254) (xy 0.5334 0.254)
				(xy 0.5334 0.2794)
			)
			(stroke
				(width 0)
				(type default)
			)
			(fill no)
			(layer "F.CrtYd")
		)
		(pad "1" smd rect
			(at 0.40005 0 90)
			(size 0.4572 0.508)
			(layers "F.Cu" "F.Mask" "F.Paste")
			(net "GND")
		)
		(pad "2" smd rect
			(at -0.40005 0 90)
			(size 0.4572 0.508)
			(layers "F.Cu" "F.Mask" "F.Paste")
			(net "SKU_PIN_BLAD1_2")
		)
	)
	(footprint ""
		(layer "F.Cu")
		(at 341.771732 -21.790152 90)
		(property "Reference" "R74"
			(at 3.220466 -56.683148 90)
			(unlocked yes)
			(layer "F.SilkS")
			(effects
				(font
					(size 0.7874 0.5842)
					(thickness 0.1524)
				)
				(justify left)
			)
		)
		(property "Value" ""
			(at 0 0 90)
			(layer "F.Fab")
			(effects
				(font
					(size 1.27 1.27)
				)
			)
		)
		(duplicate_pad_numbers_are_jumpers no)
		(fp_line
			(start 0.7874 -0.4064)
			(end 0.7874 0.4064)
			(stroke
				(width 0.1524)
				(type default)
			)
			(layer "F.SilkS")
		)
		(fp_line
			(start -0.7874 -0.4064)
			(end 0.7874 -0.4064)
			(stroke
				(width 0.1524)
				(type default)
			)
			(layer "F.SilkS")
		)
		(fp_line
			(start 0.7874 0.4064)
			(end -0.7874 0.4064)
			(stroke
				(width 0.1524)
				(type default)
			)
			(layer "F.SilkS")
		)
		(fp_line
			(start -0.7874 0.4064)
			(end -0.7874 -0.4064)
			(stroke
				(width 0.1524)
				(type default)
			)
			(layer "F.SilkS")
		)
		(fp_poly
			(pts
				(xy -0.508 0.2794) (xy -0.508 0.2286) (xy -0.635 0.2286) (xy -0.635 -0.254) (xy -0.5334 -0.254)
				(xy -0.5334 -0.2794) (xy 0.5334 -0.2794) (xy 0.5334 -0.254) (xy 0.635 -0.254) (xy 0.635 0.254) (xy 0.5334 0.254)
				(xy 0.5334 0.2794)
			)
			(stroke
				(width 0)
				(type default)
			)
			(fill no)
			(layer "F.CrtYd")
		)
		(pad "1" smd rect
			(at 0.40005 0 90)
			(size 0.4572 0.508)
			(layers "F.Cu" "F.Mask" "F.Paste")
			(net "GND")
		)
		(pad "2" smd rect
			(at -0.40005 0 90)
			(size 0.4572 0.508)
			(layers "F.Cu" "F.Mask" "F.Paste")
			(net "SFP4_PRESENT_N")
		)
	)
	(footprint ""
		(layer "F.Cu")
		(at 313.365134 -39.01567 180)
		(property "Reference" "FS8"
			(at 2.652268 5.545328 0)
			(unlocked yes)
			(layer "F.SilkS")
			(effects
				(font
					(size 0.7874 0.5842)
					(thickness 0.1524)
				)
				(justify left)
			)
		)
		(property "Value" ""
			(at 0 0 180)
			(layer "F.Fab")
			(effects
				(font
					(size 1.27 1.27)
				)
			)
		)
		(duplicate_pad_numbers_are_jumpers no)
		(fp_line
			(start 3.550412 1.050036)
			(end -0.650494 1.050036)
			(stroke
				(width 0.1524)
				(type default)
			)
			(layer "F.SilkS")
		)
		(fp_line
			(start 3.550412 -1.050036)
			(end 3.550412 1.050036)
			(stroke
				(width 0.1524)
				(type default)
			)
			(layer "F.SilkS")
		)
		(fp_line
			(start -0.650494 1.050036)
			(end -0.650494 -1.050036)
			(stroke
				(width 0.1524)
				(type default)
			)
			(layer "F.SilkS")
		)
		(fp_line
			(start -0.650494 -1.050036)
			(end 3.550412 -1.050036)
			(stroke
				(width 0.1524)
				(type default)
			)
			(layer "F.SilkS")
		)
		(fp_poly
			(pts
				(xy 3.228086 -0.9652) (xy 3.228086 -1.100074) (xy -0.327914 -1.100074) (xy -0.327914 -0.9652) (xy -0.556514 -0.9652)
				(xy -0.556514 0.9652) (xy -0.327914 0.9652) (xy -0.327914 1.100074) (xy 3.228086 1.100074) (xy 3.228086 0.9652)
				(xy 3.456686 0.9652) (xy 3.456686 -0.9652)
			)
			(stroke
				(width 0)
				(type default)
			)
			(fill no)
			(layer "F.CrtYd")
		)
		(fp_text user "2"
			(at 5.027422 -0.093472 0)
			(unlocked yes)
			(layer "F.SilkS")
			(effects
				(font
					(size 0.7874 0.5842)
					(thickness 0.1524)
				)
				(justify left)
			)
		)
		(fp_text user "1"
			(at -0.154178 1.989328 0)
			(unlocked yes)
			(layer "F.SilkS")
			(effects
				(font
					(size 0.7874 0.5842)
					(thickness 0.1524)
				)
				(justify left)
			)
		)
		(pad "1" smd rect
			(at 0 0 180)
			(size 1.016 1.8034)
			(layers "F.Cu" "F.Mask" "F.Paste")
			(net "P3V3_BLAD2")
		)
		(pad "2" smd rect
			(at 2.899918 0 180)
			(size 1.016 1.8034)
			(layers "F.Cu" "F.Mask" "F.Paste")
			(net "P3V3_10G_4_VCCR_L")
		)
	)
	(footprint ""
		(layer "F.Cu")
		(at 378.431552 -24.906478)
		(property "Reference" "R51"
			(at 33.528 16.672052 0)
			(unlocked yes)
			(layer "F.SilkS")
			(effects
				(font
					(size 0.7874 0.5842)
					(thickness 0.1524)
				)
				(justify left)
			)
		)
		(property "Value" ""
			(at 0 0 0)
			(layer "F.Fab")
			(effects
				(font
					(size 1.27 1.27)
				)
			)
		)
		(duplicate_pad_numbers_are_jumpers no)
		(fp_line
			(start -0.7874 -0.4064)
			(end 0.7874 -0.4064)
			(stroke
				(width 0.1524)
				(type default)
			)
			(layer "F.SilkS")
		)
		(fp_line
			(start -0.7874 0.4064)
			(end -0.7874 -0.4064)
			(stroke
				(width 0.1524)
				(type default)
			)
			(layer "F.SilkS")
		)
		(fp_line
			(start 0.7874 -0.4064)
			(end 0.7874 0.4064)
			(stroke
				(width 0.1524)
				(type default)
			)
			(layer "F.SilkS")
		)
		(fp_line
			(start 0.7874 0.4064)
			(end -0.7874 0.4064)
			(stroke
				(width 0.1524)
				(type default)
			)
			(layer "F.SilkS")
		)
		(fp_poly
			(pts
				(xy -0.508 0.2794) (xy -0.508 0.2286) (xy -0.635 0.2286) (xy -0.635 -0.254) (xy -0.5334 -0.254)
				(xy -0.5334 -0.2794) (xy 0.5334 -0.2794) (xy 0.5334 -0.254) (xy 0.635 -0.254) (xy 0.635 0.254) (xy 0.5334 0.254)
				(xy 0.5334 0.2794)
			)
			(stroke
				(width 0)
				(type default)
			)
			(fill no)
			(layer "F.CrtYd")
		)
		(pad "1" smd rect
			(at 0.40005 0)
			(size 0.4572 0.508)
			(layers "F.Cu" "F.Mask" "F.Paste")
			(net "GND")
		)
		(pad "2" smd rect
			(at -0.40005 0)
			(size 0.4572 0.508)
			(layers "F.Cu" "F.Mask" "F.Paste")
			(net "ENET10G_3_TX_DIS")
		)
	)
	(footprint ""
		(layer "F.Cu")
		(at 313.315096 -23.367746 -90)
		(property "Reference" "C11"
			(at -1.372108 5.36194 90)
			(unlocked yes)
			(layer "F.SilkS")
			(effects
				(font
					(size 0.7874 0.5842)
					(thickness 0.1524)
				)
				(justify left)
			)
		)
		(property "Value" ""
			(at 0 0 270)
			(layer "F.Fab")
			(effects
				(font
					(size 1.27 1.27)
				)
			)
		)
		(duplicate_pad_numbers_are_jumpers no)
		(fp_line
			(start -0.7874 0.4064)
			(end -0.7874 -0.4064)
			(stroke
				(width 0.1524)
				(type default)
			)
			(layer "F.SilkS")
		)
		(fp_line
			(start 0.7874 0.4064)
			(end -0.7874 0.4064)
			(stroke
				(width 0.1524)
				(type default)
			)
			(layer "F.SilkS")
		)
		(fp_line
			(start 0 0.381)
			(end 0 -0.381)
			(stroke
				(width 0.1524)
				(type default)
			)
			(layer "F.SilkS")
		)
		(fp_line
			(start -0.7874 -0.4064)
			(end 0.7874 -0.4064)
			(stroke
				(width 0.1524)
				(type default)
			)
			(layer "F.SilkS")
		)
		(fp_line
			(start 0.7874 -0.4064)
			(end 0.7874 0.4064)
			(stroke
				(width 0.1524)
				(type default)
			)
			(layer "F.SilkS")
		)
		(fp_poly
			(pts
				(xy -0.5334 0.254) (xy -0.635 0.254) (xy -0.635 0.2286) (xy -0.635 -0.254) (xy -0.5334 -0.254) (xy -0.5334 -0.2794)
				(xy 0.5334 -0.2794) (xy 0.5334 -0.254) (xy 0.635 -0.254) (xy 0.635 0.254) (xy 0.5334 0.254) (xy 0.5334 0.2794)
				(xy -0.508 0.2794) (xy -0.5334 0.2794)
			)
			(stroke
				(width 0)
				(type default)
			)
			(fill no)
			(layer "F.CrtYd")
		)
		(pad "1" smd rect
			(at 0.40005 0 270)
			(size 0.4572 0.508)
			(layers "F.Cu" "F.Mask" "F.Paste")
			(net "P12V")
		)
		(pad "2" smd rect
			(at -0.40005 0 270)
			(size 0.4572 0.508)
			(layers "F.Cu" "F.Mask" "F.Paste")
			(net "GND")
		)
	)
	(footprint ""
		(layer "F.Cu")
		(at 157.781752 -24.165306)
		(property "Reference" "R41"
			(at 33.5534 17.942052 0)
			(unlocked yes)
			(layer "F.SilkS")
			(effects
				(font
					(size 0.7874 0.5842)
					(thickness 0.1524)
				)
				(justify left)
			)
		)
		(property "Value" ""
			(at 0 0 0)
			(layer "F.Fab")
			(effects
				(font
					(size 1.27 1.27)
				)
			)
		)
		(duplicate_pad_numbers_are_jumpers no)
		(fp_line
			(start -0.7874 -0.4064)
			(end 0.7874 -0.4064)
			(stroke
				(width 0.1524)
				(type default)
			)
			(layer "F.SilkS")
		)
		(fp_line
			(start -0.7874 0.4064)
			(end -0.7874 -0.4064)
			(stroke
				(width 0.1524)
				(type default)
			)
			(layer "F.SilkS")
		)
		(fp_line
			(start 0.7874 -0.4064)
			(end 0.7874 0.4064)
			(stroke
				(width 0.1524)
				(type default)
			)
			(layer "F.SilkS")
		)
		(fp_line
			(start 0.7874 0.4064)
			(end -0.7874 0.4064)
			(stroke
				(width 0.1524)
				(type default)
			)
			(layer "F.SilkS")
		)
		(fp_poly
			(pts
				(xy -0.508 0.2794) (xy -0.508 0.2286) (xy -0.635 0.2286) (xy -0.635 -0.254) (xy -0.5334 -0.254)
				(xy -0.5334 -0.2794) (xy 0.5334 -0.2794) (xy 0.5334 -0.254) (xy 0.635 -0.254) (xy 0.635 0.254) (xy 0.5334 0.254)
				(xy 0.5334 0.2794)
			)
			(stroke
				(width 0)
				(type default)
			)
			(fill no)
			(layer "F.CrtYd")
		)
		(pad "1" smd rect
			(at 0.40005 0)
			(size 0.4572 0.508)
			(layers "F.Cu" "F.Mask" "F.Paste")
			(net "GND")
		)
		(pad "2" smd rect
			(at -0.40005 0)
			(size 0.4572 0.508)
			(layers "F.Cu" "F.Mask" "F.Paste")
			(net "ENET10G_1_TX_DIS")
		)
	)
	(footprint ""
		(layer "F.Cu")
		(at 90.9828 -30.897068)
		(property "Reference" "R78"
			(at -7.0866 1.70307 0)
			(unlocked yes)
			(layer "F.SilkS")
			(effects
				(font
					(size 0.7874 0.5842)
					(thickness 0.1524)
				)
				(justify left)
			)
		)
		(property "Value" ""
			(at 0 0 0)
			(layer "F.Fab")
			(effects
				(font
					(size 1.27 1.27)
				)
			)
		)
		(duplicate_pad_numbers_are_jumpers no)
		(fp_line
			(start -1.905 -0.8636)
			(end 1.905 -0.8636)
			(stroke
				(width 0.1524)
				(type default)
			)
			(layer "F.SilkS")
		)
		(fp_line
			(start -1.905 0.8636)
			(end -1.905 -0.8636)
			(stroke
				(width 0.1524)
				(type default)
			)
			(layer "F.SilkS")
		)
		(fp_line
			(start 1.905 -0.8636)
			(end 1.905 0.8636)
			(stroke
				(width 0.1524)
				(type default)
			)
			(layer "F.SilkS")
		)
		(fp_line
			(start 1.905 0.8636)
			(end -1.905 0.8636)
			(stroke
				(width 0.1524)
				(type default)
			)
			(layer "F.SilkS")
		)
		(fp_poly
			(pts
				(xy 1.524 0.6858) (xy 1.524 -0.6858) (xy 1.524 -0.7366) (xy -1.524 -0.7366) (xy -1.524 -0.6858)
				(xy -1.524 0.6858) (xy -1.524 0.7366) (xy 1.524 0.7366)
			)
			(stroke
				(width 0)
				(type default)
			)
			(fill no)
			(layer "F.CrtYd")
		)
		(pad "1" smd rect
			(at 0.94996 0)
			(size 1.1176 1.3716)
			(layers "F.Cu" "F.Mask" "F.Paste")
			(net "P3V3_BLAD1")
		)
		(pad "2" smd rect
			(at -0.94996 0)
			(size 1.1176 1.3716)
			(layers "F.Cu" "F.Mask" "F.Paste")
			(net "P3V3_10G_2_VCCT")
		)
	)
	(footprint ""
		(layer "F.Cu")
		(at 22.809962 -27.500072 180)
		(property "Reference" "J21"
			(at -2.81559 -9.110218 90)
			(unlocked yes)
			(layer "F.SilkS")
			(effects
				(font
					(size 0.7874 0.5842)
					(thickness 0.1524)
				)
				(justify left)
			)
		)
		(property "Value" ""
			(at 0 0 180)
			(layer "F.Fab")
			(effects
				(font
					(size 1.27 1.27)
				)
			)
		)
		(duplicate_pad_numbers_are_jumpers no)
		(fp_line
			(start 4.150106 2.325116)
			(end -2.15011 2.325116)
			(stroke
				(width 0.1524)
				(type default)
			)
			(layer "F.SilkS")
		)
		(fp_line
			(start 4.150106 -12.325096)
			(end 4.150106 2.325116)
			(stroke
				(width 0.1524)
				(type default)
			)
			(layer "F.SilkS")
		)
		(fp_line
			(start -1.500124 -3.800094)
			(end -2.15011 -3.800094)
			(stroke
				(width 0.1524)
				(type default)
			)
			(layer "F.SilkS")
		)
		(fp_line
			(start -1.500124 -6.199886)
			(end -1.500124 -3.800094)
			(stroke
				(width 0.1524)
				(type default)
			)
			(layer "F.SilkS")
		)
		(fp_line
			(start -2.15011 2.325116)
			(end -2.15011 -12.325096)
			(stroke
				(width 0.1524)
				(type default)
			)
			(layer "F.SilkS")
		)
		(fp_line
			(start -2.15011 -6.199886)
			(end -1.500124 -6.199886)
			(stroke
				(width 0.1524)
				(type default)
			)
			(layer "F.SilkS")
		)
		(fp_line
			(start -2.15011 -12.325096)
			(end 4.150106 -12.325096)
			(stroke
				(width 0.1524)
				(type default)
			)
			(layer "F.SilkS")
		)
		(fp_poly
			(pts
				(xy -1.143 -12.69238) (xy -0.381 -14.21638) (xy -1.905 -14.21638)
			)
			(stroke
				(width 0)
				(type default)
			)
			(fill yes)
			(layer "F.SilkS")
		)
		(fp_poly
			(pts
				(xy 2.752598 -10.74039) (xy -0.727202 -10.74039) (xy -0.752602 -10.74039) (xy -0.752602 0.74041)
				(xy 2.752598 0.74041)
			)
			(stroke
				(width 0)
				(type default)
			)
			(fill no)
			(layer "B.CrtYd")
		)
		(fp_poly
			(pts
				(xy -2.15011 -12.325096) (xy -2.15011 2.325116) (xy 4.150106 2.325116) (xy 4.150106 -12.325096)
			)
			(stroke
				(width 0)
				(type default)
			)
			(fill no)
			(layer "F.CrtYd")
		)
		(fp_line
			(start 4.150106 2.325116)
			(end -2.15011 2.325116)
			(stroke
				(width 0.1)
				(type default)
			)
			(layer "F.Fab")
		)
		(fp_line
			(start 4.150106 -12.325096)
			(end 4.150106 2.325116)
			(stroke
				(width 0.1)
				(type default)
			)
			(layer "F.Fab")
		)
		(fp_line
			(start -2.15011 2.325116)
			(end -2.15011 -12.325096)
			(stroke
				(width 0.1)
				(type default)
			)
			(layer "F.Fab")
		)
		(fp_line
			(start -2.15011 -12.325096)
			(end 4.150106 -12.325096)
			(stroke
				(width 0.1)
				(type default)
			)
			(layer "F.Fab")
		)
		(fp_poly
			(pts
				(xy -2.350516 -9.992614) (xy -3.874516 -10.754614) (xy -3.874516 -9.230614)
			)
			(stroke
				(width 0)
				(type default)
			)
			(fill yes)
			(layer "F.Fab")
		)
		(fp_text user "2"
			(at 5.029454 -9.962896 0)
			(unlocked yes)
			(layer "F.SilkS")
			(effects
				(font
					(size 0.7874 0.5842)
					(thickness 0.1524)
				)
				(justify left)
			)
		)
		(fp_text user "12"
			(at 2.631186 3.270504 0)
			(unlocked yes)
			(layer "F.SilkS")
			(effects
				(font
					(size 0.7874 0.5842)
					(thickness 0.1524)
				)
				(justify left)
			)
		)
		(fp_text user "11"
			(at -0.543814 3.188208 0)
			(unlocked yes)
			(layer "F.SilkS")
			(effects
				(font
					(size 0.7874 0.5842)
					(thickness 0.1524)
				)
				(justify left)
			)
		)
		(fp_text user "1"
			(at -1.599946 -13.080492 0)
			(unlocked yes)
			(layer "F.SilkS")
			(effects
				(font
					(size 0.7874 0.5842)
					(thickness 0.1524)
				)
				(justify left)
			)
		)
		(fp_text user "2"
			(at 2.053844 -10.992104 90)
			(unlocked yes)
			(layer "B.SilkS")
			(effects
				(font
					(size 0.7874 0.5842)
					(thickness 0.1524)
				)
				(justify left mirror)
			)
		)
		(fp_text user "12"
			(at 2.015744 2.274824 90)
			(unlocked yes)
			(layer "B.SilkS")
			(effects
				(font
					(size 0.7874 0.5842)
					(thickness 0.1524)
				)
				(justify left mirror)
			)
		)
		(fp_text user "1"
			(at 0.015748 -10.928604 90)
			(unlocked yes)
			(layer "B.SilkS")
			(effects
				(font
					(size 0.7874 0.5842)
					(thickness 0.1524)
				)
				(justify left mirror)
			)
		)
		(fp_text user "11"
			(at -0.098552 2.058924 90)
			(unlocked yes)
			(layer "B.SilkS")
			(effects
				(font
					(size 0.7874 0.5842)
					(thickness 0.1524)
				)
				(justify left mirror)
			)
		)
		(fp_text user "2"
			(at 2.079244 -10.661904 90)
			(unlocked yes)
			(layer "B.Fab")
			(effects
				(font
					(size 0.7874 0.5842)
					(thickness 0.000001)
				)
				(justify left mirror)
			)
		)
		(fp_text user "12"
			(at 2.066544 2.071624 90)
			(unlocked yes)
			(layer "B.Fab")
			(effects
				(font
					(size 0.7874 0.5842)
					(thickness 0.000001)
				)
				(justify left mirror)
			)
		)
		(fp_text user "1"
			(at 0.041148 -10.598404 90)
			(unlocked yes)
			(layer "B.Fab")
			(effects
				(font
					(size 0.7874 0.5842)
					(thickness 0.000001)
				)
				(justify left mirror)
			)
		)
		(fp_text user "11"
			(at -0.047752 1.855724 90)
			(unlocked yes)
			(layer "B.Fab")
			(effects
				(font
					(size 0.7874 0.5842)
					(thickness 0.000001)
				)
				(justify left mirror)
			)
		)
		(fp_text user "12"
			(at 4.733544 0.332994 90)
			(unlocked yes)
			(layer "F.Fab")
			(effects
				(font
					(size 0.7874 0.5842)
					(thickness 0.000001)
				)
				(justify left)
			)
		)
		(fp_text user "2"
			(at 4.708144 -11.031474 90)
			(unlocked yes)
			(layer "F.Fab")
			(effects
				(font
					(size 0.7874 0.5842)
					(thickness 0.000001)
				)
				(justify left)
			)
		)
		(fp_text user "1"
			(at -2.727452 -10.879074 90)
			(unlocked yes)
			(layer "F.Fab")
			(effects
				(font
					(size 0.7874 0.5842)
					(thickness 0.000001)
				)
				(justify left)
			)
		)
		(fp_text user "11"
			(at -2.740152 -0.632206 90)
			(unlocked yes)
			(layer "F.Fab")
			(effects
				(font
					(size 0.7874 0.5842)
					(thickness 0.000001)
				)
				(justify left)
			)
		)
		(pad "" np_thru_hole circle
			(at 0.999998 -8.999982 90)
			(size 1.0668 1.0668)
			(drill 1.0668)
			(layers "*.Cu" "*.Mask")
			(clearance 0.381)
			(thermal_gap 0.381)
		)
		(pad "" np_thru_hole circle
			(at 0.999998 -0.999998 90)
			(size 1.0668 1.0668)
			(drill 1.0668)
			(layers "*.Cu" "*.Mask")
			(clearance 0.381)
			(thermal_gap 0.381)
		)
		(pad "1" thru_hole circle
			(at 0 -9.99998 90)
			(size 1.3716 1.3716)
			(drill 0.9652)
			(layers "*.Cu" "*.Mask")
			(remove_unused_layers no)
			(net "PS_EN_PSU_N")
			(clearance 0.0508)
			(thermal_gap 0.0508)
		)
		(pad "2" thru_hole circle
			(at 1.999996 -9.99998 90)
			(size 1.3716 1.3716)
			(drill 0.9652)
			(layers "*.Cu" "*.Mask")
			(remove_unused_layers no)
			(net "Net_222")
			(clearance 0.0508)
			(thermal_gap 0.0508)
		)
		(pad "3" thru_hole circle
			(at 0 -7.999984 90)
			(size 1.3716 1.3716)
			(drill 0.9652)
			(layers "*.Cu" "*.Mask")
			(remove_unused_layers no)
			(net "Net_223")
			(clearance 0.0508)
			(thermal_gap 0.0508)
		)
		(pad "4" thru_hole circle
			(at 1.999996 -7.999984 90)
			(size 1.3716 1.3716)
			(drill 0.9652)
			(layers "*.Cu" "*.Mask")
			(remove_unused_layers no)
			(net "Net_224")
			(clearance 0.0508)
			(thermal_gap 0.0508)
		)
		(pad "5" thru_hole circle
			(at 0 -5.999988 90)
			(size 1.3716 1.3716)
			(drill 0.9652)
			(layers "*.Cu" "*.Mask")
			(remove_unused_layers no)
			(net "Net_225")
			(clearance 0.0508)
			(thermal_gap 0.0508)
		)
		(pad "6" thru_hole circle
			(at 1.999996 -5.999988 90)
			(size 1.3716 1.3716)
			(drill 0.9652)
			(layers "*.Cu" "*.Mask")
			(remove_unused_layers no)
			(net "Net_226")
			(clearance 0.0508)
			(thermal_gap 0.0508)
		)
		(pad "7" thru_hole circle
			(at 0 -3.999992 90)
			(size 1.3716 1.3716)
			(drill 0.9652)
			(layers "*.Cu" "*.Mask")
			(remove_unused_layers no)
			(net "Net_227")
			(clearance 0.0508)
			(thermal_gap 0.0508)
		)
		(pad "8" thru_hole circle
			(at 1.999996 -3.999992 90)
			(size 1.3716 1.3716)
			(drill 0.9652)
			(layers "*.Cu" "*.Mask")
			(remove_unused_layers no)
			(net "Net_228")
			(clearance 0.0508)
			(thermal_gap 0.0508)
		)
		(pad "9" thru_hole circle
			(at 0 -1.999996 90)
			(size 1.3716 1.3716)
			(drill 0.9652)
			(layers "*.Cu" "*.Mask")
			(remove_unused_layers no)
			(net "Net_229")
			(clearance 0.0508)
			(thermal_gap 0.0508)
		)
		(pad "10" thru_hole circle
			(at 1.999996 -1.999996 90)
			(size 1.3716 1.3716)
			(drill 0.9652)
			(layers "*.Cu" "*.Mask")
			(remove_unused_layers no)
			(net "Net_220")
			(clearance 0.0508)
			(thermal_gap 0.0508)
		)
		(pad "11" thru_hole circle
			(at 0 0 90)
			(size 1.3716 1.3716)
			(drill 0.9652)
			(layers "*.Cu" "*.Mask")
			(remove_unused_layers no)
			(net "GND")
			(clearance 0.0508)
			(thermal_gap 0.0508)
		)
		(pad "12" thru_hole circle
			(at 1.999996 0 90)
			(size 1.3716 1.3716)
			(drill 0.9652)
			(layers "*.Cu" "*.Mask")
			(remove_unused_layers no)
			(net "Net_221")
			(clearance 0.0508)
			(thermal_gap 0.0508)
		)
		(zone
			(layers "F.Cu" "B.Cu" "In1.Cu" "In2.Cu" "In3.Cu" "In4.Cu" "In5.Cu" "In6.Cu")
			(hatch none 0.5)
			(connect_pads
				(clearance 0)
			)
			(min_thickness 0.25)
			(keepout
				(tracks not_allowed)
				(vias allowed)
				(pads allowed)
				(copperpour not_allowed)
				(footprints allowed)
			)
			(placement
				(enabled no)
				(sheetname "")
			)
			(fill
				(thermal_gap 0.5)
				(thermal_bridge_width 0.5)
				(island_removal_mode 0)
			)
			(polygon
				(pts
					(arc
						(start 22.747732 -26.500074)
						(mid 22.737789 -26.363625)
						(end 22.708108 -26.230072)
					)
					(xy 22.063964 -26.230072) (xy 22.063964 -26.207466)
					(arc
						(start 22.063964 -25.597358)
						(mid 21.809964 -25.562304)
						(end 21.555964 -25.597358)
					)
					(xy 21.555964 -26.230072)
					(arc
						(start 20.91182 -26.230072)
						(mid 20.872114 -26.499551)
						(end 20.911566 -26.76906)
					)
					(xy 21.555456 -26.76906)
					(arc
						(start 21.555456 -27.402536)
						(mid 21.809964 -27.437737)
						(end 22.064472 -27.402536)
					)
					(xy 22.064472 -26.766266)
					(arc
						(start 22.709124 -26.766266)
						(mid 22.738005 -26.63456)
						(end 22.747732 -26.500074)
					)
				)
			)
		)
		(zone
			(layers "F.Cu" "B.Cu" "In1.Cu" "In2.Cu" "In3.Cu" "In4.Cu" "In5.Cu" "In6.Cu")
			(hatch none 0.5)
			(connect_pads
				(clearance 0)
			)
			(min_thickness 0.25)
			(keepout
				(tracks not_allowed)
				(vias allowed)
				(pads allowed)
				(copperpour not_allowed)
				(footprints allowed)
			)
			(placement
				(enabled no)
				(sheetname "")
			)
			(fill
				(thermal_gap 0.5)
				(thermal_bridge_width 0.5)
				(island_removal_mode 0)
			)
			(polygon
				(pts
					(arc
						(start 22.747732 -18.50009)
						(mid 22.737789 -18.363641)
						(end 22.708108 -18.230088)
					)
					(xy 22.063964 -18.230088) (xy 22.063964 -18.207482)
					(arc
						(start 22.063964 -17.597374)
						(mid 21.809964 -17.56232)
						(end 21.555964 -17.597374)
					)
					(xy 21.555964 -18.230088)
					(arc
						(start 20.91182 -18.230088)
						(mid 20.872114 -18.499567)
						(end 20.911566 -18.769076)
					)
					(xy 21.555456 -18.769076)
					(arc
						(start 21.555456 -19.402552)
						(mid 21.809964 -19.437753)
						(end 22.064472 -19.402552)
					)
					(xy 22.064472 -18.766282)
					(arc
						(start 22.709124 -18.766282)
						(mid 22.738005 -18.634576)
						(end 22.747732 -18.50009)
					)
				)
			)
		)
	)
	(footprint ""
		(layer "F.Cu")
		(at 344.333068 -21.674582 -90)
		(property "Reference" "R61"
			(at -3.336036 56.907684 90)
			(unlocked yes)
			(layer "F.SilkS")
			(effects
				(font
					(size 0.7874 0.5842)
					(thickness 0.1524)
				)
				(justify left)
			)
		)
		(property "Value" ""
			(at 0 0 270)
			(layer "F.Fab")
			(effects
				(font
					(size 1.27 1.27)
				)
			)
		)
		(duplicate_pad_numbers_are_jumpers no)
		(fp_line
			(start -0.7874 0.4064)
			(end -0.7874 -0.4064)
			(stroke
				(width 0.1524)
				(type default)
			)
			(layer "F.SilkS")
		)
		(fp_line
			(start 0.7874 0.4064)
			(end -0.7874 0.4064)
			(stroke
				(width 0.1524)
				(type default)
			)
			(layer "F.SilkS")
		)
		(fp_line
			(start -0.7874 -0.4064)
			(end 0.7874 -0.4064)
			(stroke
				(width 0.1524)
				(type default)
			)
			(layer "F.SilkS")
		)
		(fp_line
			(start 0.7874 -0.4064)
			(end 0.7874 0.4064)
			(stroke
				(width 0.1524)
				(type default)
			)
			(layer "F.SilkS")
		)
		(fp_poly
			(pts
				(xy -0.508 0.2794) (xy -0.508 0.2286) (xy -0.635 0.2286) (xy -0.635 -0.254) (xy -0.5334 -0.254)
				(xy -0.5334 -0.2794) (xy 0.5334 -0.2794) (xy 0.5334 -0.254) (xy 0.635 -0.254) (xy 0.635 0.254) (xy 0.5334 0.254)
				(xy 0.5334 0.2794)
			)
			(stroke
				(width 0)
				(type default)
			)
			(fill no)
			(layer "F.CrtYd")
		)
		(pad "1" smd rect
			(at 0.40005 0 270)
			(size 0.4572 0.508)
			(layers "F.Cu" "F.Mask" "F.Paste")
			(net "SKU_PIN_BLAD2_2")
		)
		(pad "2" smd rect
			(at -0.40005 0 270)
			(size 0.4572 0.508)
			(layers "F.Cu" "F.Mask" "F.Paste")
			(net "P3V3_BLAD2")
		)
	)
	(footprint ""
		(layer "F.Cu")
		(at 209.810096 -41.500044 180)
		(property "Reference" "H4"
			(at -3.594608 -3.83794 0)
			(unlocked yes)
			(layer "F.SilkS")
			(effects
				(font
					(size 0.7874 0.5842)
					(thickness 0.1524)
				)
				(justify left)
			)
		)
		(property "Value" ""
			(at 0 0 180)
			(layer "F.Fab")
			(effects
				(font
					(size 1.27 1.27)
				)
			)
		)
		(duplicate_pad_numbers_are_jumpers no)
		(fp_poly
			(pts
				(arc
					(start 3.999992 5.999988)
					(mid 0 9.99998)
					(end -3.999992 5.999988)
				)
				(arc
					(start -3.999992 0)
					(mid 0 -3.999992)
					(end 3.999992 0)
				)
			)
			(stroke
				(width 0)
				(type default)
			)
			(fill no)
			(layer "B.CrtYd")
		)
		(fp_poly
			(pts
				(arc
					(start 3.999992 5.999988)
					(mid 0 9.99998)
					(end -3.999992 5.999988)
				)
				(arc
					(start -3.999992 0)
					(mid 0 -3.999992)
					(end 3.999992 0)
				)
			)
			(stroke
				(width 0)
				(type default)
			)
			(fill no)
			(layer "F.CrtYd")
		)
		(pad "" np_thru_hole circle
			(at 0 0 180)
			(size 3.5052 3.5052)
			(drill 3.5052)
			(layers "*.Cu" "*.Mask")
			(clearance 0.381)
			(thermal_gap 0.381)
		)
		(zone
			(layers "F.Cu" "B.Cu" "In1.Cu" "In2.Cu" "In3.Cu" "In4.Cu" "In5.Cu" "In6.Cu")
			(hatch none 0.5)
			(connect_pads
				(clearance 0)
			)
			(min_thickness 0.25)
			(keepout
				(tracks not_allowed)
				(vias allowed)
				(pads allowed)
				(copperpour not_allowed)
				(footprints allowed)
			)
			(placement
				(enabled no)
				(sheetname "")
			)
			(fill
				(thermal_gap 0.5)
				(thermal_bridge_width 0.5)
				(island_removal_mode 0)
			)
			(polygon
				(pts
					(arc
						(start 207.398366 -44.952666)
						(mid 209.810096 -51.007954)
						(end 212.221826 -44.952666)
					)
					(arc
						(start 212.221826 -44.952666)
						(mid 212.108197 -44.789805)
						(end 212.068156 -44.595288)
					)
					(arc
						(start 212.068156 -41.500044)
						(mid 209.810096 -39.241984)
						(end 207.552036 -41.500044)
					)
					(arc
						(start 207.552036 -44.595288)
						(mid 207.51205 -44.789828)
						(end 207.398366 -44.952666)
					)
				)
			)
		)
	)
	(footprint ""
		(layer "F.Cu")
		(at 142.49019 -14.390116 180)
		(property "Reference" "U5"
			(at 2.73558 -10.552684 0)
			(unlocked yes)
			(layer "F.SilkS")
			(effects
				(font
					(size 0.7874 0.5842)
					(thickness 0.1524)
				)
				(justify left)
			)
		)
		(property "Value" ""
			(at 0 0 180)
			(layer "F.Fab")
			(effects
				(font
					(size 1.27 1.27)
				)
			)
		)
		(duplicate_pad_numbers_are_jumpers no)
		(fp_line
			(start 5.500116 3.700018)
			(end 4.191 3.700018)
			(stroke
				(width 0.1524)
				(type default)
			)
			(layer "F.SilkS")
		)
		(fp_line
			(start 5.500116 0.889)
			(end 5.500116 3.700018)
			(stroke
				(width 0.1524)
				(type default)
			)
			(layer "F.SilkS")
		)
		(fp_line
			(start 5.500116 -3.700018)
			(end 5.500116 -0.889)
			(stroke
				(width 0.1524)
				(type default)
			)
			(layer "F.SilkS")
		)
		(fp_line
			(start 3.7846 -3.700018)
			(end 5.500116 -3.700018)
			(stroke
				(width 0.1524)
				(type default)
			)
			(layer "F.SilkS")
		)
		(fp_line
			(start -3.7846 3.700018)
			(end -5.500116 3.700018)
			(stroke
				(width 0.1524)
				(type default)
			)
			(layer "F.SilkS")
		)
		(fp_line
			(start -5.500116 0.635)
			(end -5.500116 3.700018)
			(stroke
				(width 0.1524)
				(type default)
			)
			(layer "F.SilkS")
		)
		(fp_line
			(start -5.500116 -3.700018)
			(end -4.191 -3.700018)
			(stroke
				(width 0.1524)
				(type default)
			)
			(layer "F.SilkS")
		)
		(fp_line
			(start -5.500116 -3.700018)
			(end -5.500116 -0.635)
			(stroke
				(width 0.1524)
				(type default)
			)
			(layer "F.SilkS")
		)
		(fp_poly
			(pts
				(xy -3.387344 5.3848) (xy -3.946144 6.8072) (xy -2.853944 6.8072)
			)
			(stroke
				(width 0)
				(type default)
			)
			(fill yes)
			(layer "F.SilkS")
		)
		(fp_poly
			(pts
				(arc
					(start -4.064 -0.3302)
					(mid -4.8006 -1.0668)
					(end -5.5372 -0.3302)
				)
				(arc
					(start -5.5372 0.3048)
					(mid -5.314015 0.843615)
					(end -4.7752 1.0668)
				)
				(arc
					(start -4.7752 1.0668)
					(mid -4.272306 0.858494)
					(end -4.064 0.3556)
				)
			)
			(stroke
				(width 0)
				(type default)
			)
			(fill no)
			(layer "B.CrtYd")
		)
		(fp_poly
			(pts
				(arc
					(start 3.7338 0)
					(mid 5.8674 0)
					(end 3.7338 0)
				)
			)
			(stroke
				(width 0)
				(type default)
			)
			(fill no)
			(layer "B.CrtYd")
		)
		(fp_rect
			(start -5.5118 5.1308)
			(end 5.5118 -5.1308)
			(stroke
				(width 0)
				(type default)
			)
			(fill no)
			(layer "F.CrtYd")
		)
		(fp_text user "10"
			(at 4.718304 5.233924 90)
			(unlocked yes)
			(layer "F.SilkS")
			(effects
				(font
					(size 0.7874 0.5842)
					(thickness 0.1524)
				)
				(justify left)
			)
		)
		(fp_text user "11"
			(at 3.219704 -6.399276 90)
			(unlocked yes)
			(layer "F.SilkS")
			(effects
				(font
					(size 0.7874 0.5842)
					(thickness 0.1524)
				)
				(justify left)
			)
		)
		(fp_text user "1"
			(at -3.797046 5.749798 0)
			(unlocked yes)
			(layer "F.SilkS")
			(effects
				(font
					(size 0.7874 0.5842)
					(thickness 0.1524)
				)
				(justify left)
			)
		)
		(fp_text user "20"
			(at -4.578096 -8.583676 90)
			(unlocked yes)
			(layer "F.SilkS")
			(effects
				(font
					(size 0.7874 0.5842)
					(thickness 0.1524)
				)
				(justify left)
			)
		)
		(pad "" np_thru_hole oval
			(at -4.800092 0 180)
			(size 0.9652 1.6002)
			(drill oval 0.9652 1.6002)
			(layers "*.Cu" "*.Mask")
			(clearance 0.381)
			(thermal_gap 0.381)
		)
		(pad "" np_thru_hole circle
			(at 4.800092 0 180)
			(size 1.6002 1.6002)
			(drill 1.6002)
			(layers "*.Cu" "*.Mask")
			(clearance 0.381)
			(thermal_gap 0.381)
		)
		(pad "1" smd oval
			(at -3.400044 4.100068 180)
			(size 0.508 2.032)
			(layers "F.Cu" "F.Mask" "F.Paste")
			(net "GND")
		)
		(pad "2" smd oval
			(at -2.599944 4.100068 180)
			(size 0.508 2.032)
			(layers "F.Cu" "F.Mask" "F.Paste")
			(net "ENET10G_1_TX_FAULT")
		)
		(pad "3" smd oval
			(at -1.800098 4.100068 180)
			(size 0.508 2.032)
			(layers "F.Cu" "F.Mask" "F.Paste")
			(net "ENET10G_1_TX_DIS")
		)
		(pad "4" smd oval
			(at -0.999998 4.100068 180)
			(size 0.508 2.032)
			(layers "F.Cu" "F.Mask" "F.Paste")
			(net "ENET10G_1_SDA")
		)
		(pad "5" smd oval
			(at -0.199898 4.100068 180)
			(size 0.508 2.032)
			(layers "F.Cu" "F.Mask" "F.Paste")
			(net "ENET10G_1_SCL")
		)
		(pad "6" smd oval
			(at 0.599948 4.100068 180)
			(size 0.508 2.032)
			(layers "F.Cu" "F.Mask" "F.Paste")
			(net "ENET10G_1_MOD_DEF0")
		)
		(pad "7" smd oval
			(at 1.400048 4.100068 180)
			(size 0.508 2.032)
			(layers "F.Cu" "F.Mask" "F.Paste")
			(net "ENET10G_1_RS0")
		)
		(pad "8" smd oval
			(at 2.199894 4.100068 180)
			(size 0.508 2.032)
			(layers "F.Cu" "F.Mask" "F.Paste")
			(net "ENET10G_1_LOS")
		)
		(pad "9" smd oval
			(at 2.999994 4.100068 180)
			(size 0.508 2.032)
			(layers "F.Cu" "F.Mask" "F.Paste")
			(net "ENET10G_1_RS1")
		)
		(pad "10" smd oval
			(at 3.800094 4.100068 180)
			(size 0.508 2.032)
			(layers "F.Cu" "F.Mask" "F.Paste")
			(net "GND")
		)
		(pad "11" smd oval
			(at 3.400044 -4.100068 180)
			(size 0.508 2.032)
			(layers "F.Cu" "F.Mask" "F.Paste")
			(net "GND")
		)
		(pad "12" smd oval
			(at 2.599944 -4.100068 180)
			(size 0.508 2.032)
			(layers "F.Cu" "F.Mask" "F.Paste")
			(net "ENET10G_1_RDN")
		)
		(pad "13" smd oval
			(at 1.800098 -4.100068 180)
			(size 0.508 2.032)
			(layers "F.Cu" "F.Mask" "F.Paste")
			(net "ENET10G_1_RDP")
		)
		(pad "14" smd oval
			(at 0.999998 -4.100068 180)
			(size 0.508 2.032)
			(layers "F.Cu" "F.Mask" "F.Paste")
			(net "GND")
		)
		(pad "15" smd oval
			(at 0.199898 -4.100068 180)
			(size 0.508 2.032)
			(layers "F.Cu" "F.Mask" "F.Paste")
			(net "P3V3_10G_1_VCCR")
		)
		(pad "16" smd oval
			(at -0.599948 -4.100068 180)
			(size 0.508 2.032)
			(layers "F.Cu" "F.Mask" "F.Paste")
			(net "P3V3_10G_1_VCCT")
		)
		(pad "17" smd oval
			(at -1.400048 -4.100068 180)
			(size 0.508 2.032)
			(layers "F.Cu" "F.Mask" "F.Paste")
			(net "GND")
		)
		(pad "18" smd oval
			(at -2.199894 -4.100068 180)
			(size 0.508 2.032)
			(layers "F.Cu" "F.Mask" "F.Paste")
			(net "ENET10G_1_TDP")
		)
		(pad "19" smd oval
			(at -2.999994 -4.100068 180)
			(size 0.508 2.032)
			(layers "F.Cu" "F.Mask" "F.Paste")
			(net "ENET10G_1_TDN")
		)
		(pad "20" smd oval
			(at -3.800094 -4.100068 180)
			(size 0.508 2.032)
			(layers "F.Cu" "F.Mask" "F.Paste")
			(net "GND")
		)
		(zone
			(layers "F.Cu" "B.Cu" "In1.Cu" "In2.Cu" "In3.Cu" "In4.Cu" "In5.Cu" "In6.Cu")
			(hatch none 0.5)
			(connect_pads
				(clearance 0)
			)
			(min_thickness 0.25)
			(keepout
				(tracks not_allowed)
				(vias allowed)
				(pads allowed)
				(copperpour not_allowed)
				(footprints allowed)
			)
			(placement
				(enabled no)
				(sheetname "")
			)
			(fill
				(thermal_gap 0.5)
				(thermal_bridge_width 0.5)
				(island_removal_mode 0)
			)
			(polygon
				(pts
					(arc
						(start 147.26539 -15.609316)
						(mid 147.911968 -15.341494)
						(end 148.17979 -14.694916)
					)
					(arc
						(start 148.17979 -14.059916)
						(mid 147.29079 -13.170916)
						(end 146.40179 -14.059916)
					)
					(arc
						(start 146.40179 -14.745716)
						(mid 146.654733 -15.356373)
						(end 147.26539 -15.609316)
					)
				)
			)
		)
		(zone
			(layers "F.Cu" "B.Cu" "In1.Cu" "In2.Cu" "In3.Cu" "In4.Cu" "In5.Cu" "In6.Cu")
			(hatch none 0.5)
			(connect_pads
				(clearance 0)
			)
			(min_thickness 0.25)
			(keepout
				(tracks not_allowed)
				(vias allowed)
				(pads allowed)
				(copperpour not_allowed)
				(footprints allowed)
			)
			(placement
				(enabled no)
				(sheetname "")
			)
			(fill
				(thermal_gap 0.5)
				(thermal_bridge_width 0.5)
				(island_removal_mode 0)
			)
			(polygon
				(pts
					(arc
						(start 138.90879 -14.390116)
						(mid 136.47039 -14.390116)
						(end 138.90879 -14.390116)
					)
				)
			)
		)
	)
	(footprint ""
		(layer "F.Cu")
		(at 92.16644 -26.152094)
		(property "Reference" "R16"
			(at -7.0866 0.162052 0)
			(unlocked yes)
			(layer "F.SilkS")
			(effects
				(font
					(size 0.7874 0.5842)
					(thickness 0.1524)
				)
				(justify left)
			)
		)
		(property "Value" ""
			(at 0 0 0)
			(layer "F.Fab")
			(effects
				(font
					(size 1.27 1.27)
				)
			)
		)
		(duplicate_pad_numbers_are_jumpers no)
		(fp_line
			(start -0.7874 -0.4064)
			(end 0.7874 -0.4064)
			(stroke
				(width 0.1524)
				(type default)
			)
			(layer "F.SilkS")
		)
		(fp_line
			(start -0.7874 0.4064)
			(end -0.7874 -0.4064)
			(stroke
				(width 0.1524)
				(type default)
			)
			(layer "F.SilkS")
		)
		(fp_line
			(start 0.7874 -0.4064)
			(end 0.7874 0.4064)
			(stroke
				(width 0.1524)
				(type default)
			)
			(layer "F.SilkS")
		)
		(fp_line
			(start 0.7874 0.4064)
			(end -0.7874 0.4064)
			(stroke
				(width 0.1524)
				(type default)
			)
			(layer "F.SilkS")
		)
		(fp_poly
			(pts
				(xy -0.508 0.2794) (xy -0.508 0.2286) (xy -0.635 0.2286) (xy -0.635 -0.254) (xy -0.5334 -0.254)
				(xy -0.5334 -0.2794) (xy 0.5334 -0.2794) (xy 0.5334 -0.254) (xy 0.635 -0.254) (xy 0.635 0.254) (xy 0.5334 0.254)
				(xy 0.5334 0.2794)
			)
			(stroke
				(width 0)
				(type default)
			)
			(fill no)
			(layer "F.CrtYd")
		)
		(pad "1" smd rect
			(at 0.40005 0)
			(size 0.4572 0.508)
			(layers "F.Cu" "F.Mask" "F.Paste")
			(net "P3V3_BLAD1")
		)
		(pad "2" smd rect
			(at -0.40005 0)
			(size 0.4572 0.508)
			(layers "F.Cu" "F.Mask" "F.Paste")
			(net "ENET10G_2_RS1")
		)
	)
	(footprint ""
		(layer "F.Cu")
		(at 325.5264 -2.6416 90)
		(property "Reference" "C28"
			(at -1.6002 -4.333748 90)
			(unlocked yes)
			(layer "F.SilkS")
			(effects
				(font
					(size 0.7874 0.5842)
					(thickness 0.1524)
				)
				(justify left)
			)
		)
		(property "Value" ""
			(at 0 0 90)
			(layer "F.Fab")
			(effects
				(font
					(size 1.27 1.27)
				)
			)
		)
		(duplicate_pad_numbers_are_jumpers no)
		(fp_line
			(start 0.7874 -0.4064)
			(end 0.7874 0.4064)
			(stroke
				(width 0.1524)
				(type default)
			)
			(layer "F.SilkS")
		)
		(fp_line
			(start -0.7874 -0.4064)
			(end 0.7874 -0.4064)
			(stroke
				(width 0.1524)
				(type default)
			)
			(layer "F.SilkS")
		)
		(fp_line
			(start 0 0.381)
			(end 0 -0.381)
			(stroke
				(width 0.1524)
				(type default)
			)
			(layer "F.SilkS")
		)
		(fp_line
			(start 0.7874 0.4064)
			(end -0.7874 0.4064)
			(stroke
				(width 0.1524)
				(type default)
			)
			(layer "F.SilkS")
		)
		(fp_line
			(start -0.7874 0.4064)
			(end -0.7874 -0.4064)
			(stroke
				(width 0.1524)
				(type default)
			)
			(layer "F.SilkS")
		)
		(fp_poly
			(pts
				(xy -0.5334 0.254) (xy -0.635 0.254) (xy -0.635 0.2286) (xy -0.635 -0.254) (xy -0.5334 -0.254) (xy -0.5334 -0.2794)
				(xy 0.5334 -0.2794) (xy 0.5334 -0.254) (xy 0.635 -0.254) (xy 0.635 0.254) (xy 0.5334 0.254) (xy 0.5334 0.2794)
				(xy -0.508 0.2794) (xy -0.5334 0.2794)
			)
			(stroke
				(width 0)
				(type default)
			)
			(fill no)
			(layer "F.CrtYd")
		)
		(pad "1" smd rect
			(at 0.40005 0 90)
			(size 0.4572 0.508)
			(layers "F.Cu" "F.Mask" "F.Paste")
			(net "P3V3_10G_4_VCCT")
		)
		(pad "2" smd rect
			(at -0.40005 0 90)
			(size 0.4572 0.508)
			(layers "F.Cu" "F.Mask" "F.Paste")
			(net "GND")
		)
	)
	(footprint ""
		(layer "F.Cu")
		(at 157.781752 -22.899878)
		(property "Reference" "R40"
			(at 33.5534 17.942052 0)
			(unlocked yes)
			(layer "F.SilkS")
			(effects
				(font
					(size 0.7874 0.5842)
					(thickness 0.1524)
				)
				(justify left)
			)
		)
		(property "Value" ""
			(at 0 0 0)
			(layer "F.Fab")
			(effects
				(font
					(size 1.27 1.27)
				)
			)
		)
		(duplicate_pad_numbers_are_jumpers no)
		(fp_line
			(start -0.7874 -0.4064)
			(end 0.7874 -0.4064)
			(stroke
				(width 0.1524)
				(type default)
			)
			(layer "F.SilkS")
		)
		(fp_line
			(start -0.7874 0.4064)
			(end -0.7874 -0.4064)
			(stroke
				(width 0.1524)
				(type default)
			)
			(layer "F.SilkS")
		)
		(fp_line
			(start 0.7874 -0.4064)
			(end 0.7874 0.4064)
			(stroke
				(width 0.1524)
				(type default)
			)
			(layer "F.SilkS")
		)
		(fp_line
			(start 0.7874 0.4064)
			(end -0.7874 0.4064)
			(stroke
				(width 0.1524)
				(type default)
			)
			(layer "F.SilkS")
		)
		(fp_poly
			(pts
				(xy -0.508 0.2794) (xy -0.508 0.2286) (xy -0.635 0.2286) (xy -0.635 -0.254) (xy -0.5334 -0.254)
				(xy -0.5334 -0.2794) (xy 0.5334 -0.2794) (xy 0.5334 -0.254) (xy 0.635 -0.254) (xy 0.635 0.254) (xy 0.5334 0.254)
				(xy 0.5334 0.2794)
			)
			(stroke
				(width 0)
				(type default)
			)
			(fill no)
			(layer "F.CrtYd")
		)
		(pad "1" smd rect
			(at 0.40005 0)
			(size 0.4572 0.508)
			(layers "F.Cu" "F.Mask" "F.Paste")
			(net "GND")
		)
		(pad "2" smd rect
			(at -0.40005 0)
			(size 0.4572 0.508)
			(layers "F.Cu" "F.Mask" "F.Paste")
			(net "ENET10G_1_TX_FAULT")
		)
	)
	(footprint ""
		(layer "F.Cu")
		(at 199.049894 -4.700016 180)
		(property "Reference" "H1"
			(at -1.899412 10.961116 0)
			(unlocked yes)
			(layer "F.SilkS")
			(effects
				(font
					(size 0.7874 0.5842)
					(thickness 0.1524)
				)
				(justify left)
			)
		)
		(property "Value" ""
			(at 0 0 180)
			(layer "F.Fab")
			(effects
				(font
					(size 1.27 1.27)
				)
			)
		)
		(duplicate_pad_numbers_are_jumpers no)
		(fp_poly
			(pts
				(arc
					(start 3.999992 5.999988)
					(mid 0 9.99998)
					(end -3.999992 5.999988)
				)
				(arc
					(start -3.999992 0)
					(mid 0 -3.999992)
					(end 3.999992 0)
				)
			)
			(stroke
				(width 0)
				(type default)
			)
			(fill no)
			(layer "B.CrtYd")
		)
		(fp_poly
			(pts
				(arc
					(start 3.999992 5.999988)
					(mid 0 9.99998)
					(end -3.999992 5.999988)
				)
				(arc
					(start -3.999992 0)
					(mid 0 -3.999992)
					(end 3.999992 0)
				)
			)
			(stroke
				(width 0)
				(type default)
			)
			(fill no)
			(layer "F.CrtYd")
		)
		(pad "" np_thru_hole circle
			(at 0 0 180)
			(size 3.5052 3.5052)
			(drill 3.5052)
			(layers "*.Cu" "*.Mask")
			(clearance 0.381)
			(thermal_gap 0.381)
		)
		(zone
			(layers "F.Cu" "B.Cu" "In1.Cu" "In2.Cu" "In3.Cu" "In4.Cu" "In5.Cu" "In6.Cu")
			(hatch none 0.5)
			(connect_pads
				(clearance 0)
			)
			(min_thickness 0.25)
			(keepout
				(tracks not_allowed)
				(vias allowed)
				(pads allowed)
				(copperpour not_allowed)
				(footprints allowed)
			)
			(placement
				(enabled no)
				(sheetname "")
			)
			(fill
				(thermal_gap 0.5)
				(thermal_bridge_width 0.5)
				(island_removal_mode 0)
			)
			(polygon
				(pts
					(arc
						(start 196.638164 -8.152638)
						(mid 199.049894 -14.207926)
						(end 201.461624 -8.152638)
					)
					(arc
						(start 201.461624 -8.152638)
						(mid 201.347995 -7.989777)
						(end 201.307954 -7.79526)
					)
					(arc
						(start 201.307954 -4.700016)
						(mid 199.049894 -2.441956)
						(end 196.791834 -4.700016)
					)
					(arc
						(start 196.791834 -7.79526)
						(mid 196.751848 -7.9898)
						(end 196.638164 -8.152638)
					)
				)
			)
		)
	)
	(footprint ""
		(layer "F.Cu")
		(at 308.3814 -33.6804 90)
		(property "Reference" "L6"
			(at -0.9398 -3.68173 90)
			(unlocked yes)
			(layer "F.SilkS")
			(effects
				(font
					(size 0.7874 0.5842)
					(thickness 0.1524)
				)
				(justify left)
			)
		)
		(property "Value" ""
			(at 0 0 90)
			(layer "F.Fab")
			(effects
				(font
					(size 1.27 1.27)
				)
			)
		)
		(duplicate_pad_numbers_are_jumpers no)
		(fp_line
			(start -1.905 -0.8636)
			(end 1.905 -0.8636)
			(stroke
				(width 0.1524)
				(type default)
			)
			(layer "F.SilkS")
		)
		(fp_line
			(start 1.905 0.8382)
			(end 1.905 -0.8382)
			(stroke
				(width 0.1524)
				(type default)
			)
			(layer "F.SilkS")
		)
		(fp_line
			(start 0.127 0.8382)
			(end 0.127 -0.8382)
			(stroke
				(width 0.1524)
				(type default)
			)
			(layer "F.SilkS")
		)
		(fp_line
			(start -0.127 0.8382)
			(end -0.127 -0.8382)
			(stroke
				(width 0.1524)
				(type default)
			)
			(layer "F.SilkS")
		)
		(fp_line
			(start -1.905 0.8382)
			(end -1.905 -0.8382)
			(stroke
				(width 0.1524)
				(type default)
			)
			(layer "F.SilkS")
		)
		(fp_line
			(start 1.905 0.8636)
			(end -1.905 0.8636)
			(stroke
				(width 0.1524)
				(type default)
			)
			(layer "F.SilkS")
		)
		(fp_rect
			(start -1.524 0.7112)
			(end 1.524 -0.7366)
			(stroke
				(width 0)
				(type default)
			)
			(fill no)
			(layer "F.CrtYd")
		)
		(pad "1" smd rect
			(at 0.94996 0 90)
			(size 1.1176 1.3716)
			(layers "F.Cu" "F.Mask" "F.Paste")
			(net "P3V3_10G_4_VCCT_L")
		)
		(pad "2" smd rect
			(at -0.94996 0 90)
			(size 1.1176 1.3716)
			(layers "F.Cu" "F.Mask" "F.Paste")
			(net "P3V3_10G_4_VCCT")
		)
	)
	(footprint ""
		(layer "F.Cu")
		(at 130.101848 -24.348694 180)
		(property "Reference" "R9"
			(at 61.753496 -5.01904 0)
			(unlocked yes)
			(layer "F.SilkS")
			(effects
				(font
					(size 0.7874 0.5842)
					(thickness 0.1524)
				)
				(justify left)
			)
		)
		(property "Value" ""
			(at 0 0 180)
			(layer "F.Fab")
			(effects
				(font
					(size 1.27 1.27)
				)
			)
		)
		(duplicate_pad_numbers_are_jumpers no)
		(fp_line
			(start 0.7874 0.4064)
			(end -0.7874 0.4064)
			(stroke
				(width 0.1524)
				(type default)
			)
			(layer "F.SilkS")
		)
		(fp_line
			(start 0.7874 -0.4064)
			(end 0.7874 0.4064)
			(stroke
				(width 0.1524)
				(type default)
			)
			(layer "F.SilkS")
		)
		(fp_line
			(start -0.7874 0.4064)
			(end -0.7874 -0.4064)
			(stroke
				(width 0.1524)
				(type default)
			)
			(layer "F.SilkS")
		)
		(fp_line
			(start -0.7874 -0.4064)
			(end 0.7874 -0.4064)
			(stroke
				(width 0.1524)
				(type default)
			)
			(layer "F.SilkS")
		)
		(fp_poly
			(pts
				(xy -0.508 0.2794) (xy -0.508 0.2286) (xy -0.635 0.2286) (xy -0.635 -0.254) (xy -0.5334 -0.254)
				(xy -0.5334 -0.2794) (xy 0.5334 -0.2794) (xy 0.5334 -0.254) (xy 0.635 -0.254) (xy 0.635 0.254) (xy 0.5334 0.254)
				(xy 0.5334 0.2794)
			)
			(stroke
				(width 0)
				(type default)
			)
			(fill no)
			(layer "F.CrtYd")
		)
		(pad "1" smd rect
			(at 0.40005 0 180)
			(size 0.4572 0.508)
			(layers "F.Cu" "F.Mask" "F.Paste")
			(net "P3V3_BLAD1")
		)
		(pad "2" smd rect
			(at -0.40005 0 180)
			(size 0.4572 0.508)
			(layers "F.Cu" "F.Mask" "F.Paste")
			(net "ENET10G_1_MOD_DEF0")
		)
	)
	(footprint ""
		(layer "F.Cu")
		(at 310.308752 -30.368494 180)
		(property "Reference" "R54"
			(at 6.826504 0.72136 0)
			(unlocked yes)
			(layer "F.SilkS")
			(effects
				(font
					(size 0.7874 0.5842)
					(thickness 0.1524)
				)
				(justify left)
			)
		)
		(property "Value" ""
			(at 0 0 180)
			(layer "F.Fab")
			(effects
				(font
					(size 1.27 1.27)
				)
			)
		)
		(duplicate_pad_numbers_are_jumpers no)
		(fp_line
			(start 0.7874 0.4064)
			(end -0.7874 0.4064)
			(stroke
				(width 0.1524)
				(type default)
			)
			(layer "F.SilkS")
		)
		(fp_line
			(start 0.7874 -0.4064)
			(end 0.7874 0.4064)
			(stroke
				(width 0.1524)
				(type default)
			)
			(layer "F.SilkS")
		)
		(fp_line
			(start -0.7874 0.4064)
			(end -0.7874 -0.4064)
			(stroke
				(width 0.1524)
				(type default)
			)
			(layer "F.SilkS")
		)
		(fp_line
			(start -0.7874 -0.4064)
			(end 0.7874 -0.4064)
			(stroke
				(width 0.1524)
				(type default)
			)
			(layer "F.SilkS")
		)
		(fp_poly
			(pts
				(xy -0.508 0.2794) (xy -0.508 0.2286) (xy -0.635 0.2286) (xy -0.635 -0.254) (xy -0.5334 -0.254)
				(xy -0.5334 -0.2794) (xy 0.5334 -0.2794) (xy 0.5334 -0.254) (xy 0.635 -0.254) (xy 0.635 0.254) (xy 0.5334 0.254)
				(xy 0.5334 0.2794)
			)
			(stroke
				(width 0)
				(type default)
			)
			(fill no)
			(layer "F.CrtYd")
		)
		(pad "1" smd rect
			(at 0.40005 0 180)
			(size 0.4572 0.508)
			(layers "F.Cu" "F.Mask" "F.Paste")
			(net "GND")
		)
		(pad "2" smd rect
			(at -0.40005 0 180)
			(size 0.4572 0.508)
			(layers "F.Cu" "F.Mask" "F.Paste")
			(net "ENET10G_4_TX_FAULT")
		)
	)
	(footprint ""
		(layer "F.Cu")
		(at 89.41816 -26.152094 180)
		(property "Reference" "R45"
			(at 7.13232 -0.21844 0)
			(unlocked yes)
			(layer "F.SilkS")
			(effects
				(font
					(size 0.7874 0.5842)
					(thickness 0.1524)
				)
				(justify left)
			)
		)
		(property "Value" ""
			(at 0 0 180)
			(layer "F.Fab")
			(effects
				(font
					(size 1.27 1.27)
				)
			)
		)
		(duplicate_pad_numbers_are_jumpers no)
		(fp_line
			(start 0.7874 0.4064)
			(end -0.7874 0.4064)
			(stroke
				(width 0.1524)
				(type default)
			)
			(layer "F.SilkS")
		)
		(fp_line
			(start 0.7874 -0.4064)
			(end 0.7874 0.4064)
			(stroke
				(width 0.1524)
				(type default)
			)
			(layer "F.SilkS")
		)
		(fp_line
			(start -0.7874 0.4064)
			(end -0.7874 -0.4064)
			(stroke
				(width 0.1524)
				(type default)
			)
			(layer "F.SilkS")
		)
		(fp_line
			(start -0.7874 -0.4064)
			(end 0.7874 -0.4064)
			(stroke
				(width 0.1524)
				(type default)
			)
			(layer "F.SilkS")
		)
		(fp_poly
			(pts
				(xy -0.508 0.2794) (xy -0.508 0.2286) (xy -0.635 0.2286) (xy -0.635 -0.254) (xy -0.5334 -0.254)
				(xy -0.5334 -0.2794) (xy 0.5334 -0.2794) (xy 0.5334 -0.254) (xy 0.635 -0.254) (xy 0.635 0.254) (xy 0.5334 0.254)
				(xy 0.5334 0.2794)
			)
			(stroke
				(width 0)
				(type default)
			)
			(fill no)
			(layer "F.CrtYd")
		)
		(pad "1" smd rect
			(at 0.40005 0 180)
			(size 0.4572 0.508)
			(layers "F.Cu" "F.Mask" "F.Paste")
			(net "GND")
		)
		(pad "2" smd rect
			(at -0.40005 0 180)
			(size 0.4572 0.508)
			(layers "F.Cu" "F.Mask" "F.Paste")
			(net "ENET10G_2_RS1")
		)
	)
	(footprint ""
		(layer "F.Cu")
		(at 377.063 -29.859732 180)
		(property "Reference" "R80"
			(at -34.163 -18.064734 0)
			(unlocked yes)
			(layer "F.SilkS")
			(effects
				(font
					(size 0.7874 0.5842)
					(thickness 0.1524)
				)
				(justify left)
			)
		)
		(property "Value" ""
			(at 0 0 180)
			(layer "F.Fab")
			(effects
				(font
					(size 1.27 1.27)
				)
			)
		)
		(duplicate_pad_numbers_are_jumpers no)
		(fp_line
			(start 1.905 0.8636)
			(end -1.905 0.8636)
			(stroke
				(width 0.1524)
				(type default)
			)
			(layer "F.SilkS")
		)
		(fp_line
			(start 1.905 -0.8636)
			(end 1.905 0.8636)
			(stroke
				(width 0.1524)
				(type default)
			)
			(layer "F.SilkS")
		)
		(fp_line
			(start -1.905 0.8636)
			(end -1.905 -0.8636)
			(stroke
				(width 0.1524)
				(type default)
			)
			(layer "F.SilkS")
		)
		(fp_line
			(start -1.905 -0.8636)
			(end 1.905 -0.8636)
			(stroke
				(width 0.1524)
				(type default)
			)
			(layer "F.SilkS")
		)
		(fp_poly
			(pts
				(xy 1.524 0.6858) (xy 1.524 -0.6858) (xy 1.524 -0.7366) (xy -1.524 -0.7366) (xy -1.524 -0.6858)
				(xy -1.524 0.6858) (xy -1.524 0.7366) (xy 1.524 0.7366)
			)
			(stroke
				(width 0)
				(type default)
			)
			(fill no)
			(layer "F.CrtYd")
		)
		(pad "1" smd rect
			(at 0.94996 0 180)
			(size 1.1176 1.3716)
			(layers "F.Cu" "F.Mask" "F.Paste")
			(net "P3V3_BLAD2")
		)
		(pad "2" smd rect
			(at -0.94996 0 180)
			(size 1.1176 1.3716)
			(layers "F.Cu" "F.Mask" "F.Paste")
			(net "P3V3_10G_3_VCCT")
		)
	)
	(footprint ""
		(layer "F.Cu")
		(at 130.101848 -26.533094 180)
		(property "Reference" "R5"
			(at 61.651896 -5.14604 0)
			(unlocked yes)
			(layer "F.SilkS")
			(effects
				(font
					(size 0.7874 0.5842)
					(thickness 0.1524)
				)
				(justify left)
			)
		)
		(property "Value" ""
			(at 0 0 180)
			(layer "F.Fab")
			(effects
				(font
					(size 1.27 1.27)
				)
			)
		)
		(duplicate_pad_numbers_are_jumpers no)
		(fp_line
			(start 0.7874 0.4064)
			(end -0.7874 0.4064)
			(stroke
				(width 0.1524)
				(type default)
			)
			(layer "F.SilkS")
		)
		(fp_line
			(start 0.7874 -0.4064)
			(end 0.7874 0.4064)
			(stroke
				(width 0.1524)
				(type default)
			)
			(layer "F.SilkS")
		)
		(fp_line
			(start -0.7874 0.4064)
			(end -0.7874 -0.4064)
			(stroke
				(width 0.1524)
				(type default)
			)
			(layer "F.SilkS")
		)
		(fp_line
			(start -0.7874 -0.4064)
			(end 0.7874 -0.4064)
			(stroke
				(width 0.1524)
				(type default)
			)
			(layer "F.SilkS")
		)
		(fp_poly
			(pts
				(xy -0.508 0.2794) (xy -0.508 0.2286) (xy -0.635 0.2286) (xy -0.635 -0.254) (xy -0.5334 -0.254)
				(xy -0.5334 -0.2794) (xy 0.5334 -0.2794) (xy 0.5334 -0.254) (xy 0.635 -0.254) (xy 0.635 0.254) (xy 0.5334 0.254)
				(xy 0.5334 0.2794)
			)
			(stroke
				(width 0)
				(type default)
			)
			(fill no)
			(layer "F.CrtYd")
		)
		(pad "1" smd rect
			(at 0.40005 0 180)
			(size 0.4572 0.508)
			(layers "F.Cu" "F.Mask" "F.Paste")
			(net "P3V3_BLAD1")
		)
		(pad "2" smd rect
			(at -0.40005 0 180)
			(size 0.4572 0.508)
			(layers "F.Cu" "F.Mask" "F.Paste")
			(net "ENET10G_1_SDA")
		)
	)
	(footprint ""
		(layer "F.Cu")
		(at 349.530162 -2.100072 180)
		(property "Reference" "J7"
			(at -4.826762 -0.729234 90)
			(unlocked yes)
			(layer "F.SilkS")
			(effects
				(font
					(size 0.7874 0.5842)
					(thickness 0.1524)
				)
				(justify left)
			)
		)
		(property "Value" ""
			(at 0 0 180)
			(layer "F.Fab")
			(effects
				(font
					(size 1.27 1.27)
				)
			)
		)
		(duplicate_pad_numbers_are_jumpers no)
		(fp_line
			(start 13.999972 18.375122)
			(end 13.999972 6.866128)
			(stroke
				(width 0.1524)
				(type default)
			)
			(layer "F.SilkS")
		)
		(fp_line
			(start 13.999972 2.471928)
			(end 13.999972 -14.675104)
			(stroke
				(width 0.1524)
				(type default)
			)
			(layer "F.SilkS")
		)
		(fp_line
			(start 13.999972 -14.675104)
			(end -3.999992 -14.675104)
			(stroke
				(width 0.1524)
				(type default)
			)
			(layer "F.SilkS")
		)
		(fp_line
			(start 10.999978 15.375128)
			(end 10.999978 -11.67511)
			(stroke
				(width 0.1524)
				(type default)
			)
			(layer "F.SilkS")
		)
		(fp_line
			(start 10.999978 -11.67511)
			(end -0.999998 -11.67511)
			(stroke
				(width 0.1524)
				(type default)
			)
			(layer "F.SilkS")
		)
		(fp_line
			(start -0.999998 15.375128)
			(end 10.999978 15.375128)
			(stroke
				(width 0.1524)
				(type default)
			)
			(layer "F.SilkS")
		)
		(fp_line
			(start -0.999998 -11.67511)
			(end -0.999998 15.375128)
			(stroke
				(width 0.1524)
				(type default)
			)
			(layer "F.SilkS")
		)
		(fp_line
			(start -3.999992 18.375122)
			(end 13.999972 18.375122)
			(stroke
				(width 0.1524)
				(type default)
			)
			(layer "F.SilkS")
		)
		(fp_line
			(start -3.999992 -14.675104)
			(end -3.999992 18.375122)
			(stroke
				(width 0.1524)
				(type default)
			)
			(layer "F.SilkS")
		)
		(fp_poly
			(pts
				(xy -2.261108 0.508) (xy -2.261108 -0.508) (xy -1.245108 0)
			)
			(stroke
				(width 0)
				(type default)
			)
			(fill yes)
			(layer "F.SilkS")
		)
		(fp_line
			(start 13.999972 18.375122)
			(end 13.999972 10.777728)
			(stroke
				(width 0.1524)
				(type default)
			)
			(layer "B.SilkS")
		)
		(fp_line
			(start 13.999972 6.891528)
			(end 13.999972 5.392928)
			(stroke
				(width 0.1524)
				(type default)
			)
			(layer "B.SilkS")
		)
		(fp_line
			(start 13.999972 3.513328)
			(end 13.999972 -14.675104)
			(stroke
				(width 0.1524)
				(type default)
			)
			(layer "B.SilkS")
		)
		(fp_line
			(start 13.999972 -14.675104)
			(end -3.999992 -14.675104)
			(stroke
				(width 0.1524)
				(type default)
			)
			(layer "B.SilkS")
		)
		(fp_line
			(start -3.999992 18.375122)
			(end 13.999972 18.375122)
			(stroke
				(width 0.1524)
				(type default)
			)
			(layer "B.SilkS")
		)
		(fp_line
			(start -3.999992 14.003528)
			(end -3.999992 18.375122)
			(stroke
				(width 0.1524)
				(type default)
			)
			(layer "B.SilkS")
		)
		(fp_line
			(start -3.999992 7.755128)
			(end -3.999992 9.050528)
			(stroke
				(width 0.1524)
				(type default)
			)
			(layer "B.SilkS")
		)
		(fp_line
			(start -3.999992 3.513328)
			(end -3.999992 4.275328)
			(stroke
				(width 0.1524)
				(type default)
			)
			(layer "B.SilkS")
		)
		(fp_line
			(start -3.999992 -14.675104)
			(end -3.999992 1.481328)
			(stroke
				(width 0.1524)
				(type default)
			)
			(layer "B.SilkS")
		)
		(fp_poly
			(pts
				(xy 9.49198 11.707876) (xy 9.49198 11.608054) (xy 10.50798 11.608054) (xy 10.50798 -0.608076) (xy 0.508 -0.608076)
				(xy 0.508 -0.508) (xy -0.508 -0.508) (xy -0.508 11.707876)
			)
			(stroke
				(width 0)
				(type default)
			)
			(fill no)
			(layer "B.CrtYd")
		)
		(fp_poly
			(pts
				(xy -0.999998 15.375128) (xy 10.999978 15.375128) (xy 10.999978 -11.67511) (xy -0.999998 -11.67511)
			)
			(stroke
				(width 0)
				(type default)
			)
			(fill no)
			(layer "F.CrtYd")
		)
		(fp_line
			(start 13.999972 18.375122)
			(end 13.999972 -14.675104)
			(stroke
				(width 0.1)
				(type default)
			)
			(layer "B.Fab")
		)
		(fp_line
			(start 13.999972 -14.675104)
			(end -3.999992 -14.675104)
			(stroke
				(width 0.1)
				(type default)
			)
			(layer "B.Fab")
		)
		(fp_line
			(start -3.999992 18.375122)
			(end 13.999972 18.375122)
			(stroke
				(width 0.1)
				(type default)
			)
			(layer "B.Fab")
		)
		(fp_line
			(start -3.999992 -14.675104)
			(end -3.999992 18.375122)
			(stroke
				(width 0.1)
				(type default)
			)
			(layer "B.Fab")
		)
		(fp_line
			(start 10.999978 15.375128)
			(end 10.999978 -11.67511)
			(stroke
				(width 0.1)
				(type default)
			)
			(layer "F.Fab")
		)
		(fp_line
			(start 10.999978 -11.67511)
			(end -0.999998 -11.67511)
			(stroke
				(width 0.1)
				(type default)
			)
			(layer "F.Fab")
		)
		(fp_line
			(start -0.999998 15.375128)
			(end 10.999978 15.375128)
			(stroke
				(width 0.1)
				(type default)
			)
			(layer "F.Fab")
		)
		(fp_line
			(start -0.999998 -11.67511)
			(end -0.999998 15.375128)
			(stroke
				(width 0.1)
				(type default)
			)
			(layer "F.Fab")
		)
		(fp_poly
			(pts
				(xy -2.261108 0.508) (xy -2.261108 -0.508) (xy -1.245108 0)
			)
			(stroke
				(width 0)
				(type default)
			)
			(fill yes)
			(layer "F.Fab")
		)
		(fp_text user "PRESS-FIT"
			(at 11.88085 -1.44653 90)
			(unlocked yes)
			(layer "F.SilkS")
			(effects
				(font
					(size 1.6002 1.1938)
					(thickness 0.1524)
				)
				(justify left)
			)
		)
		(fp_text user "6"
			(at 10.143744 16.133318 0)
			(unlocked yes)
			(layer "F.SilkS")
			(effects
				(font
					(size 0.7874 0.5842)
					(thickness 0.1524)
				)
			)
		)
		(fp_text user "5"
			(at 8.111744 16.082518 0)
			(unlocked yes)
			(layer "F.SilkS")
			(effects
				(font
					(size 0.7874 0.5842)
					(thickness 0.1524)
				)
			)
		)
		(fp_text user "4"
			(at 6.130544 16.184118 0)
			(unlocked yes)
			(layer "F.SilkS")
			(effects
				(font
					(size 0.7874 0.5842)
					(thickness 0.1524)
				)
			)
		)
		(fp_text user "3"
			(at 3.946144 16.082518 0)
			(unlocked yes)
			(layer "F.SilkS")
			(effects
				(font
					(size 0.7874 0.5842)
					(thickness 0.1524)
				)
			)
		)
		(fp_text user "2"
			(at 1.837944 16.133318 0)
			(unlocked yes)
			(layer "F.SilkS")
			(effects
				(font
					(size 0.7874 0.5842)
					(thickness 0.1524)
				)
			)
		)
		(fp_text user "1"
			(at -0.117856 16.158718 0)
			(unlocked yes)
			(layer "F.SilkS")
			(effects
				(font
					(size 0.7874 0.5842)
					(thickness 0.1524)
				)
			)
		)
		(fp_text user "I"
			(at -1.649222 11.210798 180)
			(unlocked yes)
			(layer "F.SilkS")
			(effects
				(font
					(size 0.7874 0.5842)
					(thickness 0.1524)
				)
			)
		)
		(fp_text user "H"
			(at -1.649222 9.81075 180)
			(unlocked yes)
			(layer "F.SilkS")
			(effects
				(font
					(size 0.7874 0.5842)
					(thickness 0.1524)
				)
			)
		)
		(fp_text user "F"
			(at -1.676654 6.924548 0)
			(unlocked yes)
			(layer "F.SilkS")
			(effects
				(font
					(size 0.7874 0.5842)
					(thickness 0.1524)
				)
			)
		)
		(fp_text user "A"
			(at -1.718056 -0.856996 0)
			(unlocked yes)
			(layer "F.SilkS")
			(effects
				(font
					(size 0.7874 0.5842)
					(thickness 0.1524)
				)
			)
		)
		(fp_text user "G"
			(at -1.752854 8.3693 0)
			(unlocked yes)
			(layer "F.SilkS")
			(effects
				(font
					(size 0.7874 0.5842)
					(thickness 0.1524)
				)
			)
		)
		(fp_text user "C"
			(at -1.752854 2.666492 0)
			(unlocked yes)
			(layer "F.SilkS")
			(effects
				(font
					(size 0.7874 0.5842)
					(thickness 0.1524)
				)
			)
		)
		(fp_text user "E"
			(at -1.778254 5.530596 0)
			(unlocked yes)
			(layer "F.SilkS")
			(effects
				(font
					(size 0.7874 0.5842)
					(thickness 0.1524)
				)
			)
		)
		(fp_text user "D"
			(at -1.829054 4.111244 0)
			(unlocked yes)
			(layer "F.SilkS")
			(effects
				(font
					(size 0.7874 0.5842)
					(thickness 0.1524)
				)
			)
		)
		(fp_text user "B"
			(at -1.854454 1.29794 0)
			(unlocked yes)
			(layer "F.SilkS")
			(effects
				(font
					(size 0.7874 0.5842)
					(thickness 0.1524)
				)
			)
		)
		(fp_text user "6"
			(at 9.99998 -1.666748 180)
			(unlocked yes)
			(layer "B.SilkS")
			(effects
				(font
					(size 0.7874 0.5842)
					(thickness 0.000001)
				)
				(justify mirror)
			)
		)
		(fp_text user "5"
			(at 7.96798 -1.615948 180)
			(unlocked yes)
			(layer "B.SilkS")
			(effects
				(font
					(size 0.7874 0.5842)
					(thickness 0.000001)
				)
				(justify mirror)
			)
		)
		(fp_text user "4"
			(at 5.88518 -1.615948 180)
			(unlocked yes)
			(layer "B.SilkS")
			(effects
				(font
					(size 0.7874 0.5842)
					(thickness 0.000001)
				)
				(justify mirror)
			)
		)
		(fp_text user "3"
			(at 3.90398 -1.615948 180)
			(unlocked yes)
			(layer "B.SilkS")
			(effects
				(font
					(size 0.7874 0.5842)
					(thickness 0.000001)
				)
				(justify mirror)
			)
		)
		(fp_text user "2"
			(at 1.97358 -1.615948 180)
			(unlocked yes)
			(layer "B.SilkS")
			(effects
				(font
					(size 0.7874 0.5842)
					(thickness 0.000001)
				)
				(justify mirror)
			)
		)
		(fp_text user "1"
			(at -0.00762 -1.615948 180)
			(unlocked yes)
			(layer "B.SilkS")
			(effects
				(font
					(size 0.7874 0.5842)
					(thickness 0.000001)
				)
				(justify mirror)
			)
		)
		(fp_text user "C"
			(at -0.863854 2.056892 0)
			(unlocked yes)
			(layer "B.SilkS")
			(effects
				(font
					(size 0.7874 0.5842)
					(thickness 0.1524)
				)
				(justify mirror)
			)
		)
		(fp_text user "F"
			(at -1.270254 6.822948 0)
			(unlocked yes)
			(layer "B.SilkS")
			(effects
				(font
					(size 0.7874 0.5842)
					(thickness 0.1524)
				)
				(justify mirror)
			)
		)
		(fp_text user "E"
			(at -1.270254 5.835396 0)
			(unlocked yes)
			(layer "B.SilkS")
			(effects
				(font
					(size 0.7874 0.5842)
					(thickness 0.1524)
				)
				(justify mirror)
			)
		)
		(fp_text user "G"
			(at -1.346454 7.8105 0)
			(unlocked yes)
			(layer "B.SilkS")
			(effects
				(font
					(size 0.7874 0.5842)
					(thickness 0.1524)
				)
				(justify mirror)
			)
		)
		(fp_text user "B"
			(at -1.498854 1.29794 0)
			(unlocked yes)
			(layer "B.SilkS")
			(effects
				(font
					(size 0.7874 0.5842)
					(thickness 0.1524)
				)
				(justify mirror)
			)
		)
		(fp_text user "I"
			(at -1.522222 11.591798 180)
			(unlocked yes)
			(layer "B.SilkS")
			(effects
				(font
					(size 0.7874 0.5842)
					(thickness 0.1524)
				)
				(justify mirror)
			)
		)
		(fp_text user "H"
			(at -1.522222 10.19175 180)
			(unlocked yes)
			(layer "B.SilkS")
			(effects
				(font
					(size 0.7874 0.5842)
					(thickness 0.1524)
				)
				(justify mirror)
			)
		)
		(fp_text user "A"
			(at -1.692656 -0.120396 0)
			(unlocked yes)
			(layer "B.SilkS")
			(effects
				(font
					(size 0.7874 0.5842)
					(thickness 0.1524)
				)
				(justify mirror)
			)
		)
		(fp_text user "PRESS-FIT"
			(at -1.975866 16.891 0)
			(unlocked yes)
			(layer "B.SilkS")
			(effects
				(font
					(size 1.6002 1.1938)
					(thickness 0.1524)
				)
				(justify left mirror)
			)
		)
		(fp_text user "D"
			(at -2.159254 4.136644 0)
			(unlocked yes)
			(layer "B.SilkS")
			(effects
				(font
					(size 0.7874 0.5842)
					(thickness 0.1524)
				)
				(justify mirror)
			)
		)
		(fp_text user "PRESS-FIT"
			(at 12.75969 -0.0381 270)
			(unlocked yes)
			(layer "B.Fab")
			(effects
				(font
					(size 1.6002 1.1938)
					(thickness 0.000001)
				)
				(justify left mirror)
			)
		)
		(fp_text user "6"
			(at 9.99998 -1.666748 180)
			(unlocked yes)
			(layer "B.Fab")
			(effects
				(font
					(size 0.7874 0.5842)
					(thickness 0.000001)
				)
				(justify mirror)
			)
		)
		(fp_text user "5"
			(at 7.96798 -1.615948 180)
			(unlocked yes)
			(layer "B.Fab")
			(effects
				(font
					(size 0.7874 0.5842)
					(thickness 0.000001)
				)
				(justify mirror)
			)
		)
		(fp_text user "4"
			(at 5.88518 -1.615948 180)
			(unlocked yes)
			(layer "B.Fab")
			(effects
				(font
					(size 0.7874 0.5842)
					(thickness 0.000001)
				)
				(justify mirror)
			)
		)
		(fp_text user "3"
			(at 3.90398 -1.615948 180)
			(unlocked yes)
			(layer "B.Fab")
			(effects
				(font
					(size 0.7874 0.5842)
					(thickness 0.000001)
				)
				(justify mirror)
			)
		)
		(fp_text user "2"
			(at 1.97358 -1.615948 180)
			(unlocked yes)
			(layer "B.Fab")
			(effects
				(font
					(size 0.7874 0.5842)
					(thickness 0.000001)
				)
				(justify mirror)
			)
		)
		(fp_text user "1"
			(at -0.00762 -1.615948 180)
			(unlocked yes)
			(layer "B.Fab")
			(effects
				(font
					(size 0.7874 0.5842)
					(thickness 0.000001)
				)
				(justify mirror)
			)
		)
		(fp_text user "A"
			(at -1.50622 -0.041148 180)
			(unlocked yes)
			(layer "B.Fab")
			(effects
				(font
					(size 0.7874 0.5842)
					(thickness 0.000001)
				)
				(justify mirror)
			)
		)
		(fp_text user "I"
			(at -1.522222 11.210798 180)
			(unlocked yes)
			(layer "B.Fab")
			(effects
				(font
					(size 0.7874 0.5842)
					(thickness 0.000001)
				)
				(justify mirror)
			)
		)
		(fp_text user "H"
			(at -1.522222 9.81075 180)
			(unlocked yes)
			(layer "B.Fab")
			(effects
				(font
					(size 0.7874 0.5842)
					(thickness 0.000001)
				)
				(justify mirror)
			)
		)
		(fp_text user "G"
			(at -1.522222 8.410956 180)
			(unlocked yes)
			(layer "B.Fab")
			(effects
				(font
					(size 0.7874 0.5842)
					(thickness 0.000001)
				)
				(justify mirror)
			)
		)
		(fp_text user "F"
			(at -1.522222 7.010908 180)
			(unlocked yes)
			(layer "B.Fab")
			(effects
				(font
					(size 0.7874 0.5842)
					(thickness 0.000001)
				)
				(justify mirror)
			)
		)
		(fp_text user "E"
			(at -1.522222 5.61086 180)
			(unlocked yes)
			(layer "B.Fab")
			(effects
				(font
					(size 0.7874 0.5842)
					(thickness 0.000001)
				)
				(justify mirror)
			)
		)
		(fp_text user "D"
			(at -1.522222 4.210812 180)
			(unlocked yes)
			(layer "B.Fab")
			(effects
				(font
					(size 0.7874 0.5842)
					(thickness 0.000001)
				)
				(justify mirror)
			)
		)
		(fp_text user "C"
			(at -1.522222 2.810764 180)
			(unlocked yes)
			(layer "B.Fab")
			(effects
				(font
					(size 0.7874 0.5842)
					(thickness 0.000001)
				)
				(justify mirror)
			)
		)
		(fp_text user "B"
			(at -1.522222 1.410716 180)
			(unlocked yes)
			(layer "B.Fab")
			(effects
				(font
					(size 0.7874 0.5842)
					(thickness 0.000001)
				)
				(justify mirror)
			)
		)
		(fp_text user "PRESS-FIT"
			(at 12.758674 14.569186 270)
			(unlocked yes)
			(layer "F.Fab")
			(effects
				(font
					(size 1.6002 1.1938)
					(thickness 0.000001)
				)
				(justify left)
			)
		)
		(fp_text user "6"
			(at 10.12698 16.013938 180)
			(unlocked yes)
			(layer "F.Fab")
			(effects
				(font
					(size 0.7874 0.5842)
					(thickness 0.000001)
				)
			)
		)
		(fp_text user "5"
			(at 8.09498 16.064738 180)
			(unlocked yes)
			(layer "F.Fab")
			(effects
				(font
					(size 0.7874 0.5842)
					(thickness 0.000001)
				)
			)
		)
		(fp_text user "4"
			(at 6.01218 16.064738 180)
			(unlocked yes)
			(layer "F.Fab")
			(effects
				(font
					(size 0.7874 0.5842)
					(thickness 0.000001)
				)
			)
		)
		(fp_text user "3"
			(at 4.03098 16.064738 180)
			(unlocked yes)
			(layer "F.Fab")
			(effects
				(font
					(size 0.7874 0.5842)
					(thickness 0.000001)
				)
			)
		)
		(fp_text user "2"
			(at 2.10058 16.064738 180)
			(unlocked yes)
			(layer "F.Fab")
			(effects
				(font
					(size 0.7874 0.5842)
					(thickness 0.000001)
				)
			)
		)
		(fp_text user "1"
			(at 0.11938 16.064738 180)
			(unlocked yes)
			(layer "F.Fab")
			(effects
				(font
					(size 0.7874 0.5842)
					(thickness 0.000001)
				)
			)
		)
		(fp_text user "I"
			(at -1.649222 11.210798 180)
			(unlocked yes)
			(layer "F.Fab")
			(effects
				(font
					(size 0.7874 0.5842)
					(thickness 0.000001)
				)
			)
		)
		(fp_text user "H"
			(at -1.649222 9.81075 180)
			(unlocked yes)
			(layer "F.Fab")
			(effects
				(font
					(size 0.7874 0.5842)
					(thickness 0.000001)
				)
			)
		)
		(fp_text user "G"
			(at -1.649222 8.410956 180)
			(unlocked yes)
			(layer "F.Fab")
			(effects
				(font
					(size 0.7874 0.5842)
					(thickness 0.000001)
				)
			)
		)
		(fp_text user "F"
			(at -1.649222 7.010908 180)
			(unlocked yes)
			(layer "F.Fab")
			(effects
				(font
					(size 0.7874 0.5842)
					(thickness 0.000001)
				)
			)
		)
		(fp_text user "E"
			(at -1.649222 5.61086 180)
			(unlocked yes)
			(layer "F.Fab")
			(effects
				(font
					(size 0.7874 0.5842)
					(thickness 0.000001)
				)
			)
		)
		(fp_text user "D"
			(at -1.649222 4.210812 180)
			(unlocked yes)
			(layer "F.Fab")
			(effects
				(font
					(size 0.7874 0.5842)
					(thickness 0.000001)
				)
			)
		)
		(fp_text user "C"
			(at -1.649222 2.810764 180)
			(unlocked yes)
			(layer "F.Fab")
			(effects
				(font
					(size 0.7874 0.5842)
					(thickness 0.000001)
				)
			)
		)
		(fp_text user "B"
			(at -1.649222 1.410716 180)
			(unlocked yes)
			(layer "F.Fab")
			(effects
				(font
					(size 0.7874 0.5842)
					(thickness 0.000001)
				)
			)
		)
		(fp_text user "A"
			(at -1.68402 -0.803148 180)
			(unlocked yes)
			(layer "F.Fab")
			(effects
				(font
					(size 0.7874 0.5842)
					(thickness 0.000001)
				)
			)
		)
		(pad "A1" thru_hole rect
			(at 0 0)
			(size 0.9144 0.9144)
			(drill 0.508)
			(layers "*.Cu" "*.Mask")
			(remove_unused_layers no)
			(net "ENET1G_3_MDI0P")
			(clearance 0.0508)
			(thermal_gap 0.0508)
			(padstack
				(mode front_inner_back)
				(layer "Inner"
					(shape circle)
					(size 0.9144 0.9144)
					(clearance 0.0508)
				)
				(layer "B.Cu"
					(shape rect)
					(size 0.9144 0.9144)
					(clearance 0.0508)
				)
			)
		)
		(pad "A2" thru_hole circle
			(at 1.999996 -0.100076)
			(size 0.9144 0.9144)
			(drill 0.508)
			(layers "*.Cu" "*.Mask")
			(remove_unused_layers no)
			(net "GND")
			(clearance 0.0508)
			(thermal_gap 0.0508)
		)
		(pad "A3" thru_hole circle
			(at 3.999992 0)
			(size 0.9144 0.9144)
			(drill 0.508)
			(layers "*.Cu" "*.Mask")
			(remove_unused_layers no)
			(net "ENET1G_3_MDI3P")
			(clearance 0.0508)
			(thermal_gap 0.0508)
		)
		(pad "A4" thru_hole circle
			(at 5.999988 -0.100076)
			(size 0.9144 0.9144)
			(drill 0.508)
			(layers "*.Cu" "*.Mask")
			(remove_unused_layers no)
			(net "GND")
			(clearance 0.0508)
			(thermal_gap 0.0508)
		)
		(pad "A5" thru_hole circle
			(at 7.999984 0)
			(size 0.9144 0.9144)
			(drill 0.508)
			(layers "*.Cu" "*.Mask")
			(remove_unused_layers no)
			(net "ENET1G_4_MDI1P")
			(clearance 0.0508)
			(thermal_gap 0.0508)
		)
		(pad "A6" thru_hole circle
			(at 9.99998 -0.100076)
			(size 0.9144 0.9144)
			(drill 0.508)
			(layers "*.Cu" "*.Mask")
			(remove_unused_layers no)
			(net "GND")
			(clearance 0.0508)
			(thermal_gap 0.0508)
		)
		(pad "B1" thru_hole circle
			(at 0 1.400048)
			(size 0.9144 0.9144)
			(drill 0.508)
			(layers "*.Cu" "*.Mask")
			(remove_unused_layers no)
			(net "ENET1G_3_MDI0N")
			(clearance 0.0508)
			(thermal_gap 0.0508)
		)
		(pad "B2" thru_hole circle
			(at 1.999996 1.299972)
			(size 0.9144 0.9144)
			(drill 0.508)
			(layers "*.Cu" "*.Mask")
			(remove_unused_layers no)
			(net "ENET1G_3_MDI2P")
			(clearance 0.0508)
			(thermal_gap 0.0508)
		)
		(pad "B3" thru_hole circle
			(at 3.999992 1.400048)
			(size 0.9144 0.9144)
			(drill 0.508)
			(layers "*.Cu" "*.Mask")
			(remove_unused_layers no)
			(net "ENET1G_3_MDI3N")
			(clearance 0.0508)
			(thermal_gap 0.0508)
		)
		(pad "B4" thru_hole circle
			(at 5.999988 1.299972)
			(size 0.9144 0.9144)
			(drill 0.508)
			(layers "*.Cu" "*.Mask")
			(remove_unused_layers no)
			(net "ENET1G_4_MDI0P")
			(clearance 0.0508)
			(thermal_gap 0.0508)
		)
		(pad "B5" thru_hole circle
			(at 7.999984 1.400048)
			(size 0.9144 0.9144)
			(drill 0.508)
			(layers "*.Cu" "*.Mask")
			(remove_unused_layers no)
			(net "ENET1G_4_MDI1N")
			(clearance 0.0508)
			(thermal_gap 0.0508)
		)
		(pad "B6" thru_hole circle
			(at 9.99998 1.299972)
			(size 0.9144 0.9144)
			(drill 0.508)
			(layers "*.Cu" "*.Mask")
			(remove_unused_layers no)
			(net "ENET1G_4_MDI3P")
			(clearance 0.0508)
			(thermal_gap 0.0508)
		)
		(pad "C1" thru_hole circle
			(at 0 2.800096)
			(size 0.9144 0.9144)
			(drill 0.508)
			(layers "*.Cu" "*.Mask")
			(remove_unused_layers no)
			(net "GND")
			(clearance 0.0508)
			(thermal_gap 0.0508)
		)
		(pad "C2" thru_hole circle
			(at 1.999996 2.70002)
			(size 0.9144 0.9144)
			(drill 0.508)
			(layers "*.Cu" "*.Mask")
			(remove_unused_layers no)
			(net "ENET1G_3_MDI2N")
			(clearance 0.0508)
			(thermal_gap 0.0508)
		)
		(pad "C3" thru_hole circle
			(at 3.999992 2.800096)
			(size 0.9144 0.9144)
			(drill 0.508)
			(layers "*.Cu" "*.Mask")
			(remove_unused_layers no)
			(net "GND")
			(clearance 0.0508)
			(thermal_gap 0.0508)
		)
		(pad "C4" thru_hole circle
			(at 5.999988 2.70002)
			(size 0.9144 0.9144)
			(drill 0.508)
			(layers "*.Cu" "*.Mask")
			(remove_unused_layers no)
			(net "ENET1G_4_MDI0N")
			(clearance 0.0508)
			(thermal_gap 0.0508)
		)
		(pad "C5" thru_hole circle
			(at 7.999984 2.800096)
			(size 0.9144 0.9144)
			(drill 0.508)
			(layers "*.Cu" "*.Mask")
			(remove_unused_layers no)
			(net "GND")
			(clearance 0.0508)
			(thermal_gap 0.0508)
		)
		(pad "C6" thru_hole circle
			(at 9.99998 2.70002)
			(size 0.9144 0.9144)
			(drill 0.508)
			(layers "*.Cu" "*.Mask")
			(remove_unused_layers no)
			(net "ENET1G_4_MDI3N")
			(clearance 0.0508)
			(thermal_gap 0.0508)
		)
		(pad "D1" thru_hole circle
			(at 0 4.19989)
			(size 0.9144 0.9144)
			(drill 0.508)
			(layers "*.Cu" "*.Mask")
			(remove_unused_layers no)
			(net "ENET10G_3_RDP")
			(clearance 0.0508)
			(thermal_gap 0.0508)
		)
		(pad "D2" thru_hole circle
			(at 1.999996 4.100068)
			(size 0.9144 0.9144)
			(drill 0.508)
			(layers "*.Cu" "*.Mask")
			(remove_unused_layers no)
			(net "GND")
			(clearance 0.0508)
			(thermal_gap 0.0508)
		)
		(pad "D3" thru_hole circle
			(at 3.999992 4.19989)
			(size 0.9144 0.9144)
			(drill 0.508)
			(layers "*.Cu" "*.Mask")
			(remove_unused_layers no)
			(net "ENET10G_3_SDA")
			(clearance 0.0508)
			(thermal_gap 0.0508)
		)
		(pad "D4" thru_hole circle
			(at 5.999988 4.100068)
			(size 0.9144 0.9144)
			(drill 0.508)
			(layers "*.Cu" "*.Mask")
			(remove_unused_layers no)
			(net "GND")
			(clearance 0.0508)
			(thermal_gap 0.0508)
		)
		(pad "D5" thru_hole circle
			(at 7.999984 4.19989)
			(size 0.9144 0.9144)
			(drill 0.508)
			(layers "*.Cu" "*.Mask")
			(remove_unused_layers no)
			(net "ENET1G_4_MDI2P")
			(clearance 0.0508)
			(thermal_gap 0.0508)
		)
		(pad "D6" thru_hole circle
			(at 9.99998 4.100068)
			(size 0.9144 0.9144)
			(drill 0.508)
			(layers "*.Cu" "*.Mask")
			(remove_unused_layers no)
			(net "GND")
			(clearance 0.0508)
			(thermal_gap 0.0508)
		)
		(pad "E1" thru_hole circle
			(at 0 5.599938)
			(size 0.9144 0.9144)
			(drill 0.508)
			(layers "*.Cu" "*.Mask")
			(remove_unused_layers no)
			(net "ENET10G_3_RDN")
			(clearance 0.0508)
			(thermal_gap 0.0508)
		)
		(pad "E2" thru_hole circle
			(at 1.999996 5.500116)
			(size 0.9144 0.9144)
			(drill 0.508)
			(layers "*.Cu" "*.Mask")
			(remove_unused_layers no)
			(net "ENET1G_3_MDI1P")
			(clearance 0.0508)
			(thermal_gap 0.0508)
		)
		(pad "E3" thru_hole circle
			(at 3.999992 5.599938)
			(size 0.9144 0.9144)
			(drill 0.508)
			(layers "*.Cu" "*.Mask")
			(remove_unused_layers no)
			(net "ENET10G_3_SCL")
			(clearance 0.0508)
			(thermal_gap 0.0508)
		)
		(pad "E4" thru_hole circle
			(at 5.999988 5.500116)
			(size 0.9144 0.9144)
			(drill 0.508)
			(layers "*.Cu" "*.Mask")
			(remove_unused_layers no)
			(net "ENET10G_4_SDA")
			(clearance 0.0508)
			(thermal_gap 0.0508)
		)
		(pad "E5" thru_hole circle
			(at 7.999984 5.599938)
			(size 0.9144 0.9144)
			(drill 0.508)
			(layers "*.Cu" "*.Mask")
			(remove_unused_layers no)
			(net "ENET1G_4_MDI2N")
			(clearance 0.0508)
			(thermal_gap 0.0508)
		)
		(pad "E6" thru_hole circle
			(at 9.99998 5.500116)
			(size 0.9144 0.9144)
			(drill 0.508)
			(layers "*.Cu" "*.Mask")
			(remove_unused_layers no)
			(net "ENET10G_4_RDP")
			(clearance 0.0508)
			(thermal_gap 0.0508)
		)
		(pad "F1" thru_hole circle
			(at 0 6.999986)
			(size 0.9144 0.9144)
			(drill 0.508)
			(layers "*.Cu" "*.Mask")
			(remove_unused_layers no)
			(net "GND")
			(clearance 0.0508)
			(thermal_gap 0.0508)
		)
		(pad "F2" thru_hole circle
			(at 1.999996 6.89991)
			(size 0.9144 0.9144)
			(drill 0.508)
			(layers "*.Cu" "*.Mask")
			(remove_unused_layers no)
			(net "ENET1G_3_MDI1N")
			(clearance 0.0508)
			(thermal_gap 0.0508)
		)
		(pad "F3" thru_hole circle
			(at 3.999992 6.999986)
			(size 0.9144 0.9144)
			(drill 0.508)
			(layers "*.Cu" "*.Mask")
			(remove_unused_layers no)
			(net "SKU_PIN_BLAD2_1")
			(clearance 0.0508)
			(thermal_gap 0.0508)
		)
		(pad "F4" thru_hole circle
			(at 5.999988 6.89991)
			(size 0.9144 0.9144)
			(drill 0.508)
			(layers "*.Cu" "*.Mask")
			(remove_unused_layers no)
			(net "ENET10G_4_SCL")
			(clearance 0.0508)
			(thermal_gap 0.0508)
		)
		(pad "F5" thru_hole circle
			(at 7.999984 6.999986)
			(size 0.9144 0.9144)
			(drill 0.508)
			(layers "*.Cu" "*.Mask")
			(remove_unused_layers no)
			(net "GND")
			(clearance 0.0508)
			(thermal_gap 0.0508)
		)
		(pad "F6" thru_hole circle
			(at 9.99998 6.89991)
			(size 0.9144 0.9144)
			(drill 0.508)
			(layers "*.Cu" "*.Mask")
			(remove_unused_layers no)
			(net "ENET10G_4_RDN")
			(clearance 0.0508)
			(thermal_gap 0.0508)
		)
		(pad "G1" thru_hole circle
			(at 0 8.400034)
			(size 0.9144 0.9144)
			(drill 0.508)
			(layers "*.Cu" "*.Mask")
			(remove_unused_layers no)
			(net "ENET10G_3_TDP")
			(clearance 0.0508)
			(thermal_gap 0.0508)
		)
		(pad "G2" thru_hole circle
			(at 1.999996 8.299958)
			(size 0.9144 0.9144)
			(drill 0.508)
			(layers "*.Cu" "*.Mask")
			(remove_unused_layers no)
			(net "GND")
			(clearance 0.0508)
			(thermal_gap 0.0508)
		)
		(pad "G3" thru_hole circle
			(at 3.999992 8.400034)
			(size 0.9144 0.9144)
			(drill 0.508)
			(layers "*.Cu" "*.Mask")
			(remove_unused_layers no)
			(net "NODE3_RXD")
			(clearance 0.0508)
			(thermal_gap 0.0508)
		)
		(pad "G4" thru_hole circle
			(at 5.999988 8.299958)
			(size 0.9144 0.9144)
			(drill 0.508)
			(layers "*.Cu" "*.Mask")
			(remove_unused_layers no)
			(net "NODE4_RXD")
			(clearance 0.0508)
			(thermal_gap 0.0508)
		)
		(pad "G5" thru_hole circle
			(at 7.999984 8.400034)
			(size 0.9144 0.9144)
			(drill 0.508)
			(layers "*.Cu" "*.Mask")
			(remove_unused_layers no)
			(net "NODE4_EN")
			(clearance 0.0508)
			(thermal_gap 0.0508)
		)
		(pad "G6" thru_hole circle
			(at 9.99998 8.299958)
			(size 0.9144 0.9144)
			(drill 0.508)
			(layers "*.Cu" "*.Mask")
			(remove_unused_layers no)
			(net "GND")
			(clearance 0.0508)
			(thermal_gap 0.0508)
		)
		(pad "H1" thru_hole circle
			(at 0 9.800082)
			(size 0.9144 0.9144)
			(drill 0.508)
			(layers "*.Cu" "*.Mask")
			(remove_unused_layers no)
			(net "ENET10G_3_TDN")
			(clearance 0.0508)
			(thermal_gap 0.0508)
		)
		(pad "H2" thru_hole circle
			(at 1.999996 9.700006)
			(size 0.9144 0.9144)
			(drill 0.508)
			(layers "*.Cu" "*.Mask")
			(remove_unused_layers no)
			(net "NODE3_EN")
			(clearance 0.0508)
			(thermal_gap 0.0508)
		)
		(pad "H3" thru_hole circle
			(at 3.999992 9.800082)
			(size 0.9144 0.9144)
			(drill 0.508)
			(layers "*.Cu" "*.Mask")
			(remove_unused_layers no)
			(net "NODE3_TXD")
			(clearance 0.0508)
			(thermal_gap 0.0508)
		)
		(pad "H4" thru_hole circle
			(at 5.999988 9.700006)
			(size 0.9144 0.9144)
			(drill 0.508)
			(layers "*.Cu" "*.Mask")
			(remove_unused_layers no)
			(net "NODE4_TXD")
			(clearance 0.0508)
			(thermal_gap 0.0508)
		)
		(pad "H5" thru_hole circle
			(at 7.999984 9.800082)
			(size 0.9144 0.9144)
			(drill 0.508)
			(layers "*.Cu" "*.Mask")
			(remove_unused_layers no)
			(net "SFP4_PRESENT_N")
			(clearance 0.0508)
			(thermal_gap 0.0508)
		)
		(pad "H6" thru_hole circle
			(at 9.99998 9.700006)
			(size 0.9144 0.9144)
			(drill 0.508)
			(layers "*.Cu" "*.Mask")
			(remove_unused_layers no)
			(net "ENET10G_4_TDP")
			(clearance 0.0508)
			(thermal_gap 0.0508)
		)
		(pad "I1" thru_hole circle
			(at 0 11.199876)
			(size 0.9144 0.9144)
			(drill 0.508)
			(layers "*.Cu" "*.Mask")
			(remove_unused_layers no)
			(net "GND")
			(clearance 0.0508)
			(thermal_gap 0.0508)
		)
		(pad "I2" thru_hole circle
			(at 1.999996 11.100054)
			(size 0.9144 0.9144)
			(drill 0.508)
			(layers "*.Cu" "*.Mask")
			(remove_unused_layers no)
			(net "SFP3_PRESENT_N")
			(clearance 0.0508)
			(thermal_gap 0.0508)
		)
		(pad "I3" thru_hole circle
			(at 3.999992 11.199876)
			(size 0.9144 0.9144)
			(drill 0.508)
			(layers "*.Cu" "*.Mask")
			(remove_unused_layers no)
			(net "P3V3_BLAD2")
			(clearance 0.0508)
			(thermal_gap 0.0508)
		)
		(pad "I4" thru_hole circle
			(at 5.999988 11.100054)
			(size 0.9144 0.9144)
			(drill 0.508)
			(layers "*.Cu" "*.Mask")
			(remove_unused_layers no)
			(net "SKU_PIN_BLAD2_2")
			(clearance 0.0508)
			(thermal_gap 0.0508)
		)
		(pad "I5" thru_hole circle
			(at 7.999984 11.199876)
			(size 0.9144 0.9144)
			(drill 0.508)
			(layers "*.Cu" "*.Mask")
			(remove_unused_layers no)
			(net "BLADE2_MATED_N")
			(clearance 0.0508)
			(thermal_gap 0.0508)
		)
		(pad "I6" thru_hole circle
			(at 9.99998 11.100054)
			(size 0.9144 0.9144)
			(drill 0.508)
			(layers "*.Cu" "*.Mask")
			(remove_unused_layers no)
			(net "ENET10G_4_TDN")
			(clearance 0.0508)
			(thermal_gap 0.0508)
		)
		(zone
			(layer "B.Cu")
			(hatch none 0.5)
			(connect_pads
				(clearance 0)
			)
			(min_thickness 0.25)
			(keepout
				(tracks allowed)
				(vias not_allowed)
				(pads allowed)
				(copperpour not_allowed)
				(footprints allowed)
			)
			(placement
				(enabled no)
				(sheetname "")
			)
			(fill
				(thermal_gap 0.5)
				(thermal_bridge_width 0.5)
				(island_removal_mode 0)
			)
			(polygon
				(pts
					(xy 340.038182 -13.807948) (xy 340.038182 -13.708126) (xy 339.022182 -13.708126) (xy 339.022182 -1.491996)
					(xy 349.022162 -1.491996) (xy 349.022162 -1.592072) (xy 350.038162 -1.592072) (xy 350.038162 -13.807948)
				)
			)
		)
	)
	(footprint ""
		(layer "F.Cu")
		(at 345.425268 -21.674582 90)
		(property "Reference" "R60"
			(at 3.336036 -56.962548 90)
			(unlocked yes)
			(layer "F.SilkS")
			(effects
				(font
					(size 0.7874 0.5842)
					(thickness 0.1524)
				)
				(justify left)
			)
		)
		(property "Value" ""
			(at 0 0 90)
			(layer "F.Fab")
			(effects
				(font
					(size 1.27 1.27)
				)
			)
		)
		(duplicate_pad_numbers_are_jumpers no)
		(fp_line
			(start 0.7874 -0.4064)
			(end 0.7874 0.4064)
			(stroke
				(width 0.1524)
				(type default)
			)
			(layer "F.SilkS")
		)
		(fp_line
			(start -0.7874 -0.4064)
			(end 0.7874 -0.4064)
			(stroke
				(width 0.1524)
				(type default)
			)
			(layer "F.SilkS")
		)
		(fp_line
			(start 0.7874 0.4064)
			(end -0.7874 0.4064)
			(stroke
				(width 0.1524)
				(type default)
			)
			(layer "F.SilkS")
		)
		(fp_line
			(start -0.7874 0.4064)
			(end -0.7874 -0.4064)
			(stroke
				(width 0.1524)
				(type default)
			)
			(layer "F.SilkS")
		)
		(fp_poly
			(pts
				(xy -0.508 0.2794) (xy -0.508 0.2286) (xy -0.635 0.2286) (xy -0.635 -0.254) (xy -0.5334 -0.254)
				(xy -0.5334 -0.2794) (xy 0.5334 -0.2794) (xy 0.5334 -0.254) (xy 0.635 -0.254) (xy 0.635 0.254) (xy 0.5334 0.254)
				(xy 0.5334 0.2794)
			)
			(stroke
				(width 0)
				(type default)
			)
			(fill no)
			(layer "F.CrtYd")
		)
		(pad "1" smd rect
			(at 0.40005 0 90)
			(size 0.4572 0.508)
			(layers "F.Cu" "F.Mask" "F.Paste")
			(net "GND")
		)
		(pad "2" smd rect
			(at -0.40005 0 90)
			(size 0.4572 0.508)
			(layers "F.Cu" "F.Mask" "F.Paste")
			(net "SKU_PIN_BLAD2_2")
		)
	)
	(footprint ""
		(layer "F.Cu")
		(at 412.494984 -28.4099 180)
		(property "Reference" "U2"
			(at -7.495032 -9.687052 0)
			(unlocked yes)
			(layer "F.SilkS")
			(effects
				(font
					(size 0.7874 0.5842)
					(thickness 0.1524)
				)
				(justify left)
			)
		)
		(property "Value" ""
			(at 0 0 180)
			(layer "F.Fab")
			(effects
				(font
					(size 1.27 1.27)
				)
			)
		)
		(duplicate_pad_numbers_are_jumpers no)
		(fp_line
			(start 6.949948 8.32993)
			(end 6.949948 5.7912)
			(stroke
				(width 0.1524)
				(type default)
			)
			(layer "F.SilkS")
		)
		(fp_line
			(start 6.949948 4.572)
			(end 6.949948 0)
			(stroke
				(width 0.1524)
				(type default)
			)
			(layer "F.SilkS")
		)
		(fp_line
			(start 6.949948 0)
			(end 6.949948 -3.670046)
			(stroke
				(width 0.1524)
				(type default)
			)
			(layer "F.SilkS")
		)
		(fp_line
			(start 6.949948 -3.670046)
			(end 0 -3.670046)
			(stroke
				(width 0.1524)
				(type default)
			)
			(layer "F.SilkS")
		)
		(fp_line
			(start 0 -3.670046)
			(end -6.949948 -3.670046)
			(stroke
				(width 0.1524)
				(type default)
			)
			(layer "F.SilkS")
		)
		(fp_line
			(start -6.949948 8.32993)
			(end 6.949948 8.32993)
			(stroke
				(width 0.1524)
				(type default)
			)
			(layer "F.SilkS")
		)
		(fp_line
			(start -6.949948 5.7912)
			(end -6.949948 8.32993)
			(stroke
				(width 0.1524)
				(type default)
			)
			(layer "F.SilkS")
		)
		(fp_line
			(start -6.949948 0)
			(end -6.949948 4.5466)
			(stroke
				(width 0.1524)
				(type default)
			)
			(layer "F.SilkS")
		)
		(fp_line
			(start -6.949948 -3.670046)
			(end -6.949948 0)
			(stroke
				(width 0.1524)
				(type default)
			)
			(layer "F.SilkS")
		)
		(fp_poly
			(pts
				(xy -12.923266 -1.944878) (xy -14.898878 -2.483612) (xy -13.462 -3.92049)
			)
			(stroke
				(width 0)
				(type default)
			)
			(fill yes)
			(layer "F.SilkS")
		)
		(fp_poly
			(pts
				(arc
					(start 4.933188 5.180076)
					(mid 7.066788 5.180076)
					(end 4.933188 5.180076)
				)
			)
			(stroke
				(width 0)
				(type default)
			)
			(fill no)
			(layer "B.CrtYd")
		)
		(fp_poly
			(pts
				(arc
					(start -7.06755 5.180076)
					(mid -4.932426 5.180076)
					(end -7.06755 5.180076)
				)
			)
			(stroke
				(width 0)
				(type default)
			)
			(fill no)
			(layer "B.CrtYd")
		)
		(fp_poly
			(pts
				(xy -6.949948 8.32993) (xy 6.949948 8.32993) (xy 6.949948 -3.670046) (xy -6.949948 -3.670046)
			)
			(stroke
				(width 0)
				(type default)
			)
			(fill no)
			(layer "F.CrtYd")
		)
		(fp_line
			(start 6.949948 8.32993)
			(end 6.949948 -3.670046)
			(stroke
				(width 0.1)
				(type default)
			)
			(layer "F.Fab")
		)
		(fp_line
			(start 6.949948 -3.670046)
			(end -6.949948 -3.670046)
			(stroke
				(width 0.1)
				(type default)
			)
			(layer "F.Fab")
		)
		(fp_line
			(start -6.700012 0)
			(end -6.949948 0)
			(stroke
				(width 0.1)
				(type default)
			)
			(layer "F.Fab")
		)
		(fp_line
			(start -6.949948 8.32993)
			(end 6.949948 8.32993)
			(stroke
				(width 0.1)
				(type default)
			)
			(layer "F.Fab")
		)
		(fp_line
			(start -6.949948 0)
			(end -6.949948 8.32993)
			(stroke
				(width 0.1)
				(type default)
			)
			(layer "F.Fab")
		)
		(fp_line
			(start -6.949948 -3.670046)
			(end -6.949948 0)
			(stroke
				(width 0.1)
				(type default)
			)
			(layer "F.Fab")
		)
		(fp_poly
			(pts
				(xy -6.9596 0) (xy -8.7376 1.016) (xy -8.7376 -1.016)
			)
			(stroke
				(width 0)
				(type default)
			)
			(fill yes)
			(layer "F.Fab")
		)
		(fp_text user "A13"
			(at 6.353302 -9.204452 0)
			(unlocked yes)
			(layer "F.SilkS")
			(effects
				(font
					(size 0.7874 0.5842)
					(thickness 0.1524)
				)
				(justify left)
			)
		)
		(fp_text user "B13"
			(at 6.353302 -10.225278 0)
			(unlocked yes)
			(layer "F.SilkS")
			(effects
				(font
					(size 0.7874 0.5842)
					(thickness 0.1524)
				)
				(justify left)
			)
		)
		(fp_text user "A1"
			(at -11.610848 -3.845052 0)
			(unlocked yes)
			(layer "F.SilkS")
			(effects
				(font
					(size 0.7874 0.5842)
					(thickness 0.1524)
				)
				(justify left)
			)
		)
		(fp_text user "B1"
			(at -11.763248 -6.288278 0)
			(unlocked yes)
			(layer "F.SilkS")
			(effects
				(font
					(size 0.7874 0.5842)
					(thickness 0.1524)
				)
				(justify left)
			)
		)
		(fp_text user "A13"
			(at 7.360666 -0.091948 180)
			(unlocked yes)
			(layer "F.Fab")
			(effects
				(font
					(size 0.7874 0.5842)
					(thickness 0.000001)
				)
				(justify left)
			)
		)
		(fp_text user "B13"
			(at 7.360666 -2.601722 180)
			(unlocked yes)
			(layer "F.Fab")
			(effects
				(font
					(size 0.7874 0.5842)
					(thickness 0.000001)
				)
				(justify left)
			)
		)
		(fp_text user "A1"
			(at -8.609584 1.330452 180)
			(unlocked yes)
			(layer "F.Fab")
			(effects
				(font
					(size 0.7874 0.5842)
					(thickness 0.000001)
				)
				(justify left)
			)
		)
		(fp_text user "B1"
			(at -8.685784 -2.601722 180)
			(unlocked yes)
			(layer "F.Fab")
			(effects
				(font
					(size 0.7874 0.5842)
					(thickness 0.000001)
				)
				(justify left)
			)
		)
		(pad "" np_thru_hole circle
			(at -5.999988 5.180076 180)
			(size 1.6002 1.6002)
			(drill 1.6002)
			(layers "*.Cu" "*.Mask")
			(clearance 0.381)
			(thermal_gap 0.381)
		)
		(pad "" np_thru_hole circle
			(at 5.999988 5.180076 180)
			(size 1.6002 1.6002)
			(drill 1.6002)
			(layers "*.Cu" "*.Mask")
			(clearance 0.381)
			(thermal_gap 0.381)
		)
		(pad "A1" smd rect
			(at -4.59994 0 180)
			(size 0.381 1.8542)
			(layers "F.Cu" "F.Mask" "F.Paste")
			(net "GND")
		)
		(pad "A2" smd rect
			(at -3.800094 0 180)
			(size 0.381 1.8542)
			(layers "F.Cu" "F.Mask" "F.Paste")
			(net "SAS_BLAD2_RX1_P")
		)
		(pad "A3" smd rect
			(at -2.999994 0 180)
			(size 0.381 1.8542)
			(layers "F.Cu" "F.Mask" "F.Paste")
			(net "SAS_BLAD2_RX1_N")
		)
		(pad "A4" smd rect
			(at -2.199894 0 180)
			(size 0.381 1.8542)
			(layers "F.Cu" "F.Mask" "F.Paste")
			(net "GND")
		)
		(pad "A5" smd rect
			(at -1.400048 0 180)
			(size 0.381 1.8542)
			(layers "F.Cu" "F.Mask" "F.Paste")
			(net "SAS_BLAD2_RX2_P")
		)
		(pad "A6" smd rect
			(at -0.599948 0 180)
			(size 0.381 1.8542)
			(layers "F.Cu" "F.Mask" "F.Paste")
			(net "SAS_BLAD2_RX2_N")
		)
		(pad "A7" smd rect
			(at 0.199898 0 180)
			(size 0.381 1.8542)
			(layers "F.Cu" "F.Mask" "F.Paste")
			(net "GND")
		)
		(pad "A8" smd rect
			(at 0.999998 0 180)
			(size 0.381 1.8542)
			(layers "F.Cu" "F.Mask" "F.Paste")
			(net "SAS_BLAD2_RX3_P")
		)
		(pad "A9" smd rect
			(at 1.800098 0 180)
			(size 0.381 1.8542)
			(layers "F.Cu" "F.Mask" "F.Paste")
			(net "SAS_BLAD2_RX3_N")
		)
		(pad "A10" smd rect
			(at 2.599944 0 180)
			(size 0.381 1.8542)
			(layers "F.Cu" "F.Mask" "F.Paste")
			(net "GND")
		)
		(pad "A11" smd rect
			(at 3.400044 0 180)
			(size 0.381 1.8542)
			(layers "F.Cu" "F.Mask" "F.Paste")
			(net "SAS_BLAD2_RX4_P")
		)
		(pad "A12" smd rect
			(at 4.19989 0 180)
			(size 0.381 1.8542)
			(layers "F.Cu" "F.Mask" "F.Paste")
			(net "SAS_BLAD2_RX4_N")
		)
		(pad "A13" smd rect
			(at 4.99999 0 180)
			(size 0.381 1.8542)
			(layers "F.Cu" "F.Mask" "F.Paste")
			(net "GND")
		)
		(pad "B1" smd rect
			(at -4.99999 -2.510028 180)
			(size 0.381 1.8542)
			(layers "F.Cu" "F.Mask" "F.Paste")
			(net "GND")
		)
		(pad "B2" smd rect
			(at -4.19989 -2.510028 180)
			(size 0.381 1.8542)
			(layers "F.Cu" "F.Mask" "F.Paste")
			(net "SAS_BLAD2_TX1_P")
		)
		(pad "B3" smd rect
			(at -3.400044 -2.510028 180)
			(size 0.381 1.8542)
			(layers "F.Cu" "F.Mask" "F.Paste")
			(net "SAS_BLAD2_TX1_N")
		)
		(pad "B4" smd rect
			(at -2.599944 -2.510028 180)
			(size 0.381 1.8542)
			(layers "F.Cu" "F.Mask" "F.Paste")
			(net "GND")
		)
		(pad "B5" smd rect
			(at -1.800098 -2.510028 180)
			(size 0.381 1.8542)
			(layers "F.Cu" "F.Mask" "F.Paste")
			(net "SAS_BLAD2_TX2_P")
		)
		(pad "B6" smd rect
			(at -0.999998 -2.510028 180)
			(size 0.381 1.8542)
			(layers "F.Cu" "F.Mask" "F.Paste")
			(net "SAS_BLAD2_TX2_N")
		)
		(pad "B7" smd rect
			(at -0.199898 -2.510028 180)
			(size 0.381 1.8542)
			(layers "F.Cu" "F.Mask" "F.Paste")
			(net "GND")
		)
		(pad "B8" smd rect
			(at 0.599948 -2.510028 180)
			(size 0.381 1.8542)
			(layers "F.Cu" "F.Mask" "F.Paste")
			(net "SAS_BLAD2_TX3_P")
		)
		(pad "B9" smd rect
			(at 1.400048 -2.510028 180)
			(size 0.381 1.8542)
			(layers "F.Cu" "F.Mask" "F.Paste")
			(net "SAS_BLAD2_TX3_N")
		)
		(pad "B10" smd rect
			(at 2.199894 -2.510028 180)
			(size 0.381 1.8542)
			(layers "F.Cu" "F.Mask" "F.Paste")
			(net "GND")
		)
		(pad "B11" smd rect
			(at 2.999994 -2.510028 180)
			(size 0.381 1.8542)
			(layers "F.Cu" "F.Mask" "F.Paste")
			(net "SAS_BLAD2_TX4_P")
		)
		(pad "B12" smd rect
			(at 3.800094 -2.510028 180)
			(size 0.381 1.8542)
			(layers "F.Cu" "F.Mask" "F.Paste")
			(net "SAS_BLAD2_TX4_N")
		)
		(pad "B13" smd rect
			(at 4.59994 -2.510028 180)
			(size 0.381 1.8542)
			(layers "F.Cu" "F.Mask" "F.Paste")
			(net "GND")
		)
		(zone
			(layer "F.Cu")
			(hatch none 0.5)
			(connect_pads
				(clearance 0)
			)
			(min_thickness 0.25)
			(keepout
				(tracks not_allowed)
				(vias allowed)
				(pads allowed)
				(copperpour not_allowed)
				(footprints allowed)
			)
			(placement
				(enabled no)
				(sheetname "")
			)
			(fill
				(thermal_gap 0.5)
				(thermal_bridge_width 0.5)
				(island_removal_mode 0)
			)
			(polygon
				(pts
					(xy 407.414984 -36.73983) (xy 405.575008 -36.73983) (xy 405.575008 -35.279838) (xy 407.414984 -35.279838)
				)
			)
		)
		(zone
			(layer "F.Cu")
			(hatch none 0.5)
			(connect_pads
				(clearance 0)
			)
			(min_thickness 0.25)
			(keepout
				(tracks not_allowed)
				(vias allowed)
				(pads allowed)
				(copperpour not_allowed)
				(footprints allowed)
			)
			(placement
				(enabled no)
				(sheetname "")
			)
			(fill
				(thermal_gap 0.5)
				(thermal_bridge_width 0.5)
				(island_removal_mode 0)
			)
			(polygon
				(pts
					(xy 419.41496 -36.73983) (xy 417.574984 -36.73983) (xy 417.574984 -35.279838) (xy 419.41496 -35.279838)
				)
			)
		)
		(zone
			(layers "F.Cu" "B.Cu" "In1.Cu" "In2.Cu" "In3.Cu" "In4.Cu" "In5.Cu" "In6.Cu")
			(hatch none 0.5)
			(connect_pads
				(clearance 0)
			)
			(min_thickness 0.25)
			(keepout
				(tracks not_allowed)
				(vias allowed)
				(pads allowed)
				(copperpour not_allowed)
				(footprints allowed)
			)
			(placement
				(enabled no)
				(sheetname "")
			)
			(fill
				(thermal_gap 0.5)
				(thermal_bridge_width 0.5)
				(island_removal_mode 0)
			)
			(polygon
				(pts
					(arc
						(start 407.713942 -33.589976)
						(mid 405.27605 -33.589976)
						(end 407.713942 -33.589976)
					)
				)
			)
		)
		(zone
			(layers "F.Cu" "B.Cu" "In1.Cu" "In2.Cu" "In3.Cu" "In4.Cu" "In5.Cu" "In6.Cu")
			(hatch none 0.5)
			(connect_pads
				(clearance 0)
			)
			(min_thickness 0.25)
			(keepout
				(tracks not_allowed)
				(vias allowed)
				(pads allowed)
				(copperpour not_allowed)
				(footprints allowed)
			)
			(placement
				(enabled no)
				(sheetname "")
			)
			(fill
				(thermal_gap 0.5)
				(thermal_bridge_width 0.5)
				(island_removal_mode 0)
			)
			(polygon
				(pts
					(arc
						(start 419.71468 -33.589976)
						(mid 417.275264 -33.589976)
						(end 419.71468 -33.589976)
					)
				)
			)
		)
	)
	(footprint ""
		(layer "F.Cu")
		(at 298.920154 -10.6299)
		(property "Reference" "J5"
			(at -5.4102 -11.267948 0)
			(unlocked yes)
			(layer "F.SilkS")
			(effects
				(font
					(size 0.7874 0.5842)
					(thickness 0.1524)
				)
				(justify left)
			)
		)
		(property "Value" ""
			(at 0 0 0)
			(layer "F.Fab")
			(effects
				(font
					(size 1.27 1.27)
				)
			)
		)
		(duplicate_pad_numbers_are_jumpers no)
		(fp_line
			(start -5.32511 -10.500106)
			(end -5.32511 0)
			(stroke
				(width 0.1524)
				(type default)
			)
			(layer "F.SilkS")
		)
		(fp_line
			(start -5.32511 0)
			(end -5.32511 43.029886)
			(stroke
				(width 0.1524)
				(type default)
			)
			(layer "F.SilkS")
		)
		(fp_line
			(start -5.32511 13.129768)
			(end 5.32511 13.129768)
			(stroke
				(width 0.1524)
				(type default)
			)
			(layer "F.SilkS")
		)
		(fp_line
			(start -5.32511 43.029886)
			(end 5.32511 43.029886)
			(stroke
				(width 0.1524)
				(type default)
			)
			(layer "F.SilkS")
		)
		(fp_line
			(start 5.32511 -10.500106)
			(end -5.32511 -10.500106)
			(stroke
				(width 0.1524)
				(type default)
			)
			(layer "F.SilkS")
		)
		(fp_line
			(start 5.32511 43.029886)
			(end 5.32511 -10.500106)
			(stroke
				(width 0.1524)
				(type default)
			)
			(layer "F.SilkS")
		)
		(fp_poly
			(pts
				(xy -7.86638 -0.8636) (xy -7.86638 0.9398) (xy -7.86638 0.951484) (xy -6.11378 0)
			)
			(stroke
				(width 0)
				(type default)
			)
			(fill yes)
			(layer "F.SilkS")
		)
		(fp_poly
			(pts
				(arc
					(start 2.758694 0)
					(mid -2.758694 0)
					(end 2.758694 0)
				)
			)
			(stroke
				(width 0)
				(type default)
			)
			(fill no)
			(layer "B.CrtYd")
		)
		(fp_poly
			(pts
				(arc
					(start 2.758694 5.62991)
					(mid -2.758694 5.62991)
					(end 2.758694 5.62991)
				)
			)
			(stroke
				(width 0)
				(type default)
			)
			(fill no)
			(layer "B.CrtYd")
		)
		(fp_poly
			(pts
				(arc
					(start 2.95275 -6.620002)
					(mid -2.95275 -6.620002)
					(end 2.95275 -6.620002)
				)
			)
			(stroke
				(width 0)
				(type default)
			)
			(fill no)
			(layer "B.CrtYd")
		)
		(fp_poly
			(pts
				(xy -5.32511 0) (xy -5.32511 43.029886) (xy 5.32511 43.029886) (xy 5.32511 -10.500106) (xy -5.32511 -10.500106)
			)
			(stroke
				(width 0)
				(type default)
			)
			(fill no)
			(layer "F.CrtYd")
		)
		(fp_line
			(start -5.32511 -10.500106)
			(end -5.32511 0)
			(stroke
				(width 0.1)
				(type default)
			)
			(layer "F.Fab")
		)
		(fp_line
			(start -5.32511 0)
			(end -5.32511 43.029886)
			(stroke
				(width 0.1)
				(type default)
			)
			(layer "F.Fab")
		)
		(fp_line
			(start -5.32511 13.129768)
			(end 5.32511 13.129768)
			(stroke
				(width 0.1)
				(type default)
			)
			(layer "F.Fab")
		)
		(fp_line
			(start -5.32511 43.029886)
			(end 5.32511 43.029886)
			(stroke
				(width 0.1)
				(type default)
			)
			(layer "F.Fab")
		)
		(fp_line
			(start 5.32511 -10.500106)
			(end -5.32511 -10.500106)
			(stroke
				(width 0.1)
				(type default)
			)
			(layer "F.Fab")
		)
		(fp_line
			(start 5.32511 43.029886)
			(end 5.32511 -10.500106)
			(stroke
				(width 0.1)
				(type default)
			)
			(layer "F.Fab")
		)
		(fp_poly
			(pts
				(xy -7.86638 -0.8636) (xy -7.86638 0.9398) (xy -7.86638 0.951484) (xy -6.11378 0)
			)
			(stroke
				(width 0)
				(type default)
			)
			(fill yes)
			(layer "F.Fab")
		)
		(fp_text user "1"
			(at -6.031484 -0.039116 0)
			(unlocked yes)
			(layer "F.SilkS")
			(effects
				(font
					(size 0.7874 0.5842)
					(thickness 0.1524)
				)
				(justify left)
			)
		)
		(fp_text user "1"
			(at -2.9464 0.043688 0)
			(unlocked yes)
			(layer "B.SilkS")
			(effects
				(font
					(size 0.7874 0.5842)
					(thickness 0.1524)
				)
				(justify left mirror)
			)
		)
		(fp_text user "1"
			(at -2.9464 0.043688 0)
			(unlocked yes)
			(layer "B.Fab")
			(effects
				(font
					(size 0.7874 0.5842)
					(thickness 0.000001)
				)
				(justify left mirror)
			)
		)
		(fp_text user "1"
			(at -6.031484 -0.039116 0)
			(unlocked yes)
			(layer "F.Fab")
			(effects
				(font
					(size 0.7874 0.5842)
					(thickness 0.000001)
				)
				(justify left)
			)
		)
		(pad "1" thru_hole circle
			(at 0 0)
			(size 5.4102 5.4102)
			(drill 4.0132)
			(layers "*.Cu" "*.Mask")
			(remove_unused_layers no)
			(net "GND")
			(clearance -0.4445)
		)
		(pad "2" thru_hole circle
			(at 0 5.62991)
			(size 5.4102 5.4102)
			(drill 4.0132)
			(layers "*.Cu" "*.Mask")
			(remove_unused_layers no)
			(net "GND")
			(clearance -0.4445)
		)
		(pad "3" thru_hole circle
			(at 0 -6.620002)
			(size 5.7912 5.7912)
			(drill 4.0132)
			(layers "*.Cu" "*.Mask")
			(remove_unused_layers no)
			(net "GND")
			(clearance -0.635)
		)
	)
	(footprint ""
		(layer "F.Cu")
		(at 155.459938 -10.6299)
		(property "Reference" "J12"
			(at -0.7112 -11.064748 0)
			(unlocked yes)
			(layer "F.SilkS")
			(effects
				(font
					(size 0.7874 0.5842)
					(thickness 0.1524)
				)
				(justify left)
			)
		)
		(property "Value" ""
			(at 0 0 0)
			(layer "F.Fab")
			(effects
				(font
					(size 1.27 1.27)
				)
			)
		)
		(duplicate_pad_numbers_are_jumpers no)
		(fp_line
			(start -5.32511 -10.500106)
			(end -5.32511 0)
			(stroke
				(width 0.1524)
				(type default)
			)
			(layer "F.SilkS")
		)
		(fp_line
			(start -5.32511 0)
			(end -5.32511 43.029886)
			(stroke
				(width 0.1524)
				(type default)
			)
			(layer "F.SilkS")
		)
		(fp_line
			(start -5.32511 13.129768)
			(end 5.32511 13.129768)
			(stroke
				(width 0.1524)
				(type default)
			)
			(layer "F.SilkS")
		)
		(fp_line
			(start -5.32511 43.029886)
			(end 5.32511 43.029886)
			(stroke
				(width 0.1524)
				(type default)
			)
			(layer "F.SilkS")
		)
		(fp_line
			(start 5.32511 -10.500106)
			(end -5.32511 -10.500106)
			(stroke
				(width 0.1524)
				(type default)
			)
			(layer "F.SilkS")
		)
		(fp_line
			(start 5.32511 43.029886)
			(end 5.32511 -10.500106)
			(stroke
				(width 0.1524)
				(type default)
			)
			(layer "F.SilkS")
		)
		(fp_poly
			(pts
				(xy -7.865364 4.480814) (xy -6.59003 5.755894) (xy -6.581902 5.764276) (xy -6.015228 3.852164)
			)
			(stroke
				(width 0)
				(type default)
			)
			(fill yes)
			(layer "F.SilkS")
		)
		(fp_poly
			(pts
				(arc
					(start 2.758694 0)
					(mid -2.758694 0)
					(end 2.758694 0)
				)
			)
			(stroke
				(width 0)
				(type default)
			)
			(fill no)
			(layer "B.CrtYd")
		)
		(fp_poly
			(pts
				(arc
					(start 2.758694 5.62991)
					(mid -2.758694 5.62991)
					(end 2.758694 5.62991)
				)
			)
			(stroke
				(width 0)
				(type default)
			)
			(fill no)
			(layer "B.CrtYd")
		)
		(fp_poly
			(pts
				(arc
					(start 2.95275 -6.620002)
					(mid -2.95275 -6.620002)
					(end 2.95275 -6.620002)
				)
			)
			(stroke
				(width 0)
				(type default)
			)
			(fill no)
			(layer "B.CrtYd")
		)
		(fp_poly
			(pts
				(xy -5.32511 0) (xy -5.32511 43.029886) (xy 5.32511 43.029886) (xy 5.32511 -10.500106) (xy -5.32511 -10.500106)
			)
			(stroke
				(width 0)
				(type default)
			)
			(fill no)
			(layer "F.CrtYd")
		)
		(fp_line
			(start -5.32511 -10.500106)
			(end -5.32511 0)
			(stroke
				(width 0.1)
				(type default)
			)
			(layer "F.Fab")
		)
		(fp_line
			(start -5.32511 0)
			(end -5.32511 43.029886)
			(stroke
				(width 0.1)
				(type default)
			)
			(layer "F.Fab")
		)
		(fp_line
			(start -5.32511 13.129768)
			(end 5.32511 13.129768)
			(stroke
				(width 0.1)
				(type default)
			)
			(layer "F.Fab")
		)
		(fp_line
			(start -5.32511 43.029886)
			(end 5.32511 43.029886)
			(stroke
				(width 0.1)
				(type default)
			)
			(layer "F.Fab")
		)
		(fp_line
			(start 5.32511 -10.500106)
			(end -5.32511 -10.500106)
			(stroke
				(width 0.1)
				(type default)
			)
			(layer "F.Fab")
		)
		(fp_line
			(start 5.32511 43.029886)
			(end 5.32511 -10.500106)
			(stroke
				(width 0.1)
				(type default)
			)
			(layer "F.Fab")
		)
		(fp_poly
			(pts
				(xy -7.86638 -0.8636) (xy -7.86638 0.9398) (xy -7.86638 0.951484) (xy -6.11378 0)
			)
			(stroke
				(width 0)
				(type default)
			)
			(fill yes)
			(layer "F.Fab")
		)
		(fp_text user "1"
			(at -6.082284 3.770884 0)
			(unlocked yes)
			(layer "F.SilkS")
			(effects
				(font
					(size 0.7874 0.5842)
					(thickness 0.1524)
				)
				(justify left)
			)
		)
		(fp_text user "1"
			(at -2.9464 0.043688 0)
			(unlocked yes)
			(layer "B.SilkS")
			(effects
				(font
					(size 0.7874 0.5842)
					(thickness 0.1524)
				)
				(justify left mirror)
			)
		)
		(fp_text user "1"
			(at -2.9464 0.043688 0)
			(unlocked yes)
			(layer "B.Fab")
			(effects
				(font
					(size 0.7874 0.5842)
					(thickness 0.000001)
				)
				(justify left mirror)
			)
		)
		(fp_text user "1"
			(at -6.031484 -0.039116 0)
			(unlocked yes)
			(layer "F.Fab")
			(effects
				(font
					(size 0.7874 0.5842)
					(thickness 0.000001)
				)
				(justify left)
			)
		)
		(pad "1" thru_hole circle
			(at 0 0)
			(size 5.4102 5.4102)
			(drill 4.0132)
			(layers "*.Cu" "*.Mask")
			(remove_unused_layers no)
			(net "GND")
			(clearance -0.4445)
		)
		(pad "2" thru_hole circle
			(at 0 5.62991)
			(size 5.4102 5.4102)
			(drill 4.0132)
			(layers "*.Cu" "*.Mask")
			(remove_unused_layers no)
			(net "GND")
			(clearance -0.4445)
		)
		(pad "3" thru_hole circle
			(at 0 -6.620002)
			(size 5.7912 5.7912)
			(drill 4.0132)
			(layers "*.Cu" "*.Mask")
			(remove_unused_layers no)
			(net "GND")
			(clearance -0.635)
		)
	)
	(footprint ""
		(layer "F.Cu")
		(at 29.707332 -19.7358 -90)
		(property "Reference" "R88"
			(at 0.9144 -4.907788 90)
			(unlocked yes)
			(layer "F.SilkS")
			(effects
				(font
					(size 0.7874 0.5842)
					(thickness 0.1524)
				)
				(justify left)
			)
		)
		(property "Value" ""
			(at 0 0 270)
			(layer "F.Fab")
			(effects
				(font
					(size 1.27 1.27)
				)
			)
		)
		(duplicate_pad_numbers_are_jumpers no)
		(fp_line
			(start -0.7874 0.4064)
			(end -0.7874 -0.4064)
			(stroke
				(width 0.1524)
				(type default)
			)
			(layer "F.SilkS")
		)
		(fp_line
			(start 0.7874 0.4064)
			(end -0.7874 0.4064)
			(stroke
				(width 0.1524)
				(type default)
			)
			(layer "F.SilkS")
		)
		(fp_line
			(start -0.7874 -0.4064)
			(end 0.7874 -0.4064)
			(stroke
				(width 0.1524)
				(type default)
			)
			(layer "F.SilkS")
		)
		(fp_line
			(start 0.7874 -0.4064)
			(end 0.7874 0.4064)
			(stroke
				(width 0.1524)
				(type default)
			)
			(layer "F.SilkS")
		)
		(fp_poly
			(pts
				(xy -0.508 0.2794) (xy -0.508 0.2286) (xy -0.635 0.2286) (xy -0.635 -0.254) (xy -0.5334 -0.254)
				(xy -0.5334 -0.2794) (xy 0.5334 -0.2794) (xy 0.5334 -0.254) (xy 0.635 -0.254) (xy 0.635 0.254) (xy 0.5334 0.254)
				(xy 0.5334 0.2794)
			)
			(stroke
				(width 0)
				(type default)
			)
			(fill no)
			(layer "F.CrtYd")
		)
		(pad "1" smd rect
			(at 0.40005 0 270)
			(size 0.4572 0.508)
			(layers "F.Cu" "F.Mask" "F.Paste")
			(net "N39395053")
		)
		(pad "2" smd rect
			(at -0.40005 0 270)
			(size 0.4572 0.508)
			(layers "F.Cu" "F.Mask" "F.Paste")
			(net "P12V")
		)
	)
	(footprint ""
		(layer "F.Cu")
		(at 119.433848 -21.147532 180)
		(property "Reference" "R69"
			(at 60.737496 -5.119116 0)
			(unlocked yes)
			(layer "F.SilkS")
			(effects
				(font
					(size 0.7874 0.5842)
					(thickness 0.1524)
				)
				(justify left)
			)
		)
		(property "Value" ""
			(at 0 0 180)
			(layer "F.Fab")
			(effects
				(font
					(size 1.27 1.27)
				)
			)
		)
		(duplicate_pad_numbers_are_jumpers no)
		(fp_line
			(start 0.7874 0.4064)
			(end -0.7874 0.4064)
			(stroke
				(width 0.1524)
				(type default)
			)
			(layer "F.SilkS")
		)
		(fp_line
			(start 0.7874 -0.4064)
			(end 0.7874 0.4064)
			(stroke
				(width 0.1524)
				(type default)
			)
			(layer "F.SilkS")
		)
		(fp_line
			(start -0.7874 0.4064)
			(end -0.7874 -0.4064)
			(stroke
				(width 0.1524)
				(type default)
			)
			(layer "F.SilkS")
		)
		(fp_line
			(start -0.7874 -0.4064)
			(end 0.7874 -0.4064)
			(stroke
				(width 0.1524)
				(type default)
			)
			(layer "F.SilkS")
		)
		(fp_poly
			(pts
				(xy -0.508 0.2794) (xy -0.508 0.2286) (xy -0.635 0.2286) (xy -0.635 -0.254) (xy -0.5334 -0.254)
				(xy -0.5334 -0.2794) (xy 0.5334 -0.2794) (xy 0.5334 -0.254) (xy 0.635 -0.254) (xy 0.635 0.254) (xy 0.5334 0.254)
				(xy 0.5334 0.2794)
			)
			(stroke
				(width 0)
				(type default)
			)
			(fill no)
			(layer "F.CrtYd")
		)
		(pad "1" smd rect
			(at 0.40005 0 180)
			(size 0.4572 0.508)
			(layers "F.Cu" "F.Mask" "F.Paste")
			(net "ENET10G_2_MOD_DEF0")
		)
		(pad "2" smd rect
			(at -0.40005 0 180)
			(size 0.4572 0.508)
			(layers "F.Cu" "F.Mask" "F.Paste")
			(net "SFP2_PRESENT_N")
		)
	)
	(footprint ""
		(layer "F.Cu")
		(at 393.484862 -28.4099 180)
		(property "Reference" "U4"
			(at -7.110476 -9.509252 0)
			(unlocked yes)
			(layer "F.SilkS")
			(effects
				(font
					(size 0.7874 0.5842)
					(thickness 0.1524)
				)
				(justify left)
			)
		)
		(property "Value" ""
			(at 0 0 180)
			(layer "F.Fab")
			(effects
				(font
					(size 1.27 1.27)
				)
			)
		)
		(duplicate_pad_numbers_are_jumpers no)
		(fp_line
			(start 6.949948 8.32993)
			(end 6.949948 5.7912)
			(stroke
				(width 0.1524)
				(type default)
			)
			(layer "F.SilkS")
		)
		(fp_line
			(start 6.949948 4.572)
			(end 6.949948 0)
			(stroke
				(width 0.1524)
				(type default)
			)
			(layer "F.SilkS")
		)
		(fp_line
			(start 6.949948 0)
			(end 6.949948 -3.670046)
			(stroke
				(width 0.1524)
				(type default)
			)
			(layer "F.SilkS")
		)
		(fp_line
			(start 6.949948 -3.670046)
			(end 0 -3.670046)
			(stroke
				(width 0.1524)
				(type default)
			)
			(layer "F.SilkS")
		)
		(fp_line
			(start 0 -3.670046)
			(end -6.949948 -3.670046)
			(stroke
				(width 0.1524)
				(type default)
			)
			(layer "F.SilkS")
		)
		(fp_line
			(start -6.949948 8.32993)
			(end 6.949948 8.32993)
			(stroke
				(width 0.1524)
				(type default)
			)
			(layer "F.SilkS")
		)
		(fp_line
			(start -6.949948 5.7912)
			(end -6.949948 8.32993)
			(stroke
				(width 0.1524)
				(type default)
			)
			(layer "F.SilkS")
		)
		(fp_line
			(start -6.949948 0)
			(end -6.949948 4.5466)
			(stroke
				(width 0.1524)
				(type default)
			)
			(layer "F.SilkS")
		)
		(fp_line
			(start -6.949948 -3.670046)
			(end -6.949948 0)
			(stroke
				(width 0.1524)
				(type default)
			)
			(layer "F.SilkS")
		)
		(fp_poly
			(pts
				(xy -6.9596 0) (xy -8.7376 1.016) (xy -8.7376 -1.016)
			)
			(stroke
				(width 0)
				(type default)
			)
			(fill yes)
			(layer "F.SilkS")
		)
		(fp_poly
			(pts
				(arc
					(start 4.933188 5.180076)
					(mid 7.066788 5.180076)
					(end 4.933188 5.180076)
				)
			)
			(stroke
				(width 0)
				(type default)
			)
			(fill no)
			(layer "B.CrtYd")
		)
		(fp_poly
			(pts
				(arc
					(start -7.06755 5.180076)
					(mid -4.932426 5.180076)
					(end -7.06755 5.180076)
				)
			)
			(stroke
				(width 0)
				(type default)
			)
			(fill no)
			(layer "B.CrtYd")
		)
		(fp_poly
			(pts
				(xy -6.949948 8.32993) (xy 6.949948 8.32993) (xy 6.949948 -3.670046) (xy -6.949948 -3.670046)
			)
			(stroke
				(width 0)
				(type default)
			)
			(fill no)
			(layer "F.CrtYd")
		)
		(fp_line
			(start 6.949948 8.32993)
			(end 6.949948 -3.670046)
			(stroke
				(width 0.1)
				(type default)
			)
			(layer "F.Fab")
		)
		(fp_line
			(start 6.949948 -3.670046)
			(end -6.949948 -3.670046)
			(stroke
				(width 0.1)
				(type default)
			)
			(layer "F.Fab")
		)
		(fp_line
			(start -6.700012 0)
			(end -6.949948 0)
			(stroke
				(width 0.1)
				(type default)
			)
			(layer "F.Fab")
		)
		(fp_line
			(start -6.949948 8.32993)
			(end 6.949948 8.32993)
			(stroke
				(width 0.1)
				(type default)
			)
			(layer "F.Fab")
		)
		(fp_line
			(start -6.949948 0)
			(end -6.949948 8.32993)
			(stroke
				(width 0.1)
				(type default)
			)
			(layer "F.Fab")
		)
		(fp_line
			(start -6.949948 -3.670046)
			(end -6.949948 0)
			(stroke
				(width 0.1)
				(type default)
			)
			(layer "F.Fab")
		)
		(fp_poly
			(pts
				(xy -6.9596 0) (xy -8.7376 1.016) (xy -8.7376 -1.016)
			)
			(stroke
				(width 0)
				(type default)
			)
			(fill yes)
			(layer "F.Fab")
		)
		(fp_text user "A13"
			(at 12.41171 0.603504 90)
			(unlocked yes)
			(layer "F.SilkS")
			(effects
				(font
					(size 0.7874 0.5842)
					(thickness 0.1524)
				)
				(justify left)
			)
		)
		(fp_text user "B13"
			(at 12.254484 -6.279896 90)
			(unlocked yes)
			(layer "F.SilkS")
			(effects
				(font
					(size 0.7874 0.5842)
					(thickness 0.1524)
				)
				(justify left)
			)
		)
		(fp_text user "A1"
			(at -8.787892 -9.229852 0)
			(unlocked yes)
			(layer "F.SilkS")
			(effects
				(font
					(size 0.7874 0.5842)
					(thickness 0.1524)
				)
				(justify left)
			)
		)
		(fp_text user "B1"
			(at -8.838692 -10.225278 0)
			(unlocked yes)
			(layer "F.SilkS")
			(effects
				(font
					(size 0.7874 0.5842)
					(thickness 0.1524)
				)
				(justify left)
			)
		)
		(fp_text user "A13"
			(at 7.360666 -0.091948 180)
			(unlocked yes)
			(layer "F.Fab")
			(effects
				(font
					(size 0.7874 0.5842)
					(thickness 0.000001)
				)
				(justify left)
			)
		)
		(fp_text user "B13"
			(at 7.360666 -2.601722 180)
			(unlocked yes)
			(layer "F.Fab")
			(effects
				(font
					(size 0.7874 0.5842)
					(thickness 0.000001)
				)
				(justify left)
			)
		)
		(fp_text user "A1"
			(at -8.609584 1.330452 180)
			(unlocked yes)
			(layer "F.Fab")
			(effects
				(font
					(size 0.7874 0.5842)
					(thickness 0.000001)
				)
				(justify left)
			)
		)
		(fp_text user "B1"
			(at -8.685784 -2.601722 180)
			(unlocked yes)
			(layer "F.Fab")
			(effects
				(font
					(size 0.7874 0.5842)
					(thickness 0.000001)
				)
				(justify left)
			)
		)
		(pad "" np_thru_hole circle
			(at -5.999988 5.180076 180)
			(size 1.6002 1.6002)
			(drill 1.6002)
			(layers "*.Cu" "*.Mask")
			(clearance 0.381)
			(thermal_gap 0.381)
		)
		(pad "" np_thru_hole circle
			(at 5.999988 5.180076 180)
			(size 1.6002 1.6002)
			(drill 1.6002)
			(layers "*.Cu" "*.Mask")
			(clearance 0.381)
			(thermal_gap 0.381)
		)
		(pad "A1" smd rect
			(at -4.59994 0 180)
			(size 0.381 1.8542)
			(layers "F.Cu" "F.Mask" "F.Paste")
			(net "GND")
		)
		(pad "A2" smd rect
			(at -3.800094 0 180)
			(size 0.381 1.8542)
			(layers "F.Cu" "F.Mask" "F.Paste")
			(net "SAS_BLAD2_RX5_P")
		)
		(pad "A3" smd rect
			(at -2.999994 0 180)
			(size 0.381 1.8542)
			(layers "F.Cu" "F.Mask" "F.Paste")
			(net "SAS_BLAD2_RX5_N")
		)
		(pad "A4" smd rect
			(at -2.199894 0 180)
			(size 0.381 1.8542)
			(layers "F.Cu" "F.Mask" "F.Paste")
			(net "GND")
		)
		(pad "A5" smd rect
			(at -1.400048 0 180)
			(size 0.381 1.8542)
			(layers "F.Cu" "F.Mask" "F.Paste")
			(net "SAS_BLAD2_RX6_P")
		)
		(pad "A6" smd rect
			(at -0.599948 0 180)
			(size 0.381 1.8542)
			(layers "F.Cu" "F.Mask" "F.Paste")
			(net "SAS_BLAD2_RX6_N")
		)
		(pad "A7" smd rect
			(at 0.199898 0 180)
			(size 0.381 1.8542)
			(layers "F.Cu" "F.Mask" "F.Paste")
			(net "GND")
		)
		(pad "A8" smd rect
			(at 0.999998 0 180)
			(size 0.381 1.8542)
			(layers "F.Cu" "F.Mask" "F.Paste")
			(net "SAS_BLAD2_RX7_P")
		)
		(pad "A9" smd rect
			(at 1.800098 0 180)
			(size 0.381 1.8542)
			(layers "F.Cu" "F.Mask" "F.Paste")
			(net "SAS_BLAD2_RX7_N")
		)
		(pad "A10" smd rect
			(at 2.599944 0 180)
			(size 0.381 1.8542)
			(layers "F.Cu" "F.Mask" "F.Paste")
			(net "GND")
		)
		(pad "A11" smd rect
			(at 3.400044 0 180)
			(size 0.381 1.8542)
			(layers "F.Cu" "F.Mask" "F.Paste")
			(net "SAS_BLAD2_RX8_P")
		)
		(pad "A12" smd rect
			(at 4.19989 0 180)
			(size 0.381 1.8542)
			(layers "F.Cu" "F.Mask" "F.Paste")
			(net "SAS_BLAD2_RX8_N")
		)
		(pad "A13" smd rect
			(at 4.99999 0 180)
			(size 0.381 1.8542)
			(layers "F.Cu" "F.Mask" "F.Paste")
			(net "GND")
		)
		(pad "B1" smd rect
			(at -4.99999 -2.510028 180)
			(size 0.381 1.8542)
			(layers "F.Cu" "F.Mask" "F.Paste")
			(net "GND")
		)
		(pad "B2" smd rect
			(at -4.19989 -2.510028 180)
			(size 0.381 1.8542)
			(layers "F.Cu" "F.Mask" "F.Paste")
			(net "SAS_BLAD2_TX5_P")
		)
		(pad "B3" smd rect
			(at -3.400044 -2.510028 180)
			(size 0.381 1.8542)
			(layers "F.Cu" "F.Mask" "F.Paste")
			(net "SAS_BLAD2_TX5_N")
		)
		(pad "B4" smd rect
			(at -2.599944 -2.510028 180)
			(size 0.381 1.8542)
			(layers "F.Cu" "F.Mask" "F.Paste")
			(net "GND")
		)
		(pad "B5" smd rect
			(at -1.800098 -2.510028 180)
			(size 0.381 1.8542)
			(layers "F.Cu" "F.Mask" "F.Paste")
			(net "SAS_BLAD2_TX6_P")
		)
		(pad "B6" smd rect
			(at -0.999998 -2.510028 180)
			(size 0.381 1.8542)
			(layers "F.Cu" "F.Mask" "F.Paste")
			(net "SAS_BLAD2_TX6_N")
		)
		(pad "B7" smd rect
			(at -0.199898 -2.510028 180)
			(size 0.381 1.8542)
			(layers "F.Cu" "F.Mask" "F.Paste")
			(net "GND")
		)
		(pad "B8" smd rect
			(at 0.599948 -2.510028 180)
			(size 0.381 1.8542)
			(layers "F.Cu" "F.Mask" "F.Paste")
			(net "SAS_BLAD2_TX7_P")
		)
		(pad "B9" smd rect
			(at 1.400048 -2.510028 180)
			(size 0.381 1.8542)
			(layers "F.Cu" "F.Mask" "F.Paste")
			(net "SAS_BLAD2_TX7_N")
		)
		(pad "B10" smd rect
			(at 2.199894 -2.510028 180)
			(size 0.381 1.8542)
			(layers "F.Cu" "F.Mask" "F.Paste")
			(net "GND")
		)
		(pad "B11" smd rect
			(at 2.999994 -2.510028 180)
			(size 0.381 1.8542)
			(layers "F.Cu" "F.Mask" "F.Paste")
			(net "SAS_BLAD2_TX8_P")
		)
		(pad "B12" smd rect
			(at 3.800094 -2.510028 180)
			(size 0.381 1.8542)
			(layers "F.Cu" "F.Mask" "F.Paste")
			(net "SAS_BLAD2_TX8_N")
		)
		(pad "B13" smd rect
			(at 4.59994 -2.510028 180)
			(size 0.381 1.8542)
			(layers "F.Cu" "F.Mask" "F.Paste")
			(net "GND")
		)
		(zone
			(layer "F.Cu")
			(hatch none 0.5)
			(connect_pads
				(clearance 0)
			)
			(min_thickness 0.25)
			(keepout
				(tracks not_allowed)
				(vias allowed)
				(pads allowed)
				(copperpour not_allowed)
				(footprints allowed)
			)
			(placement
				(enabled no)
				(sheetname "")
			)
			(fill
				(thermal_gap 0.5)
				(thermal_bridge_width 0.5)
				(island_removal_mode 0)
			)
			(polygon
				(pts
					(xy 388.404862 -36.73983) (xy 386.564886 -36.73983) (xy 386.564886 -35.279838) (xy 388.404862 -35.279838)
				)
			)
		)
		(zone
			(layer "F.Cu")
			(hatch none 0.5)
			(connect_pads
				(clearance 0)
			)
			(min_thickness 0.25)
			(keepout
				(tracks not_allowed)
				(vias allowed)
				(pads allowed)
				(copperpour not_allowed)
				(footprints allowed)
			)
			(placement
				(enabled no)
				(sheetname "")
			)
			(fill
				(thermal_gap 0.5)
				(thermal_bridge_width 0.5)
				(island_removal_mode 0)
			)
			(polygon
				(pts
					(xy 400.404838 -36.73983) (xy 398.564862 -36.73983) (xy 398.564862 -35.279838) (xy 400.404838 -35.279838)
				)
			)
		)
		(zone
			(layers "F.Cu" "B.Cu" "In1.Cu" "In2.Cu" "In3.Cu" "In4.Cu" "In5.Cu" "In6.Cu")
			(hatch none 0.5)
			(connect_pads
				(clearance 0)
			)
			(min_thickness 0.25)
			(keepout
				(tracks not_allowed)
				(vias allowed)
				(pads allowed)
				(copperpour not_allowed)
				(footprints allowed)
			)
			(placement
				(enabled no)
				(sheetname "")
			)
			(fill
				(thermal_gap 0.5)
				(thermal_bridge_width 0.5)
				(island_removal_mode 0)
			)
			(polygon
				(pts
					(arc
						(start 388.70382 -33.589976)
						(mid 386.265928 -33.589976)
						(end 388.70382 -33.589976)
					)
				)
			)
		)
		(zone
			(layers "F.Cu" "B.Cu" "In1.Cu" "In2.Cu" "In3.Cu" "In4.Cu" "In5.Cu" "In6.Cu")
			(hatch none 0.5)
			(connect_pads
				(clearance 0)
			)
			(min_thickness 0.25)
			(keepout
				(tracks not_allowed)
				(vias allowed)
				(pads allowed)
				(copperpour not_allowed)
				(footprints allowed)
			)
			(placement
				(enabled no)
				(sheetname "")
			)
			(fill
				(thermal_gap 0.5)
				(thermal_bridge_width 0.5)
				(island_removal_mode 0)
			)
			(polygon
				(pts
					(arc
						(start 400.704558 -33.589976)
						(mid 398.265142 -33.589976)
						(end 400.704558 -33.589976)
					)
				)
			)
		)
	)
	(footprint ""
		(layer "F.Cu")
		(at 117.31244 -23.27021)
		(property "Reference" "R6"
			(at -61.341 5.115052 0)
			(unlocked yes)
			(layer "F.SilkS")
			(effects
				(font
					(size 0.7874 0.5842)
					(thickness 0.1524)
				)
				(justify left)
			)
		)
		(property "Value" ""
			(at 0 0 0)
			(layer "F.Fab")
			(effects
				(font
					(size 1.27 1.27)
				)
			)
		)
		(duplicate_pad_numbers_are_jumpers no)
		(fp_line
			(start -0.7874 -0.4064)
			(end 0.7874 -0.4064)
			(stroke
				(width 0.1524)
				(type default)
			)
			(layer "F.SilkS")
		)
		(fp_line
			(start -0.7874 0.4064)
			(end -0.7874 -0.4064)
			(stroke
				(width 0.1524)
				(type default)
			)
			(layer "F.SilkS")
		)
		(fp_line
			(start 0.7874 -0.4064)
			(end 0.7874 0.4064)
			(stroke
				(width 0.1524)
				(type default)
			)
			(layer "F.SilkS")
		)
		(fp_line
			(start 0.7874 0.4064)
			(end -0.7874 0.4064)
			(stroke
				(width 0.1524)
				(type default)
			)
			(layer "F.SilkS")
		)
		(fp_poly
			(pts
				(xy -0.508 0.2794) (xy -0.508 0.2286) (xy -0.635 0.2286) (xy -0.635 -0.254) (xy -0.5334 -0.254)
				(xy -0.5334 -0.2794) (xy 0.5334 -0.2794) (xy 0.5334 -0.254) (xy 0.635 -0.254) (xy 0.635 0.254) (xy 0.5334 0.254)
				(xy 0.5334 0.2794)
			)
			(stroke
				(width 0)
				(type default)
			)
			(fill no)
			(layer "F.CrtYd")
		)
		(pad "1" smd rect
			(at 0.40005 0)
			(size 0.4572 0.508)
			(layers "F.Cu" "F.Mask" "F.Paste")
			(net "P3V3_BLAD1")
		)
		(pad "2" smd rect
			(at -0.40005 0)
			(size 0.4572 0.508)
			(layers "F.Cu" "F.Mask" "F.Paste")
			(net "ENET10G_2_SDA")
		)
	)
	(footprint ""
		(layer "F.Cu")
		(at 338.127848 -22.946106)
		(property "Reference" "R24"
			(at -58.3438 -4.587748 0)
			(unlocked yes)
			(layer "F.SilkS")
			(effects
				(font
					(size 0.7874 0.5842)
					(thickness 0.1524)
				)
				(justify left)
			)
		)
		(property "Value" ""
			(at 0 0 0)
			(layer "F.Fab")
			(effects
				(font
					(size 1.27 1.27)
				)
			)
		)
		(duplicate_pad_numbers_are_jumpers no)
		(fp_line
			(start -0.7874 -0.4064)
			(end 0.7874 -0.4064)
			(stroke
				(width 0.1524)
				(type default)
			)
			(layer "F.SilkS")
		)
		(fp_line
			(start -0.7874 0.4064)
			(end -0.7874 -0.4064)
			(stroke
				(width 0.1524)
				(type default)
			)
			(layer "F.SilkS")
		)
		(fp_line
			(start 0.7874 -0.4064)
			(end 0.7874 0.4064)
			(stroke
				(width 0.1524)
				(type default)
			)
			(layer "F.SilkS")
		)
		(fp_line
			(start 0.7874 0.4064)
			(end -0.7874 0.4064)
			(stroke
				(width 0.1524)
				(type default)
			)
			(layer "F.SilkS")
		)
		(fp_poly
			(pts
				(xy -0.508 0.2794) (xy -0.508 0.2286) (xy -0.635 0.2286) (xy -0.635 -0.254) (xy -0.5334 -0.254)
				(xy -0.5334 -0.2794) (xy 0.5334 -0.2794) (xy 0.5334 -0.254) (xy 0.635 -0.254) (xy 0.635 0.254) (xy 0.5334 0.254)
				(xy 0.5334 0.2794)
			)
			(stroke
				(width 0)
				(type default)
			)
			(fill no)
			(layer "F.CrtYd")
		)
		(pad "1" smd rect
			(at 0.40005 0)
			(size 0.4572 0.508)
			(layers "F.Cu" "F.Mask" "F.Paste")
			(net "P3V3_BLAD2")
		)
		(pad "2" smd rect
			(at -0.40005 0)
			(size 0.4572 0.508)
			(layers "F.Cu" "F.Mask" "F.Paste")
			(net "ENET10G_4_SCL")
		)
	)
	(footprint ""
		(layer "F.Cu")
		(at 156.0576 -28.488132 180)
		(property "Reference" "R76"
			(at -33.9344 -18.674334 0)
			(unlocked yes)
			(layer "F.SilkS")
			(effects
				(font
					(size 0.7874 0.5842)
					(thickness 0.1524)
				)
				(justify left)
			)
		)
		(property "Value" ""
			(at 0 0 180)
			(layer "F.Fab")
			(effects
				(font
					(size 1.27 1.27)
				)
			)
		)
		(duplicate_pad_numbers_are_jumpers no)
		(fp_line
			(start 1.905 0.8636)
			(end -1.905 0.8636)
			(stroke
				(width 0.1524)
				(type default)
			)
			(layer "F.SilkS")
		)
		(fp_line
			(start 1.905 -0.8636)
			(end 1.905 0.8636)
			(stroke
				(width 0.1524)
				(type default)
			)
			(layer "F.SilkS")
		)
		(fp_line
			(start -1.905 0.8636)
			(end -1.905 -0.8636)
			(stroke
				(width 0.1524)
				(type default)
			)
			(layer "F.SilkS")
		)
		(fp_line
			(start -1.905 -0.8636)
			(end 1.905 -0.8636)
			(stroke
				(width 0.1524)
				(type default)
			)
			(layer "F.SilkS")
		)
		(fp_poly
			(pts
				(xy 1.524 0.6858) (xy 1.524 -0.6858) (xy 1.524 -0.7366) (xy -1.524 -0.7366) (xy -1.524 -0.6858)
				(xy -1.524 0.6858) (xy -1.524 0.7366) (xy 1.524 0.7366)
			)
			(stroke
				(width 0)
				(type default)
			)
			(fill no)
			(layer "F.CrtYd")
		)
		(pad "1" smd rect
			(at 0.94996 0 180)
			(size 1.1176 1.3716)
			(layers "F.Cu" "F.Mask" "F.Paste")
			(net "P3V3_BLAD1")
		)
		(pad "2" smd rect
			(at -0.94996 0 180)
			(size 1.1176 1.3716)
			(layers "F.Cu" "F.Mask" "F.Paste")
			(net "P3V3_10G_1_VCCT")
		)
	)
	(footprint ""
		(layer "F.Cu")
		(at 155.064714 -37.841428)
		(property "Reference" "FS3"
			(at 35.23488 24.299164 0)
			(unlocked yes)
			(layer "F.SilkS")
			(effects
				(font
					(size 0.7874 0.5842)
					(thickness 0.1524)
				)
				(justify left)
			)
		)
		(property "Value" ""
			(at 0 0 0)
			(layer "F.Fab")
			(effects
				(font
					(size 1.27 1.27)
				)
			)
		)
		(duplicate_pad_numbers_are_jumpers no)
		(fp_line
			(start -0.650494 -1.050036)
			(end 3.550412 -1.050036)
			(stroke
				(width 0.1524)
				(type default)
			)
			(layer "F.SilkS")
		)
		(fp_line
			(start -0.650494 1.050036)
			(end -0.650494 -1.050036)
			(stroke
				(width 0.1524)
				(type default)
			)
			(layer "F.SilkS")
		)
		(fp_line
			(start 3.550412 -1.050036)
			(end 3.550412 1.050036)
			(stroke
				(width 0.1524)
				(type default)
			)
			(layer "F.SilkS")
		)
		(fp_line
			(start 3.550412 1.050036)
			(end -0.650494 1.050036)
			(stroke
				(width 0.1524)
				(type default)
			)
			(layer "F.SilkS")
		)
		(fp_poly
			(pts
				(xy 3.228086 -0.9652) (xy 3.228086 -1.100074) (xy -0.327914 -1.100074) (xy -0.327914 -0.9652) (xy -0.556514 -0.9652)
				(xy -0.556514 0.9652) (xy -0.327914 0.9652) (xy -0.327914 1.100074) (xy 3.228086 1.100074) (xy 3.228086 0.9652)
				(xy 3.456686 0.9652) (xy 3.456686 -0.9652)
			)
			(stroke
				(width 0)
				(type default)
			)
			(fill no)
			(layer "F.CrtYd")
		)
		(fp_text user "1"
			(at -1.201674 0.016764 0)
			(unlocked yes)
			(layer "F.SilkS")
			(effects
				(font
					(size 0.7874 0.5842)
					(thickness 0.1524)
				)
				(justify left)
			)
		)
		(fp_text user "2"
			(at 4.157726 -0.389636 0)
			(unlocked yes)
			(layer "F.SilkS")
			(effects
				(font
					(size 0.7874 0.5842)
					(thickness 0.1524)
				)
				(justify left)
			)
		)
		(pad "1" smd rect
			(at 0 0)
			(size 1.016 1.8034)
			(layers "F.Cu" "F.Mask" "F.Paste")
			(net "P3V3_BLAD1")
		)
		(pad "2" smd rect
			(at 2.899918 0)
			(size 1.016 1.8034)
			(layers "F.Cu" "F.Mask" "F.Paste")
			(net "P3V3_10G_1_VCCR_L")
		)
	)
	(footprint ""
		(layer "F.Cu")
		(at 79.810102 -41.500044 180)
		(property "Reference" "H3"
			(at 3.029204 -4.59994 0)
			(unlocked yes)
			(layer "F.SilkS")
			(effects
				(font
					(size 0.7874 0.5842)
					(thickness 0.1524)
				)
				(justify left)
			)
		)
		(property "Value" ""
			(at 0 0 180)
			(layer "F.Fab")
			(effects
				(font
					(size 1.27 1.27)
				)
			)
		)
		(duplicate_pad_numbers_are_jumpers no)
		(fp_poly
			(pts
				(arc
					(start 3.999992 5.999988)
					(mid 0 9.99998)
					(end -3.999992 5.999988)
				)
				(arc
					(start -3.999992 0)
					(mid 0 -3.999992)
					(end 3.999992 0)
				)
			)
			(stroke
				(width 0)
				(type default)
			)
			(fill no)
			(layer "B.CrtYd")
		)
		(fp_poly
			(pts
				(arc
					(start 3.999992 5.999988)
					(mid 0 9.99998)
					(end -3.999992 5.999988)
				)
				(arc
					(start -3.999992 0)
					(mid 0 -3.999992)
					(end 3.999992 0)
				)
			)
			(stroke
				(width 0)
				(type default)
			)
			(fill no)
			(layer "F.CrtYd")
		)
		(pad "" np_thru_hole circle
			(at 0 0 180)
			(size 3.5052 3.5052)
			(drill 3.5052)
			(layers "*.Cu" "*.Mask")
			(clearance 0.381)
			(thermal_gap 0.381)
		)
		(zone
			(layers "F.Cu" "B.Cu" "In1.Cu" "In2.Cu" "In3.Cu" "In4.Cu" "In5.Cu" "In6.Cu")
			(hatch none 0.5)
			(connect_pads
				(clearance 0)
			)
			(min_thickness 0.25)
			(keepout
				(tracks not_allowed)
				(vias allowed)
				(pads allowed)
				(copperpour not_allowed)
				(footprints allowed)
			)
			(placement
				(enabled no)
				(sheetname "")
			)
			(fill
				(thermal_gap 0.5)
				(thermal_bridge_width 0.5)
				(island_removal_mode 0)
			)
			(polygon
				(pts
					(arc
						(start 77.398372 -44.952666)
						(mid 79.810102 -51.007954)
						(end 82.221832 -44.952666)
					)
					(arc
						(start 82.221832 -44.952666)
						(mid 82.108203 -44.789805)
						(end 82.068162 -44.595288)
					)
					(arc
						(start 82.068162 -41.500044)
						(mid 79.810102 -39.241984)
						(end 77.552042 -41.500044)
					)
					(arc
						(start 77.552042 -44.595288)
						(mid 77.512056 -44.789828)
						(end 77.398372 -44.952666)
					)
				)
			)
		)
	)
	(footprint ""
		(layer "F.Cu")
		(at 105.9688 -2.9464 90)
		(property "Reference" "C20"
			(at -2.3876 -4.943348 90)
			(unlocked yes)
			(layer "F.SilkS")
			(effects
				(font
					(size 0.7874 0.5842)
					(thickness 0.1524)
				)
				(justify left)
			)
		)
		(property "Value" ""
			(at 0 0 90)
			(layer "F.Fab")
			(effects
				(font
					(size 1.27 1.27)
				)
			)
		)
		(duplicate_pad_numbers_are_jumpers no)
		(fp_line
			(start 0.7874 -0.4064)
			(end 0.7874 0.4064)
			(stroke
				(width 0.1524)
				(type default)
			)
			(layer "F.SilkS")
		)
		(fp_line
			(start -0.7874 -0.4064)
			(end 0.7874 -0.4064)
			(stroke
				(width 0.1524)
				(type default)
			)
			(layer "F.SilkS")
		)
		(fp_line
			(start 0 0.381)
			(end 0 -0.381)
			(stroke
				(width 0.1524)
				(type default)
			)
			(layer "F.SilkS")
		)
		(fp_line
			(start 0.7874 0.4064)
			(end -0.7874 0.4064)
			(stroke
				(width 0.1524)
				(type default)
			)
			(layer "F.SilkS")
		)
		(fp_line
			(start -0.7874 0.4064)
			(end -0.7874 -0.4064)
			(stroke
				(width 0.1524)
				(type default)
			)
			(layer "F.SilkS")
		)
		(fp_poly
			(pts
				(xy -0.5334 0.254) (xy -0.635 0.254) (xy -0.635 0.2286) (xy -0.635 -0.254) (xy -0.5334 -0.254) (xy -0.5334 -0.2794)
				(xy 0.5334 -0.2794) (xy 0.5334 -0.254) (xy 0.635 -0.254) (xy 0.635 0.254) (xy 0.5334 0.254) (xy 0.5334 0.2794)
				(xy -0.508 0.2794) (xy -0.5334 0.2794)
			)
			(stroke
				(width 0)
				(type default)
			)
			(fill no)
			(layer "F.CrtYd")
		)
		(pad "1" smd rect
			(at 0.40005 0 90)
			(size 0.4572 0.508)
			(layers "F.Cu" "F.Mask" "F.Paste")
			(net "P3V3_10G_2_VCCT")
		)
		(pad "2" smd rect
			(at -0.40005 0 90)
			(size 0.4572 0.508)
			(layers "F.Cu" "F.Mask" "F.Paste")
			(net "GND")
		)
	)
	(footprint ""
		(layer "F.Cu")
		(at 351.177352 -21.092668)
		(property "Reference" "R75"
			(at -58.908696 -4.409948 0)
			(unlocked yes)
			(layer "F.SilkS")
			(effects
				(font
					(size 0.7874 0.5842)
					(thickness 0.1524)
				)
				(justify left)
			)
		)
		(property "Value" ""
			(at 0 0 0)
			(layer "F.Fab")
			(effects
				(font
					(size 1.27 1.27)
				)
			)
		)
		(duplicate_pad_numbers_are_jumpers no)
		(fp_line
			(start -0.7874 -0.4064)
			(end 0.7874 -0.4064)
			(stroke
				(width 0.1524)
				(type default)
			)
			(layer "F.SilkS")
		)
		(fp_line
			(start -0.7874 0.4064)
			(end -0.7874 -0.4064)
			(stroke
				(width 0.1524)
				(type default)
			)
			(layer "F.SilkS")
		)
		(fp_line
			(start 0.7874 -0.4064)
			(end 0.7874 0.4064)
			(stroke
				(width 0.1524)
				(type default)
			)
			(layer "F.SilkS")
		)
		(fp_line
			(start 0.7874 0.4064)
			(end -0.7874 0.4064)
			(stroke
				(width 0.1524)
				(type default)
			)
			(layer "F.SilkS")
		)
		(fp_poly
			(pts
				(xy -0.508 0.2794) (xy -0.508 0.2286) (xy -0.635 0.2286) (xy -0.635 -0.254) (xy -0.5334 -0.254)
				(xy -0.5334 -0.2794) (xy 0.5334 -0.2794) (xy 0.5334 -0.254) (xy 0.635 -0.254) (xy 0.635 0.254) (xy 0.5334 0.254)
				(xy 0.5334 0.2794)
			)
			(stroke
				(width 0)
				(type default)
			)
			(fill no)
			(layer "F.CrtYd")
		)
		(pad "1" smd rect
			(at 0.40005 0)
			(size 0.4572 0.508)
			(layers "F.Cu" "F.Mask" "F.Paste")
			(net "ENET10G_3_MOD_DEF0")
		)
		(pad "2" smd rect
			(at -0.40005 0)
			(size 0.4572 0.508)
			(layers "F.Cu" "F.Mask" "F.Paste")
			(net "SFP3_PRESENT_N")
		)
	)
	(footprint ""
		(layer "F.Cu")
		(at 402.988018 -33.589976)
		(property "Reference" "U9"
			(at -21.532342 -12.261342 90)
			(unlocked yes)
			(layer "F.SilkS")
			(effects
				(font
					(size 0.7874 0.5842)
					(thickness 0.1524)
				)
				(justify left)
			)
		)
		(property "Value" ""
			(at 0 0 0)
			(layer "F.Fab")
			(effects
				(font
					(size 1.27 1.27)
				)
			)
		)
		(duplicate_pad_numbers_are_jumpers no)
		(fp_line
			(start -20.984972 -16.800068)
			(end 20.984972 -16.800068)
			(stroke
				(width 0.1524)
				(type default)
			)
			(layer "F.SilkS")
		)
		(fp_line
			(start -20.984972 -10.3886)
			(end -20.984972 -10.3124)
			(stroke
				(width 0.1524)
				(type default)
			)
			(layer "F.SilkS")
		)
		(fp_line
			(start -20.984972 -10.3124)
			(end -20.984972 -16.800068)
			(stroke
				(width 0.1524)
				(type default)
			)
			(layer "F.SilkS")
		)
		(fp_line
			(start -20.984972 0)
			(end -20.984972 -7.6962)
			(stroke
				(width 0.1524)
				(type default)
			)
			(layer "F.SilkS")
		)
		(fp_line
			(start -20.984972 4.699)
			(end -20.984972 0)
			(stroke
				(width 0.1524)
				(type default)
			)
			(layer "F.SilkS")
		)
		(fp_line
			(start -20.984972 13.679932)
			(end -20.984972 7.3152)
			(stroke
				(width 0.1524)
				(type default)
			)
			(layer "F.SilkS")
		)
		(fp_line
			(start -18.379948 -12.599924)
			(end -0.635 -12.599924)
			(stroke
				(width 0.1524)
				(type default)
			)
			(layer "F.SilkS")
		)
		(fp_line
			(start -18.379948 -10.4394)
			(end -18.379948 -12.599924)
			(stroke
				(width 0.1524)
				(type default)
			)
			(layer "F.SilkS")
		)
		(fp_line
			(start -18.379948 -1.0668)
			(end -18.379948 -7.5692)
			(stroke
				(width 0.1524)
				(type default)
			)
			(layer "F.SilkS")
		)
		(fp_line
			(start -18.379948 4.5466)
			(end -18.379948 1.0668)
			(stroke
				(width 0.1524)
				(type default)
			)
			(layer "F.SilkS")
		)
		(fp_line
			(start -18.379948 11.569954)
			(end -18.379948 7.4422)
			(stroke
				(width 0.1524)
				(type default)
			)
			(layer "F.SilkS")
		)
		(fp_line
			(start -13.64996 11.569954)
			(end -18.379948 11.569954)
			(stroke
				(width 0.1524)
				(type default)
			)
			(layer "F.SilkS")
		)
		(fp_line
			(start -13.64996 13.679932)
			(end -20.984972 13.679932)
			(stroke
				(width 0.1524)
				(type default)
			)
			(layer "F.SilkS")
		)
		(fp_line
			(start -13.64996 13.679932)
			(end -13.64996 11.569954)
			(stroke
				(width 0.1524)
				(type default)
			)
			(layer "F.SilkS")
		)
		(fp_line
			(start -4.949952 11.569954)
			(end -4.949952 13.679932)
			(stroke
				(width 0.1524)
				(type default)
			)
			(layer "F.SilkS")
		)
		(fp_line
			(start -0.635 -12.599924)
			(end -0.635 11.569954)
			(stroke
				(width 0.1524)
				(type default)
			)
			(layer "F.SilkS")
		)
		(fp_line
			(start -0.635 11.569954)
			(end -4.949952 11.569954)
			(stroke
				(width 0.1524)
				(type default)
			)
			(layer "F.SilkS")
		)
		(fp_line
			(start 0.635 -12.599924)
			(end 18.379948 -12.599924)
			(stroke
				(width 0.1524)
				(type default)
			)
			(layer "F.SilkS")
		)
		(fp_line
			(start 0.635 11.569954)
			(end 0.635 -12.599924)
			(stroke
				(width 0.1524)
				(type default)
			)
			(layer "F.SilkS")
		)
		(fp_line
			(start 5.359908 11.569954)
			(end 0.635 11.569954)
			(stroke
				(width 0.1524)
				(type default)
			)
			(layer "F.SilkS")
		)
		(fp_line
			(start 5.359908 13.679932)
			(end -4.949952 13.679932)
			(stroke
				(width 0.1524)
				(type default)
			)
			(layer "F.SilkS")
		)
		(fp_line
			(start 5.359908 13.679932)
			(end 5.359908 11.569954)
			(stroke
				(width 0.1524)
				(type default)
			)
			(layer "F.SilkS")
		)
		(fp_line
			(start 14.059916 11.569954)
			(end 14.059916 13.679932)
			(stroke
				(width 0.1524)
				(type default)
			)
			(layer "F.SilkS")
		)
		(fp_line
			(start 18.379948 -12.599924)
			(end 18.379948 -10.4394)
			(stroke
				(width 0.1524)
				(type default)
			)
			(layer "F.SilkS")
		)
		(fp_line
			(start 18.379948 -7.5438)
			(end 18.379948 -1.0922)
			(stroke
				(width 0.1524)
				(type default)
			)
			(layer "F.SilkS")
		)
		(fp_line
			(start 18.379948 1.0668)
			(end 18.379948 4.5466)
			(stroke
				(width 0.1524)
				(type default)
			)
			(layer "F.SilkS")
		)
		(fp_line
			(start 18.379948 7.4422)
			(end 18.379948 11.569954)
			(stroke
				(width 0.1524)
				(type default)
			)
			(layer "F.SilkS")
		)
		(fp_line
			(start 18.379948 11.569954)
			(end 14.059916 11.569954)
			(stroke
				(width 0.1524)
				(type default)
			)
			(layer "F.SilkS")
		)
		(fp_line
			(start 20.984972 -16.800068)
			(end 20.984972 -10.3124)
			(stroke
				(width 0.1524)
				(type default)
			)
			(layer "F.SilkS")
		)
		(fp_line
			(start 20.984972 -7.6962)
			(end 20.984972 4.699)
			(stroke
				(width 0.1524)
				(type default)
			)
			(layer "F.SilkS")
		)
		(fp_line
			(start 20.984972 7.3152)
			(end 20.984972 13.679932)
			(stroke
				(width 0.1524)
				(type default)
			)
			(layer "F.SilkS")
		)
		(fp_line
			(start 20.984972 13.679932)
			(end 14.059916 13.679932)
			(stroke
				(width 0.1524)
				(type default)
			)
			(layer "F.SilkS")
		)
		(fp_poly
			(pts
				(xy 12.908788 14.0208) (xy 14.525244 17.253458) (xy 16.1417 15.637256)
			)
			(stroke
				(width 0)
				(type default)
			)
			(fill yes)
			(layer "F.SilkS")
		)
		(fp_poly
			(pts
				(arc
					(start -17.89938 0)
					(mid -20.340828 0)
					(end -17.89938 0)
				)
			)
			(stroke
				(width 0)
				(type default)
			)
			(fill no)
			(layer "B.CrtYd")
		)
		(fp_poly
			(pts
				(arc
					(start 20.334986 0)
					(mid 17.895062 0)
					(end 20.334986 0)
				)
			)
			(stroke
				(width 0)
				(type default)
			)
			(fill no)
			(layer "B.CrtYd")
		)
		(fp_poly
			(pts
				(arc
					(start -17.775682 -8.999982)
					(mid -21.444458 -8.999982)
					(end -17.775682 -8.999982)
				)
			)
			(stroke
				(width 0)
				(type default)
			)
			(fill no)
			(layer "B.CrtYd")
		)
		(fp_poly
			(pts
				(arc
					(start -17.775682 5.999988)
					(mid -21.444458 5.999988)
					(end -17.775682 5.999988)
				)
			)
			(stroke
				(width 0)
				(type default)
			)
			(fill no)
			(layer "B.CrtYd")
		)
		(fp_poly
			(pts
				(arc
					(start 21.444458 -8.999982)
					(mid 17.775682 -8.999982)
					(end 21.444458 -8.999982)
				)
			)
			(stroke
				(width 0)
				(type default)
			)
			(fill no)
			(layer "B.CrtYd")
		)
		(fp_poly
			(pts
				(arc
					(start 21.444458 5.999988)
					(mid 17.775682 5.999988)
					(end 21.444458 5.999988)
				)
			)
			(stroke
				(width 0)
				(type default)
			)
			(fill no)
			(layer "B.CrtYd")
		)
		(fp_poly
			(pts
				(xy -18.3388 -12.573) (xy -18.3388 -10.3886) (xy -17.7292 -10.3886) (xy -17.7292 -7.6708) (xy -18.3388 -7.6708)
				(xy -18.3388 -1.016) (xy -17.8308 -1.016) (xy -17.8308 0.9652) (xy -18.3388 0.9652) (xy -18.3388 4.6228)
				(xy -17.7292 4.6228) (xy -17.7292 7.3406) (xy -18.3388 7.3406) (xy -18.3388 11.5316) (xy -0.6604 11.5316)
				(xy -0.6604 7.3406) (xy -0.6604 4.6228) (xy -0.6604 0.9652) (xy -0.6604 -1.016) (xy -0.6604 -7.6708)
				(xy -0.6604 -10.3886) (xy -0.6604 -12.573)
			)
			(stroke
				(width 0)
				(type default)
			)
			(fill no)
			(layer "F.CrtYd")
		)
		(fp_poly
			(pts
				(xy 0.7112 -12.5984) (xy 0.7112 -10.3632) (xy 0.7112 -7.6454) (xy 0.7112 -0.9906) (xy 0.7112 0.9906)
				(xy 0.7112 4.6482) (xy 0.7112 7.366) (xy 0.7112 11.557) (xy 18.3896 11.557) (xy 18.3896 7.366) (xy 18.3896 7.3406)
				(xy 17.8054 7.3406) (xy 17.8054 4.6482) (xy 17.8308 4.6482) (xy 18.3896 4.6482) (xy 18.3896 0.9906)
				(xy 18.3896 0.9652) (xy 17.9324 0.9652) (xy 17.8816 0.9652) (xy 17.8816 -0.9906) (xy 17.9324 -0.9906)
				(xy 18.3642 -0.9906) (xy 18.3642 -7.6454) (xy 17.8308 -7.6454) (xy 17.8054 -7.6454) (xy 17.8054 -10.3632)
				(xy 17.8308 -10.3632) (xy 18.3642 -10.3632) (xy 18.3642 -12.5984)
			)
			(stroke
				(width 0)
				(type default)
			)
			(fill no)
			(layer "F.CrtYd")
		)
		(fp_poly
			(pts
				(xy -20.984972 0) (xy -20.984972 -7.874) (xy -21.392134 -7.874) (xy -21.392134 -10.1092) (xy -20.984972 -10.1092)
				(xy -20.984972 -16.800068) (xy 20.984972 -16.800068) (xy 20.984972 -10.1092) (xy 21.3868 -10.1092)
				(xy 21.3868 -7.874) (xy 20.984972 -7.874) (xy 20.984972 0) (xy 20.984972 4.9022) (xy 21.3868 4.9022)
				(xy 21.3868 7.112) (xy 20.984972 7.112) (xy 20.984972 13.679932) (xy 9.50468 13.679932) (xy 9.50468 11.569954)
				(xy 18.415 11.569954) (xy 18.408904 7.2898) (xy 17.8308 7.2898) (xy 17.8308 4.699) (xy 17.8562 4.699)
				(xy 18.405094 4.699) (xy 18.399506 0.9144) (xy 17.9324 0.9144) (xy 17.9324 -0.9398) (xy 18.396966 -0.9398)
				(xy 18.38706 -7.7216) (xy 17.8308 -7.7216) (xy 17.8308 -10.2362) (xy 18.383504 -10.2362) (xy 18.383504 -10.2616)
				(xy 18.379948 -12.599924) (xy 0.635 -12.599924) (xy 0.635 11.569954) (xy 9.50214 11.569954) (xy 9.50214 13.679932)
				(xy -9.50214 13.679932) (xy -9.50214 11.569954) (xy -0.635 11.569954) (xy -0.635 -12.599924) (xy -18.379948 -12.599924)
				(xy -18.377662 -10.2616) (xy -17.8308 -10.2616) (xy -17.8308 -7.747) (xy -18.375122 -7.747) (xy -18.375122 -7.7216)
				(xy -18.375122 -0.9144) (xy -17.9324 -0.9144) (xy -17.9324 0.9144) (xy -18.375122 0.9144) (xy -18.375122 4.7498)
				(xy -17.8308 4.7498) (xy -17.8308 7.2644) (xy -18.375122 7.2644) (xy -18.375122 11.569954) (xy -9.50468 11.569954)
				(xy -9.50468 13.679932) (xy -20.984972 13.679932) (xy -20.984972 7.112) (xy -21.392134 7.112) (xy -21.392134 4.8768)
				(xy -20.984972 4.8768)
			)
			(stroke
				(width 0)
				(type default)
			)
			(fill no)
			(layer "F.CrtYd")
		)
		(fp_line
			(start -20.984972 -16.800068)
			(end 20.984972 -16.800068)
			(stroke
				(width 0.1)
				(type default)
			)
			(layer "F.Fab")
		)
		(fp_line
			(start -20.984972 -16.800068)
			(end 20.984972 -16.800068)
			(stroke
				(width 0.1)
				(type default)
			)
			(layer "F.Fab")
		)
		(fp_line
			(start -20.984972 0)
			(end -20.984972 -16.800068)
			(stroke
				(width 0.1)
				(type default)
			)
			(layer "F.Fab")
		)
		(fp_line
			(start -20.984972 0)
			(end -20.984972 -16.800068)
			(stroke
				(width 0.1)
				(type default)
			)
			(layer "F.Fab")
		)
		(fp_line
			(start -20.984972 13.679932)
			(end -20.984972 0)
			(stroke
				(width 0.1)
				(type default)
			)
			(layer "F.Fab")
		)
		(fp_line
			(start -20.984972 13.679932)
			(end -20.984972 0)
			(stroke
				(width 0.1)
				(type default)
			)
			(layer "F.Fab")
		)
		(fp_line
			(start -18.379948 -12.599924)
			(end -0.635 -12.599924)
			(stroke
				(width 0.1)
				(type default)
			)
			(layer "F.Fab")
		)
		(fp_line
			(start -18.379948 11.569954)
			(end -18.379948 -12.599924)
			(stroke
				(width 0.1)
				(type default)
			)
			(layer "F.Fab")
		)
		(fp_line
			(start -13.854938 13.679932)
			(end -20.984972 13.679932)
			(stroke
				(width 0.1)
				(type default)
			)
			(layer "F.Fab")
		)
		(fp_line
			(start -13.64996 11.569954)
			(end -18.379948 11.569954)
			(stroke
				(width 0.1)
				(type default)
			)
			(layer "F.Fab")
		)
		(fp_line
			(start -13.64996 13.679932)
			(end -13.64996 11.569954)
			(stroke
				(width 0.1)
				(type default)
			)
			(layer "F.Fab")
		)
		(fp_line
			(start -4.949952 11.569954)
			(end -4.949952 13.679932)
			(stroke
				(width 0.1)
				(type default)
			)
			(layer "F.Fab")
		)
		(fp_line
			(start -0.635 -12.599924)
			(end -0.635 11.569954)
			(stroke
				(width 0.1)
				(type default)
			)
			(layer "F.Fab")
		)
		(fp_line
			(start -0.635 11.569954)
			(end -4.949952 11.569954)
			(stroke
				(width 0.1)
				(type default)
			)
			(layer "F.Fab")
		)
		(fp_line
			(start 0.635 -12.599924)
			(end 18.379948 -12.599924)
			(stroke
				(width 0.1)
				(type default)
			)
			(layer "F.Fab")
		)
		(fp_line
			(start 0.635 11.569954)
			(end 0.635 -12.599924)
			(stroke
				(width 0.1)
				(type default)
			)
			(layer "F.Fab")
		)
		(fp_line
			(start 5.15493 13.679932)
			(end -5.15493 13.679932)
			(stroke
				(width 0.1)
				(type default)
			)
			(layer "F.Fab")
		)
		(fp_line
			(start 5.359908 11.569954)
			(end 0.635 11.569954)
			(stroke
				(width 0.1)
				(type default)
			)
			(layer "F.Fab")
		)
		(fp_line
			(start 5.359908 13.679932)
			(end 5.359908 11.569954)
			(stroke
				(width 0.1)
				(type default)
			)
			(layer "F.Fab")
		)
		(fp_line
			(start 14.059916 11.569954)
			(end 14.059916 13.679932)
			(stroke
				(width 0.1)
				(type default)
			)
			(layer "F.Fab")
		)
		(fp_line
			(start 18.379948 -12.599924)
			(end 18.379948 11.569954)
			(stroke
				(width 0.1)
				(type default)
			)
			(layer "F.Fab")
		)
		(fp_line
			(start 18.379948 11.569954)
			(end 14.059916 11.569954)
			(stroke
				(width 0.1)
				(type default)
			)
			(layer "F.Fab")
		)
		(fp_line
			(start 20.984972 -16.800068)
			(end 20.984972 13.679932)
			(stroke
				(width 0.1)
				(type default)
			)
			(layer "F.Fab")
		)
		(fp_line
			(start 20.984972 -16.800068)
			(end 20.984972 13.679932)
			(stroke
				(width 0.1)
				(type default)
			)
			(layer "F.Fab")
		)
		(fp_line
			(start 20.984972 13.679932)
			(end -20.984972 13.679932)
			(stroke
				(width 0.1)
				(type default)
			)
			(layer "F.Fab")
		)
		(fp_line
			(start 20.984972 13.679932)
			(end 13.854938 13.679932)
			(stroke
				(width 0.1)
				(type default)
			)
			(layer "F.Fab")
		)
		(fp_poly
			(pts
				(xy 11.90498 14.2367) (xy 10.76198 17.6657) (xy 13.04798 17.6657)
			)
			(stroke
				(width 0)
				(type default)
			)
			(fill yes)
			(layer "F.Fab")
		)
		(fp_text user "G3"
			(at -22.9108 5.908294 0)
			(unlocked yes)
			(layer "F.SilkS")
			(effects
				(font
					(size 0.7874 0.5842)
					(thickness 0.1524)
				)
				(justify left)
			)
		)
		(fp_text user "G1"
			(at -22.8346 -9.62533 0)
			(unlocked yes)
			(layer "F.SilkS")
			(effects
				(font
					(size 0.7874 0.5842)
					(thickness 0.1524)
				)
				(justify left)
			)
		)
		(fp_text user "G2"
			(at -22.5298 1.101852 0)
			(unlocked yes)
			(layer "F.SilkS")
			(effects
				(font
					(size 0.7874 0.5842)
					(thickness 0.1524)
				)
				(justify left)
			)
		)
		(fp_text user "G5"
			(at 21.1582 7.934452 0)
			(unlocked yes)
			(layer "F.SilkS")
			(effects
				(font
					(size 0.7874 0.5842)
					(thickness 0.1524)
				)
				(justify left)
			)
		)
		(fp_text user "G6"
			(at 21.1836 10.251694 0)
			(unlocked yes)
			(layer "F.SilkS")
			(effects
				(font
					(size 0.7874 0.5842)
					(thickness 0.1524)
				)
				(justify left)
			)
		)
		(fp_text user "G4"
			(at 21.7424 -9.09193 0)
			(unlocked yes)
			(layer "F.SilkS")
			(effects
				(font
					(size 0.7874 0.5842)
					(thickness 0.1524)
				)
				(justify left)
			)
		)
		(fp_text user "G1"
			(at -21.5392 -9.108948 0)
			(unlocked yes)
			(layer "B.SilkS")
			(effects
				(font
					(size 0.7874 0.5842)
					(thickness 0.1524)
				)
				(justify left mirror)
			)
		)
		(fp_text user "G3"
			(at -21.5138 5.908294 0)
			(unlocked yes)
			(layer "B.SilkS")
			(effects
				(font
					(size 0.7874 0.5842)
					(thickness 0.1524)
				)
				(justify left mirror)
			)
		)
		(fp_text user "G2"
			(at -20.4216 -0.091948 0)
			(unlocked yes)
			(layer "B.SilkS")
			(effects
				(font
					(size 0.7874 0.5842)
					(thickness 0.1524)
				)
				(justify left mirror)
			)
		)
		(fp_text user "G6"
			(at 21.336 8.575294 0)
			(unlocked yes)
			(layer "B.SilkS")
			(effects
				(font
					(size 0.7874 0.5842)
					(thickness 0.1524)
				)
				(justify left mirror)
			)
		)
		(fp_text user "G5"
			(at 21.5646 1.203452 0)
			(unlocked yes)
			(layer "B.SilkS")
			(effects
				(font
					(size 0.7874 0.5842)
					(thickness 0.1524)
				)
				(justify left mirror)
			)
		)
		(fp_text user "G4"
			(at 22.8346 -9.09193 0)
			(unlocked yes)
			(layer "B.SilkS")
			(effects
				(font
					(size 0.7874 0.5842)
					(thickness 0.1524)
				)
				(justify left mirror)
			)
		)
		(fp_text user "G1"
			(at -21.5392 -9.108948 0)
			(unlocked yes)
			(layer "B.Fab")
			(effects
				(font
					(size 0.7874 0.5842)
					(thickness 0.000001)
				)
				(justify left mirror)
			)
		)
		(fp_text user "G3"
			(at -21.5138 5.908294 0)
			(unlocked yes)
			(layer "B.Fab")
			(effects
				(font
					(size 0.7874 0.5842)
					(thickness 0.000001)
				)
				(justify left mirror)
			)
		)
		(fp_text user "G2"
			(at -20.4216 -0.091948 0)
			(unlocked yes)
			(layer "B.Fab")
			(effects
				(font
					(size 0.7874 0.5842)
					(thickness 0.000001)
				)
				(justify left mirror)
			)
		)
		(fp_text user "G5"
			(at 21.8948 -0.091948 0)
			(unlocked yes)
			(layer "B.Fab")
			(effects
				(font
					(size 0.7874 0.5842)
					(thickness 0.000001)
				)
				(justify left mirror)
			)
		)
		(fp_text user "G4"
			(at 22.8346 -9.09193 0)
			(unlocked yes)
			(layer "B.Fab")
			(effects
				(font
					(size 0.7874 0.5842)
					(thickness 0.000001)
				)
				(justify left mirror)
			)
		)
		(fp_text user "G6"
			(at 23.0886 5.908294 0)
			(unlocked yes)
			(layer "B.Fab")
			(effects
				(font
					(size 0.7874 0.5842)
					(thickness 0.000001)
				)
				(justify left mirror)
			)
		)
		(fp_text user "G3"
			(at -22.9108 5.908294 0)
			(unlocked yes)
			(layer "F.Fab")
			(effects
				(font
					(size 0.7874 0.5842)
					(thickness 0.000001)
				)
				(justify left)
			)
		)
		(fp_text user "G1"
			(at -22.7076 -9.09193 0)
			(unlocked yes)
			(layer "F.Fab")
			(effects
				(font
					(size 0.7874 0.5842)
					(thickness 0.000001)
				)
				(justify left)
			)
		)
		(fp_text user "G2"
			(at -22.5806 -0.091948 0)
			(unlocked yes)
			(layer "F.Fab")
			(effects
				(font
					(size 0.7874 0.5842)
					(thickness 0.000001)
				)
				(justify left)
			)
		)
		(fp_text user "G5"
			(at 21.2344 -0.091948 0)
			(unlocked yes)
			(layer "F.Fab")
			(effects
				(font
					(size 0.7874 0.5842)
					(thickness 0.000001)
				)
				(justify left)
			)
		)
		(fp_text user "G6"
			(at 21.6662 5.908294 0)
			(unlocked yes)
			(layer "F.Fab")
			(effects
				(font
					(size 0.7874 0.5842)
					(thickness 0.000001)
				)
				(justify left)
			)
		)
		(fp_text user "G4"
			(at 21.7424 -9.09193 0)
			(unlocked yes)
			(layer "F.Fab")
			(effects
				(font
					(size 0.7874 0.5842)
					(thickness 0.000001)
				)
				(justify left)
			)
		)
		(pad "A1" smd rect
			(at 12.109958 12.62507)
			(size 0.9144 2.1336)
			(layers "F.Cu" "F.Mask" "F.Paste")
			(net "GND")
		)
		(pad "A2" smd rect
			(at 9.709912 12.62507)
			(size 0.9144 2.1336)
			(layers "F.Cu" "F.Mask" "F.Paste")
			(net "GND")
		)
		(pad "A3" smd rect
			(at 7.31012 12.62507)
			(size 0.9144 2.1336)
			(layers "F.Cu" "F.Mask" "F.Paste")
			(net "GND")
		)
		(pad "B1" smd rect
			(at -6.89991 12.62507)
			(size 0.9144 2.1336)
			(layers "F.Cu" "F.Mask" "F.Paste")
			(net "GND")
		)
		(pad "B2" smd rect
			(at -9.299956 12.62507)
			(size 0.9144 2.1336)
			(layers "F.Cu" "F.Mask" "F.Paste")
			(net "GND")
		)
		(pad "B3" smd rect
			(at -11.700002 12.62507)
			(size 0.9144 2.1336)
			(layers "F.Cu" "F.Mask" "F.Paste")
			(net "GND")
		)
		(pad "G1" thru_hole circle
			(at -19.61007 -8.999982)
			(size 3.5306 3.5306)
			(drill 2.5146)
			(layers "*.Cu" "*.Mask")
			(remove_unused_layers no)
			(net "GND")
			(clearance -0.254)
		)
		(pad "G2" thru_hole circle
			(at -19.120104 0)
			(size 2.3368 2.3368)
			(drill 1.5748)
			(layers "*.Cu" "*.Mask")
			(remove_unused_layers no)
			(net "GND")
			(clearance -0.127)
		)
		(pad "G3" thru_hole circle
			(at -19.61007 5.999988)
			(size 3.5306 3.5306)
			(drill 2.5146)
			(layers "*.Cu" "*.Mask")
			(remove_unused_layers no)
			(net "GND")
			(clearance -0.254)
		)
		(pad "G4" thru_hole circle
			(at 19.61007 -8.999982)
			(size 3.5306 3.5306)
			(drill 2.5146)
			(layers "*.Cu" "*.Mask")
			(remove_unused_layers no)
			(net "GND")
			(clearance -0.254)
		)
		(pad "G5" thru_hole circle
			(at 19.120104 0)
			(size 2.3368 2.3368)
			(drill 1.5748)
			(layers "*.Cu" "*.Mask")
			(remove_unused_layers no)
			(net "GND")
			(clearance -0.127)
		)
		(pad "G6" thru_hole circle
			(at 19.61007 5.999988)
			(size 3.5306 3.5306)
			(drill 2.5146)
			(layers "*.Cu" "*.Mask")
			(remove_unused_layers no)
			(net "GND")
			(clearance -0.254)
		)
	)
	(footprint ""
		(layer "F.Cu")
		(at 30.977332 -19.7358 -90)
		(property "Reference" "R86"
			(at 0.9144 -4.729988 90)
			(unlocked yes)
			(layer "F.SilkS")
			(effects
				(font
					(size 0.7874 0.5842)
					(thickness 0.1524)
				)
				(justify left)
			)
		)
		(property "Value" ""
			(at 0 0 270)
			(layer "F.Fab")
			(effects
				(font
					(size 1.27 1.27)
				)
			)
		)
		(duplicate_pad_numbers_are_jumpers no)
		(fp_line
			(start -0.7874 0.4064)
			(end -0.7874 -0.4064)
			(stroke
				(width 0.1524)
				(type default)
			)
			(layer "F.SilkS")
		)
		(fp_line
			(start 0.7874 0.4064)
			(end -0.7874 0.4064)
			(stroke
				(width 0.1524)
				(type default)
			)
			(layer "F.SilkS")
		)
		(fp_line
			(start -0.7874 -0.4064)
			(end 0.7874 -0.4064)
			(stroke
				(width 0.1524)
				(type default)
			)
			(layer "F.SilkS")
		)
		(fp_line
			(start 0.7874 -0.4064)
			(end 0.7874 0.4064)
			(stroke
				(width 0.1524)
				(type default)
			)
			(layer "F.SilkS")
		)
		(fp_poly
			(pts
				(xy -0.508 0.2794) (xy -0.508 0.2286) (xy -0.635 0.2286) (xy -0.635 -0.254) (xy -0.5334 -0.254)
				(xy -0.5334 -0.2794) (xy 0.5334 -0.2794) (xy 0.5334 -0.254) (xy 0.635 -0.254) (xy 0.635 0.254) (xy 0.5334 0.254)
				(xy 0.5334 0.2794)
			)
			(stroke
				(width 0)
				(type default)
			)
			(fill no)
			(layer "F.CrtYd")
		)
		(pad "1" smd rect
			(at 0.40005 0 270)
			(size 0.4572 0.508)
			(layers "F.Cu" "F.Mask" "F.Paste")
			(net "N39391900")
		)
		(pad "2" smd rect
			(at -0.40005 0 270)
			(size 0.4572 0.508)
			(layers "F.Cu" "F.Mask" "F.Paste")
			(net "P12V")
		)
	)
	(footprint ""
		(layer "F.Cu")
		(at 130.146552 -21.143468)
		(property "Reference" "R66"
			(at -61.8236 5.140452 0)
			(unlocked yes)
			(layer "F.SilkS")
			(effects
				(font
					(size 0.7874 0.5842)
					(thickness 0.1524)
				)
				(justify left)
			)
		)
		(property "Value" ""
			(at 0 0 0)
			(layer "F.Fab")
			(effects
				(font
					(size 1.27 1.27)
				)
			)
		)
		(duplicate_pad_numbers_are_jumpers no)
		(fp_line
			(start -0.7874 -0.4064)
			(end 0.7874 -0.4064)
			(stroke
				(width 0.1524)
				(type default)
			)
			(layer "F.SilkS")
		)
		(fp_line
			(start -0.7874 0.4064)
			(end -0.7874 -0.4064)
			(stroke
				(width 0.1524)
				(type default)
			)
			(layer "F.SilkS")
		)
		(fp_line
			(start 0.7874 -0.4064)
			(end 0.7874 0.4064)
			(stroke
				(width 0.1524)
				(type default)
			)
			(layer "F.SilkS")
		)
		(fp_line
			(start 0.7874 0.4064)
			(end -0.7874 0.4064)
			(stroke
				(width 0.1524)
				(type default)
			)
			(layer "F.SilkS")
		)
		(fp_poly
			(pts
				(xy -0.508 0.2794) (xy -0.508 0.2286) (xy -0.635 0.2286) (xy -0.635 -0.254) (xy -0.5334 -0.254)
				(xy -0.5334 -0.2794) (xy 0.5334 -0.2794) (xy 0.5334 -0.254) (xy 0.635 -0.254) (xy 0.635 0.254) (xy 0.5334 0.254)
				(xy 0.5334 0.2794)
			)
			(stroke
				(width 0)
				(type default)
			)
			(fill no)
			(layer "F.CrtYd")
		)
		(pad "1" smd rect
			(at 0.40005 0)
			(size 0.4572 0.508)
			(layers "F.Cu" "F.Mask" "F.Paste")
			(net "ENET10G_1_MOD_DEF0")
		)
		(pad "2" smd rect
			(at -0.40005 0)
			(size 0.4572 0.508)
			(layers "F.Cu" "F.Mask" "F.Paste")
			(net "SFP1_PRESENT_N")
		)
	)
	(footprint ""
		(layer "F.Cu")
		(at 157.781752 -26.709878)
		(property "Reference" "R43"
			(at 33.5534 17.942052 0)
			(unlocked yes)
			(layer "F.SilkS")
			(effects
				(font
					(size 0.7874 0.5842)
					(thickness 0.1524)
				)
				(justify left)
			)
		)
		(property "Value" ""
			(at 0 0 0)
			(layer "F.Fab")
			(effects
				(font
					(size 1.27 1.27)
				)
			)
		)
		(duplicate_pad_numbers_are_jumpers no)
		(fp_line
			(start -0.7874 -0.4064)
			(end 0.7874 -0.4064)
			(stroke
				(width 0.1524)
				(type default)
			)
			(layer "F.SilkS")
		)
		(fp_line
			(start -0.7874 0.4064)
			(end -0.7874 -0.4064)
			(stroke
				(width 0.1524)
				(type default)
			)
			(layer "F.SilkS")
		)
		(fp_line
			(start 0.7874 -0.4064)
			(end 0.7874 0.4064)
			(stroke
				(width 0.1524)
				(type default)
			)
			(layer "F.SilkS")
		)
		(fp_line
			(start 0.7874 0.4064)
			(end -0.7874 0.4064)
			(stroke
				(width 0.1524)
				(type default)
			)
			(layer "F.SilkS")
		)
		(fp_poly
			(pts
				(xy -0.508 0.2794) (xy -0.508 0.2286) (xy -0.635 0.2286) (xy -0.635 -0.254) (xy -0.5334 -0.254)
				(xy -0.5334 -0.2794) (xy 0.5334 -0.2794) (xy 0.5334 -0.254) (xy 0.635 -0.254) (xy 0.635 0.254) (xy 0.5334 0.254)
				(xy 0.5334 0.2794)
			)
			(stroke
				(width 0)
				(type default)
			)
			(fill no)
			(layer "F.CrtYd")
		)
		(pad "1" smd rect
			(at 0.40005 0)
			(size 0.4572 0.508)
			(layers "F.Cu" "F.Mask" "F.Paste")
			(net "GND")
		)
		(pad "2" smd rect
			(at -0.40005 0)
			(size 0.4572 0.508)
			(layers "F.Cu" "F.Mask" "F.Paste")
			(net "ENET10G_1_RS1")
		)
	)
	(footprint ""
		(layer "F.Cu")
		(at 130.101848 -23.256494 180)
		(property "Reference" "R13"
			(at 61.778896 -5.14604 0)
			(unlocked yes)
			(layer "F.SilkS")
			(effects
				(font
					(size 0.7874 0.5842)
					(thickness 0.1524)
				)
				(justify left)
			)
		)
		(property "Value" ""
			(at 0 0 180)
			(layer "F.Fab")
			(effects
				(font
					(size 1.27 1.27)
				)
			)
		)
		(duplicate_pad_numbers_are_jumpers no)
		(fp_line
			(start 0.7874 0.4064)
			(end -0.7874 0.4064)
			(stroke
				(width 0.1524)
				(type default)
			)
			(layer "F.SilkS")
		)
		(fp_line
			(start 0.7874 -0.4064)
			(end 0.7874 0.4064)
			(stroke
				(width 0.1524)
				(type default)
			)
			(layer "F.SilkS")
		)
		(fp_line
			(start -0.7874 0.4064)
			(end -0.7874 -0.4064)
			(stroke
				(width 0.1524)
				(type default)
			)
			(layer "F.SilkS")
		)
		(fp_line
			(start -0.7874 -0.4064)
			(end 0.7874 -0.4064)
			(stroke
				(width 0.1524)
				(type default)
			)
			(layer "F.SilkS")
		)
		(fp_poly
			(pts
				(xy -0.508 0.2794) (xy -0.508 0.2286) (xy -0.635 0.2286) (xy -0.635 -0.254) (xy -0.5334 -0.254)
				(xy -0.5334 -0.2794) (xy 0.5334 -0.2794) (xy 0.5334 -0.254) (xy 0.635 -0.254) (xy 0.635 0.254) (xy 0.5334 0.254)
				(xy 0.5334 0.2794)
			)
			(stroke
				(width 0)
				(type default)
			)
			(fill no)
			(layer "F.CrtYd")
		)
		(pad "1" smd rect
			(at 0.40005 0 180)
			(size 0.4572 0.508)
			(layers "F.Cu" "F.Mask" "F.Paste")
			(net "P3V3_BLAD1")
		)
		(pad "2" smd rect
			(at -0.40005 0 180)
			(size 0.4572 0.508)
			(layers "F.Cu" "F.Mask" "F.Paste")
			(net "ENET10G_1_LOS")
		)
	)
	(footprint ""
		(layer "F.Cu")
		(at 376.121676 -38.7604)
		(property "Reference" "FS7"
			(at 35.262312 22.86508 0)
			(unlocked yes)
			(layer "F.SilkS")
			(effects
				(font
					(size 0.7874 0.5842)
					(thickness 0.1524)
				)
				(justify left)
			)
		)
		(property "Value" ""
			(at 0 0 0)
			(layer "F.Fab")
			(effects
				(font
					(size 1.27 1.27)
				)
			)
		)
		(duplicate_pad_numbers_are_jumpers no)
		(fp_line
			(start -0.650494 -1.050036)
			(end 3.550412 -1.050036)
			(stroke
				(width 0.1524)
				(type default)
			)
			(layer "F.SilkS")
		)
		(fp_line
			(start -0.650494 1.050036)
			(end -0.650494 -1.050036)
			(stroke
				(width 0.1524)
				(type default)
			)
			(layer "F.SilkS")
		)
		(fp_line
			(start 3.550412 -1.050036)
			(end 3.550412 1.050036)
			(stroke
				(width 0.1524)
				(type default)
			)
			(layer "F.SilkS")
		)
		(fp_line
			(start 3.550412 1.050036)
			(end -0.650494 1.050036)
			(stroke
				(width 0.1524)
				(type default)
			)
			(layer "F.SilkS")
		)
		(fp_poly
			(pts
				(xy 3.228086 -0.9652) (xy 3.228086 -1.100074) (xy -0.327914 -1.100074) (xy -0.327914 -0.9652) (xy -0.556514 -0.9652)
				(xy -0.556514 0.9652) (xy -0.327914 0.9652) (xy -0.327914 1.100074) (xy 3.228086 1.100074) (xy 3.228086 0.9652)
				(xy 3.456686 0.9652) (xy 3.456686 -0.9652)
			)
			(stroke
				(width 0)
				(type default)
			)
			(fill no)
			(layer "F.CrtYd")
		)
		(fp_text user "1"
			(at -1.225042 0.74168 0)
			(unlocked yes)
			(layer "F.SilkS")
			(effects
				(font
					(size 0.7874 0.5842)
					(thickness 0.1524)
				)
				(justify left)
			)
		)
		(fp_text user "2"
			(at 3.905758 0.20828 0)
			(unlocked yes)
			(layer "F.SilkS")
			(effects
				(font
					(size 0.7874 0.5842)
					(thickness 0.1524)
				)
				(justify left)
			)
		)
		(pad "1" smd rect
			(at 0 0)
			(size 1.016 1.8034)
			(layers "F.Cu" "F.Mask" "F.Paste")
			(net "P3V3_BLAD2")
		)
		(pad "2" smd rect
			(at 2.899918 0)
			(size 1.016 1.8034)
			(layers "F.Cu" "F.Mask" "F.Paste")
			(net "P3V3_10G_3_VCCR_L")
		)
	)
	(footprint ""
		(layer "F.Cu")
		(at 313.338464 -36.54933 180)
		(property "Reference" "FS6"
			(at 2.570988 6.850888 0)
			(unlocked yes)
			(layer "F.SilkS")
			(effects
				(font
					(size 0.7874 0.5842)
					(thickness 0.1524)
				)
				(justify left)
			)
		)
		(property "Value" ""
			(at 0 0 180)
			(layer "F.Fab")
			(effects
				(font
					(size 1.27 1.27)
				)
			)
		)
		(duplicate_pad_numbers_are_jumpers no)
		(fp_line
			(start 3.550412 1.050036)
			(end -0.650494 1.050036)
			(stroke
				(width 0.1524)
				(type default)
			)
			(layer "F.SilkS")
		)
		(fp_line
			(start 3.550412 -1.050036)
			(end 3.550412 1.050036)
			(stroke
				(width 0.1524)
				(type default)
			)
			(layer "F.SilkS")
		)
		(fp_line
			(start -0.650494 1.050036)
			(end -0.650494 -1.050036)
			(stroke
				(width 0.1524)
				(type default)
			)
			(layer "F.SilkS")
		)
		(fp_line
			(start -0.650494 -1.050036)
			(end 3.550412 -1.050036)
			(stroke
				(width 0.1524)
				(type default)
			)
			(layer "F.SilkS")
		)
		(fp_poly
			(pts
				(xy 3.228086 -0.9652) (xy 3.228086 -1.100074) (xy -0.327914 -1.100074) (xy -0.327914 -0.9652) (xy -0.556514 -0.9652)
				(xy -0.556514 0.9652) (xy -0.327914 0.9652) (xy -0.327914 1.100074) (xy 3.228086 1.100074) (xy 3.228086 0.9652)
				(xy 3.456686 0.9652) (xy 3.456686 -0.9652)
			)
			(stroke
				(width 0)
				(type default)
			)
			(fill no)
			(layer "F.CrtYd")
		)
		(fp_text user "2"
			(at 5.098542 0.323088 0)
			(unlocked yes)
			(layer "F.SilkS")
			(effects
				(font
					(size 0.7874 0.5842)
					(thickness 0.1524)
				)
				(justify left)
			)
		)
		(fp_text user "1"
			(at -0.565658 -0.819912 0)
			(unlocked yes)
			(layer "F.SilkS")
			(effects
				(font
					(size 0.7874 0.5842)
					(thickness 0.1524)
				)
				(justify left)
			)
		)
		(pad "1" smd rect
			(at 0 0 180)
			(size 1.016 1.8034)
			(layers "F.Cu" "F.Mask" "F.Paste")
			(net "P3V3_BLAD2")
		)
		(pad "2" smd rect
			(at 2.899918 0 180)
			(size 1.016 1.8034)
			(layers "F.Cu" "F.Mask" "F.Paste")
			(net "P3V3_10G_4_VCCT_L")
		)
	)
	(footprint ""
		(layer "F.Cu")
		(at 103.6828 -2.921 90)
		(property "Reference" "C23"
			(at -2.3622 -4.765548 90)
			(unlocked yes)
			(layer "F.SilkS")
			(effects
				(font
					(size 0.7874 0.5842)
					(thickness 0.1524)
				)
				(justify left)
			)
		)
		(property "Value" ""
			(at 0 0 90)
			(layer "F.Fab")
			(effects
				(font
					(size 1.27 1.27)
				)
			)
		)
		(duplicate_pad_numbers_are_jumpers no)
		(fp_line
			(start 0.7874 -0.4064)
			(end 0.7874 0.4064)
			(stroke
				(width 0.1524)
				(type default)
			)
			(layer "F.SilkS")
		)
		(fp_line
			(start -0.7874 -0.4064)
			(end 0.7874 -0.4064)
			(stroke
				(width 0.1524)
				(type default)
			)
			(layer "F.SilkS")
		)
		(fp_line
			(start 0 0.381)
			(end 0 -0.381)
			(stroke
				(width 0.1524)
				(type default)
			)
			(layer "F.SilkS")
		)
		(fp_line
			(start 0.7874 0.4064)
			(end -0.7874 0.4064)
			(stroke
				(width 0.1524)
				(type default)
			)
			(layer "F.SilkS")
		)
		(fp_line
			(start -0.7874 0.4064)
			(end -0.7874 -0.4064)
			(stroke
				(width 0.1524)
				(type default)
			)
			(layer "F.SilkS")
		)
		(fp_poly
			(pts
				(xy -0.5334 0.254) (xy -0.635 0.254) (xy -0.635 0.2286) (xy -0.635 -0.254) (xy -0.5334 -0.254) (xy -0.5334 -0.2794)
				(xy 0.5334 -0.2794) (xy 0.5334 -0.254) (xy 0.635 -0.254) (xy 0.635 0.254) (xy 0.5334 0.254) (xy 0.5334 0.2794)
				(xy -0.508 0.2794) (xy -0.5334 0.2794)
			)
			(stroke
				(width 0)
				(type default)
			)
			(fill no)
			(layer "F.CrtYd")
		)
		(pad "1" smd rect
			(at 0.40005 0 90)
			(size 0.4572 0.508)
			(layers "F.Cu" "F.Mask" "F.Paste")
			(net "P3V3_10G_2_VCCR")
		)
		(pad "2" smd rect
			(at -0.40005 0 90)
			(size 0.4572 0.508)
			(layers "F.Cu" "F.Mask" "F.Paste")
			(net "GND")
		)
	)
	(footprint ""
		(layer "F.Cu")
		(at 117.31244 -22.17801)
		(property "Reference" "R2"
			(at -61.341 5.115052 0)
			(unlocked yes)
			(layer "F.SilkS")
			(effects
				(font
					(size 0.7874 0.5842)
					(thickness 0.1524)
				)
				(justify left)
			)
		)
		(property "Value" ""
			(at 0 0 0)
			(layer "F.Fab")
			(effects
				(font
					(size 1.27 1.27)
				)
			)
		)
		(duplicate_pad_numbers_are_jumpers no)
		(fp_line
			(start -0.7874 -0.4064)
			(end 0.7874 -0.4064)
			(stroke
				(width 0.1524)
				(type default)
			)
			(layer "F.SilkS")
		)
		(fp_line
			(start -0.7874 0.4064)
			(end -0.7874 -0.4064)
			(stroke
				(width 0.1524)
				(type default)
			)
			(layer "F.SilkS")
		)
		(fp_line
			(start 0.7874 -0.4064)
			(end 0.7874 0.4064)
			(stroke
				(width 0.1524)
				(type default)
			)
			(layer "F.SilkS")
		)
		(fp_line
			(start 0.7874 0.4064)
			(end -0.7874 0.4064)
			(stroke
				(width 0.1524)
				(type default)
			)
			(layer "F.SilkS")
		)
		(fp_poly
			(pts
				(xy -0.508 0.2794) (xy -0.508 0.2286) (xy -0.635 0.2286) (xy -0.635 -0.254) (xy -0.5334 -0.254)
				(xy -0.5334 -0.2794) (xy 0.5334 -0.2794) (xy 0.5334 -0.254) (xy 0.635 -0.254) (xy 0.635 0.254) (xy 0.5334 0.254)
				(xy 0.5334 0.2794)
			)
			(stroke
				(width 0)
				(type default)
			)
			(fill no)
			(layer "F.CrtYd")
		)
		(pad "1" smd rect
			(at 0.40005 0)
			(size 0.4572 0.508)
			(layers "F.Cu" "F.Mask" "F.Paste")
			(net "P3V3_BLAD1")
		)
		(pad "2" smd rect
			(at -0.40005 0)
			(size 0.4572 0.508)
			(layers "F.Cu" "F.Mask" "F.Paste")
			(net "ENET10G_2_TX_FAULT")
		)
	)
	(footprint ""
		(layer "F.Cu")
		(at 155.091384 -40.288972)
		(property "Reference" "FS1"
			(at 35.25774 25.689052 0)
			(unlocked yes)
			(layer "F.SilkS")
			(effects
				(font
					(size 0.7874 0.5842)
					(thickness 0.1524)
				)
				(justify left)
			)
		)
		(property "Value" ""
			(at 0 0 0)
			(layer "F.Fab")
			(effects
				(font
					(size 1.27 1.27)
				)
			)
		)
		(duplicate_pad_numbers_are_jumpers no)
		(fp_line
			(start -0.650494 -1.050036)
			(end 3.550412 -1.050036)
			(stroke
				(width 0.1524)
				(type default)
			)
			(layer "F.SilkS")
		)
		(fp_line
			(start -0.650494 1.050036)
			(end -0.650494 -1.050036)
			(stroke
				(width 0.1524)
				(type default)
			)
			(layer "F.SilkS")
		)
		(fp_line
			(start 3.550412 -1.050036)
			(end 3.550412 1.050036)
			(stroke
				(width 0.1524)
				(type default)
			)
			(layer "F.SilkS")
		)
		(fp_line
			(start 3.550412 1.050036)
			(end -0.650494 1.050036)
			(stroke
				(width 0.1524)
				(type default)
			)
			(layer "F.SilkS")
		)
		(fp_poly
			(pts
				(xy 3.228086 -0.9652) (xy 3.228086 -1.100074) (xy -0.327914 -1.100074) (xy -0.327914 -0.9652) (xy -0.556514 -0.9652)
				(xy -0.556514 0.9652) (xy -0.327914 0.9652) (xy -0.327914 1.100074) (xy 3.228086 1.100074) (xy 3.228086 0.9652)
				(xy 3.456686 0.9652) (xy 3.456686 -0.9652)
			)
			(stroke
				(width 0)
				(type default)
			)
			(fill no)
			(layer "F.CrtYd")
		)
		(fp_text user "1"
			(at -1.051814 -1.615948 0)
			(unlocked yes)
			(layer "F.SilkS")
			(effects
				(font
					(size 0.7874 0.5842)
					(thickness 0.1524)
				)
				(justify left)
			)
		)
		(fp_text user "2"
			(at 2.986786 -1.793748 0)
			(unlocked yes)
			(layer "F.SilkS")
			(effects
				(font
					(size 0.7874 0.5842)
					(thickness 0.1524)
				)
				(justify left)
			)
		)
		(pad "1" smd rect
			(at 0 0)
			(size 1.016 1.8034)
			(layers "F.Cu" "F.Mask" "F.Paste")
			(net "P3V3_BLAD1")
		)
		(pad "2" smd rect
			(at 2.899918 0)
			(size 1.016 1.8034)
			(layers "F.Cu" "F.Mask" "F.Paste")
			(net "P3V3_10G_1_VCCT_L")
		)
	)
	(footprint ""
		(layer "F.Cu")
		(at 351.177352 -23.256494 180)
		(property "Reference" "R29"
			(at 58.908696 4.30276 0)
			(unlocked yes)
			(layer "F.SilkS")
			(effects
				(font
					(size 0.7874 0.5842)
					(thickness 0.1524)
				)
				(justify left)
			)
		)
		(property "Value" ""
			(at 0 0 180)
			(layer "F.Fab")
			(effects
				(font
					(size 1.27 1.27)
				)
			)
		)
		(duplicate_pad_numbers_are_jumpers no)
		(fp_line
			(start 0.7874 0.4064)
			(end -0.7874 0.4064)
			(stroke
				(width 0.1524)
				(type default)
			)
			(layer "F.SilkS")
		)
		(fp_line
			(start 0.7874 -0.4064)
			(end 0.7874 0.4064)
			(stroke
				(width 0.1524)
				(type default)
			)
			(layer "F.SilkS")
		)
		(fp_line
			(start -0.7874 0.4064)
			(end -0.7874 -0.4064)
			(stroke
				(width 0.1524)
				(type default)
			)
			(layer "F.SilkS")
		)
		(fp_line
			(start -0.7874 -0.4064)
			(end 0.7874 -0.4064)
			(stroke
				(width 0.1524)
				(type default)
			)
			(layer "F.SilkS")
		)
		(fp_poly
			(pts
				(xy -0.508 0.2794) (xy -0.508 0.2286) (xy -0.635 0.2286) (xy -0.635 -0.254) (xy -0.5334 -0.254)
				(xy -0.5334 -0.2794) (xy 0.5334 -0.2794) (xy 0.5334 -0.254) (xy 0.635 -0.254) (xy 0.635 0.254) (xy 0.5334 0.254)
				(xy 0.5334 0.2794)
			)
			(stroke
				(width 0)
				(type default)
			)
			(fill no)
			(layer "F.CrtYd")
		)
		(pad "1" smd rect
			(at 0.40005 0 180)
			(size 0.4572 0.508)
			(layers "F.Cu" "F.Mask" "F.Paste")
			(net "P3V3_BLAD2")
		)
		(pad "2" smd rect
			(at -0.40005 0 180)
			(size 0.4572 0.508)
			(layers "F.Cu" "F.Mask" "F.Paste")
			(net "ENET10G_3_LOS")
		)
	)
	(footprint ""
		(layer "F.Cu")
		(at 377.063 -32.094932 180)
		(property "Reference" "R81"
			(at -34.29 -19.258534 0)
			(unlocked yes)
			(layer "F.SilkS")
			(effects
				(font
					(size 0.7874 0.5842)
					(thickness 0.1524)
				)
				(justify left)
			)
		)
		(property "Value" ""
			(at 0 0 180)
			(layer "F.Fab")
			(effects
				(font
					(size 1.27 1.27)
				)
			)
		)
		(duplicate_pad_numbers_are_jumpers no)
		(fp_line
			(start 1.905 0.8636)
			(end -1.905 0.8636)
			(stroke
				(width 0.1524)
				(type default)
			)
			(layer "F.SilkS")
		)
		(fp_line
			(start 1.905 -0.8636)
			(end 1.905 0.8636)
			(stroke
				(width 0.1524)
				(type default)
			)
			(layer "F.SilkS")
		)
		(fp_line
			(start -1.905 0.8636)
			(end -1.905 -0.8636)
			(stroke
				(width 0.1524)
				(type default)
			)
			(layer "F.SilkS")
		)
		(fp_line
			(start -1.905 -0.8636)
			(end 1.905 -0.8636)
			(stroke
				(width 0.1524)
				(type default)
			)
			(layer "F.SilkS")
		)
		(fp_poly
			(pts
				(xy 1.524 0.6858) (xy 1.524 -0.6858) (xy 1.524 -0.7366) (xy -1.524 -0.7366) (xy -1.524 -0.6858)
				(xy -1.524 0.6858) (xy -1.524 0.7366) (xy 1.524 0.7366)
			)
			(stroke
				(width 0)
				(type default)
			)
			(fill no)
			(layer "F.CrtYd")
		)
		(pad "1" smd rect
			(at 0.94996 0 180)
			(size 1.1176 1.3716)
			(layers "F.Cu" "F.Mask" "F.Paste")
			(net "P3V3_BLAD2")
		)
		(pad "2" smd rect
			(at -0.94996 0 180)
			(size 1.1176 1.3716)
			(layers "F.Cu" "F.Mask" "F.Paste")
			(net "P3V3_10G_3_VCCR")
		)
	)
	(footprint ""
		(layer "F.Cu")
		(at 351.208848 -26.533094 180)
		(property "Reference" "R21"
			(at 58.940192 4.17576 0)
			(unlocked yes)
			(layer "F.SilkS")
			(effects
				(font
					(size 0.7874 0.5842)
					(thickness 0.1524)
				)
				(justify left)
			)
		)
		(property "Value" ""
			(at 0 0 180)
			(layer "F.Fab")
			(effects
				(font
					(size 1.27 1.27)
				)
			)
		)
		(duplicate_pad_numbers_are_jumpers no)
		(fp_line
			(start 0.7874 0.4064)
			(end -0.7874 0.4064)
			(stroke
				(width 0.1524)
				(type default)
			)
			(layer "F.SilkS")
		)
		(fp_line
			(start 0.7874 -0.4064)
			(end 0.7874 0.4064)
			(stroke
				(width 0.1524)
				(type default)
			)
			(layer "F.SilkS")
		)
		(fp_line
			(start -0.7874 0.4064)
			(end -0.7874 -0.4064)
			(stroke
				(width 0.1524)
				(type default)
			)
			(layer "F.SilkS")
		)
		(fp_line
			(start -0.7874 -0.4064)
			(end 0.7874 -0.4064)
			(stroke
				(width 0.1524)
				(type default)
			)
			(layer "F.SilkS")
		)
		(fp_poly
			(pts
				(xy -0.508 0.2794) (xy -0.508 0.2286) (xy -0.635 0.2286) (xy -0.635 -0.254) (xy -0.5334 -0.254)
				(xy -0.5334 -0.2794) (xy 0.5334 -0.2794) (xy 0.5334 -0.254) (xy 0.635 -0.254) (xy 0.635 0.254) (xy 0.5334 0.254)
				(xy 0.5334 0.2794)
			)
			(stroke
				(width 0)
				(type default)
			)
			(fill no)
			(layer "F.CrtYd")
		)
		(pad "1" smd rect
			(at 0.40005 0 180)
			(size 0.4572 0.508)
			(layers "F.Cu" "F.Mask" "F.Paste")
			(net "P3V3_BLAD2")
		)
		(pad "2" smd rect
			(at -0.40005 0 180)
			(size 0.4572 0.508)
			(layers "F.Cu" "F.Mask" "F.Paste")
			(net "ENET10G_3_SDA")
		)
	)
	(footprint ""
		(layer "F.Cu")
		(at 346.521532 -21.657818 90)
		(property "Reference" "R64"
			(at 3.3528 -57.038748 90)
			(unlocked yes)
			(layer "F.SilkS")
			(effects
				(font
					(size 0.7874 0.5842)
					(thickness 0.1524)
				)
				(justify left)
			)
		)
		(property "Value" ""
			(at 0 0 90)
			(layer "F.Fab")
			(effects
				(font
					(size 1.27 1.27)
				)
			)
		)
		(duplicate_pad_numbers_are_jumpers no)
		(fp_line
			(start 0.7874 -0.4064)
			(end 0.7874 0.4064)
			(stroke
				(width 0.1524)
				(type default)
			)
			(layer "F.SilkS")
		)
		(fp_line
			(start -0.7874 -0.4064)
			(end 0.7874 -0.4064)
			(stroke
				(width 0.1524)
				(type default)
			)
			(layer "F.SilkS")
		)
		(fp_line
			(start 0.7874 0.4064)
			(end -0.7874 0.4064)
			(stroke
				(width 0.1524)
				(type default)
			)
			(layer "F.SilkS")
		)
		(fp_line
			(start -0.7874 0.4064)
			(end -0.7874 -0.4064)
			(stroke
				(width 0.1524)
				(type default)
			)
			(layer "F.SilkS")
		)
		(fp_poly
			(pts
				(xy -0.508 0.2794) (xy -0.508 0.2286) (xy -0.635 0.2286) (xy -0.635 -0.254) (xy -0.5334 -0.254)
				(xy -0.5334 -0.2794) (xy 0.5334 -0.2794) (xy 0.5334 -0.254) (xy 0.635 -0.254) (xy 0.635 0.254) (xy 0.5334 0.254)
				(xy 0.5334 0.2794)
			)
			(stroke
				(width 0)
				(type default)
			)
			(fill no)
			(layer "F.CrtYd")
		)
		(pad "1" smd rect
			(at 0.40005 0 90)
			(size 0.4572 0.508)
			(layers "F.Cu" "F.Mask" "F.Paste")
			(net "GND")
		)
		(pad "2" smd rect
			(at -0.40005 0 90)
			(size 0.4572 0.508)
			(layers "F.Cu" "F.Mask" "F.Paste")
			(net "SKU_PIN_BLAD2_1")
		)
	)
	(footprint ""
		(layer "F.Cu")
		(at 146.3294 -3.048 90)
		(property "Reference" "C17"
			(at -2.2606 -8.143748 90)
			(unlocked yes)
			(layer "F.SilkS")
			(effects
				(font
					(size 0.7874 0.5842)
					(thickness 0.1524)
				)
				(justify left)
			)
		)
		(property "Value" ""
			(at 0 0 90)
			(layer "F.Fab")
			(effects
				(font
					(size 1.27 1.27)
				)
			)
		)
		(duplicate_pad_numbers_are_jumpers no)
		(fp_line
			(start 0.7874 -0.4064)
			(end 0.7874 0.4064)
			(stroke
				(width 0.1524)
				(type default)
			)
			(layer "F.SilkS")
		)
		(fp_line
			(start -0.7874 -0.4064)
			(end 0.7874 -0.4064)
			(stroke
				(width 0.1524)
				(type default)
			)
			(layer "F.SilkS")
		)
		(fp_line
			(start 0 0.381)
			(end 0 -0.381)
			(stroke
				(width 0.1524)
				(type default)
			)
			(layer "F.SilkS")
		)
		(fp_line
			(start 0.7874 0.4064)
			(end -0.7874 0.4064)
			(stroke
				(width 0.1524)
				(type default)
			)
			(layer "F.SilkS")
		)
		(fp_line
			(start -0.7874 0.4064)
			(end -0.7874 -0.4064)
			(stroke
				(width 0.1524)
				(type default)
			)
			(layer "F.SilkS")
		)
		(fp_poly
			(pts
				(xy -0.5334 0.254) (xy -0.635 0.254) (xy -0.635 0.2286) (xy -0.635 -0.254) (xy -0.5334 -0.254) (xy -0.5334 -0.2794)
				(xy 0.5334 -0.2794) (xy 0.5334 -0.254) (xy 0.635 -0.254) (xy 0.635 0.254) (xy 0.5334 0.254) (xy 0.5334 0.2794)
				(xy -0.508 0.2794) (xy -0.5334 0.2794)
			)
			(stroke
				(width 0)
				(type default)
			)
			(fill no)
			(layer "F.CrtYd")
		)
		(pad "1" smd rect
			(at 0.40005 0 90)
			(size 0.4572 0.508)
			(layers "F.Cu" "F.Mask" "F.Paste")
			(net "P3V3_10G_1_VCCT")
		)
		(pad "2" smd rect
			(at -0.40005 0 90)
			(size 0.4572 0.508)
			(layers "F.Cu" "F.Mask" "F.Paste")
			(net "GND")
		)
	)
	(footprint ""
		(layer "F.Cu")
		(at 312.1406 -34.173668)
		(property "Reference" "R82"
			(at -1.3716 -8.05053 0)
			(unlocked yes)
			(layer "F.SilkS")
			(effects
				(font
					(size 0.7874 0.5842)
					(thickness 0.1524)
				)
				(justify left)
			)
		)
		(property "Value" ""
			(at 0 0 0)
			(layer "F.Fab")
			(effects
				(font
					(size 1.27 1.27)
				)
			)
		)
		(duplicate_pad_numbers_are_jumpers no)
		(fp_line
			(start -1.905 -0.8636)
			(end 1.905 -0.8636)
			(stroke
				(width 0.1524)
				(type default)
			)
			(layer "F.SilkS")
		)
		(fp_line
			(start -1.905 0.8636)
			(end -1.905 -0.8636)
			(stroke
				(width 0.1524)
				(type default)
			)
			(layer "F.SilkS")
		)
		(fp_line
			(start 1.905 -0.8636)
			(end 1.905 0.8636)
			(stroke
				(width 0.1524)
				(type default)
			)
			(layer "F.SilkS")
		)
		(fp_line
			(start 1.905 0.8636)
			(end -1.905 0.8636)
			(stroke
				(width 0.1524)
				(type default)
			)
			(layer "F.SilkS")
		)
		(fp_poly
			(pts
				(xy 1.524 0.6858) (xy 1.524 -0.6858) (xy 1.524 -0.7366) (xy -1.524 -0.7366) (xy -1.524 -0.6858)
				(xy -1.524 0.6858) (xy -1.524 0.7366) (xy 1.524 0.7366)
			)
			(stroke
				(width 0)
				(type default)
			)
			(fill no)
			(layer "F.CrtYd")
		)
		(pad "1" smd rect
			(at 0.94996 0)
			(size 1.1176 1.3716)
			(layers "F.Cu" "F.Mask" "F.Paste")
			(net "P3V3_BLAD2")
		)
		(pad "2" smd rect
			(at -0.94996 0)
			(size 1.1176 1.3716)
			(layers "F.Cu" "F.Mask" "F.Paste")
			(net "P3V3_10G_4_VCCT")
		)
	)
	(footprint ""
		(layer "F.Cu")
		(at 338.127848 -21.803106)
		(property "Reference" "R22"
			(at -58.3438 -4.587748 0)
			(unlocked yes)
			(layer "F.SilkS")
			(effects
				(font
					(size 0.7874 0.5842)
					(thickness 0.1524)
				)
				(justify left)
			)
		)
		(property "Value" ""
			(at 0 0 0)
			(layer "F.Fab")
			(effects
				(font
					(size 1.27 1.27)
				)
			)
		)
		(duplicate_pad_numbers_are_jumpers no)
		(fp_line
			(start -0.7874 -0.4064)
			(end 0.7874 -0.4064)
			(stroke
				(width 0.1524)
				(type default)
			)
			(layer "F.SilkS")
		)
		(fp_line
			(start -0.7874 0.4064)
			(end -0.7874 -0.4064)
			(stroke
				(width 0.1524)
				(type default)
			)
			(layer "F.SilkS")
		)
		(fp_line
			(start 0.7874 -0.4064)
			(end 0.7874 0.4064)
			(stroke
				(width 0.1524)
				(type default)
			)
			(layer "F.SilkS")
		)
		(fp_line
			(start 0.7874 0.4064)
			(end -0.7874 0.4064)
			(stroke
				(width 0.1524)
				(type default)
			)
			(layer "F.SilkS")
		)
		(fp_poly
			(pts
				(xy -0.508 0.2794) (xy -0.508 0.2286) (xy -0.635 0.2286) (xy -0.635 -0.254) (xy -0.5334 -0.254)
				(xy -0.5334 -0.2794) (xy 0.5334 -0.2794) (xy 0.5334 -0.254) (xy 0.635 -0.254) (xy 0.635 0.254) (xy 0.5334 0.254)
				(xy 0.5334 0.2794)
			)
			(stroke
				(width 0)
				(type default)
			)
			(fill no)
			(layer "F.CrtYd")
		)
		(pad "1" smd rect
			(at 0.40005 0)
			(size 0.4572 0.508)
			(layers "F.Cu" "F.Mask" "F.Paste")
			(net "P3V3_BLAD2")
		)
		(pad "2" smd rect
			(at -0.40005 0)
			(size 0.4572 0.508)
			(layers "F.Cu" "F.Mask" "F.Paste")
			(net "ENET10G_4_SDA")
		)
	)
	(footprint ""
		(layer "F.Cu")
		(at 8.570214 -49.30013 180)
		(property "Reference" "J19"
			(at -19.65198 -7.666736 0)
			(unlocked yes)
			(layer "F.SilkS")
			(effects
				(font
					(size 0.7874 0.5842)
					(thickness 0.1524)
				)
				(justify left)
			)
		)
		(property "Value" ""
			(at 0 0 180)
			(layer "F.Fab")
			(effects
				(font
					(size 1.27 1.27)
				)
			)
		)
		(duplicate_pad_numbers_are_jumpers no)
		(fp_line
			(start 7.869936 2.500122)
			(end 6.370066 3.999992)
			(stroke
				(width 0.1524)
				(type default)
			)
			(layer "F.SilkS")
		)
		(fp_line
			(start 7.869936 -5.299964)
			(end 7.869936 2.500122)
			(stroke
				(width 0.1524)
				(type default)
			)
			(layer "F.SilkS")
		)
		(fp_line
			(start 6.370066 3.999992)
			(end -0.379984 3.999992)
			(stroke
				(width 0.1524)
				(type default)
			)
			(layer "F.SilkS")
		)
		(fp_line
			(start -0.379984 3.999992)
			(end -1.880108 2.500122)
			(stroke
				(width 0.1524)
				(type default)
			)
			(layer "F.SilkS")
		)
		(fp_line
			(start -1.764792 -6.850888)
			(end 7.869936 -6.850888)
			(stroke
				(width 0.1524)
				(type default)
			)
			(layer "F.SilkS")
		)
		(fp_line
			(start -1.880108 2.500122)
			(end -1.880108 -6.649974)
			(stroke
				(width 0.1524)
				(type default)
			)
			(layer "F.SilkS")
		)
		(fp_line
			(start -2.579878 -6.649974)
			(end -2.579878 -3.9624)
			(stroke
				(width 0.1524)
				(type default)
			)
			(layer "F.SilkS")
		)
		(fp_line
			(start -2.770378 2.690622)
			(end -4.080002 3.999992)
			(stroke
				(width 0.1524)
				(type default)
			)
			(layer "F.SilkS")
		)
		(fp_line
			(start -4.080002 3.999992)
			(end -42.7101 3.999992)
			(stroke
				(width 0.1524)
				(type default)
			)
			(layer "F.SilkS")
		)
		(fp_line
			(start -42.7101 3.999992)
			(end -44.20997 2.500122)
			(stroke
				(width 0.1524)
				(type default)
			)
			(layer "F.SilkS")
		)
		(fp_line
			(start -44.20997 2.500122)
			(end -44.20997 -5.299964)
			(stroke
				(width 0.1524)
				(type default)
			)
			(layer "F.SilkS")
		)
		(fp_line
			(start -44.20997 -6.850888)
			(end -2.704592 -6.850888)
			(stroke
				(width 0.1524)
				(type default)
			)
			(layer "F.SilkS")
		)
		(fp_arc
			(start -2.23012 -6.999986)
			(mid -1.98262 -6.897472)
			(end -1.880108 -6.649974)
			(stroke
				(width 0.1524)
				(type default)
			)
			(layer "F.SilkS")
		)
		(fp_arc
			(start -2.579878 -6.649974)
			(mid -2.477435 -6.897345)
			(end -2.23012 -6.999986)
			(stroke
				(width 0.1524)
				(type default)
			)
			(layer "F.SilkS")
		)
		(fp_line
			(start 7.869936 2.500122)
			(end 6.370066 3.999992)
			(stroke
				(width 0.1524)
				(type default)
			)
			(layer "B.SilkS")
		)
		(fp_line
			(start 7.869936 -5.299964)
			(end 7.869936 2.500122)
			(stroke
				(width 0.1524)
				(type default)
			)
			(layer "B.SilkS")
		)
		(fp_line
			(start 6.370066 3.999992)
			(end -0.379984 3.999992)
			(stroke
				(width 0.1524)
				(type default)
			)
			(layer "B.SilkS")
		)
		(fp_line
			(start -0.379984 3.999992)
			(end -1.880108 2.500122)
			(stroke
				(width 0.1524)
				(type default)
			)
			(layer "B.SilkS")
		)
		(fp_line
			(start -1.764792 -6.850888)
			(end 7.869936 -6.850888)
			(stroke
				(width 0.1524)
				(type default)
			)
			(layer "B.SilkS")
		)
		(fp_line
			(start -1.880108 2.500122)
			(end -1.880108 -6.649974)
			(stroke
				(width 0.1524)
				(type default)
			)
			(layer "B.SilkS")
		)
		(fp_line
			(start -2.579878 -6.649974)
			(end -2.579878 -4.0132)
			(stroke
				(width 0.1524)
				(type default)
			)
			(layer "B.SilkS")
		)
		(fp_line
			(start -2.770378 2.690622)
			(end -4.080002 3.999992)
			(stroke
				(width 0.1524)
				(type default)
			)
			(layer "B.SilkS")
		)
		(fp_line
			(start -4.080002 3.999992)
			(end -42.7101 3.999992)
			(stroke
				(width 0.1524)
				(type default)
			)
			(layer "B.SilkS")
		)
		(fp_line
			(start -42.7101 3.999992)
			(end -44.20997 2.500122)
			(stroke
				(width 0.1524)
				(type default)
			)
			(layer "B.SilkS")
		)
		(fp_line
			(start -44.20997 2.500122)
			(end -44.20997 -5.299964)
			(stroke
				(width 0.1524)
				(type default)
			)
			(layer "B.SilkS")
		)
		(fp_line
			(start -44.20997 -6.850888)
			(end -2.704592 -6.850888)
			(stroke
				(width 0.1524)
				(type default)
			)
			(layer "B.SilkS")
		)
		(fp_arc
			(start -2.23012 -6.999986)
			(mid -1.98262 -6.897472)
			(end -1.880108 -6.649974)
			(stroke
				(width 0.1524)
				(type default)
			)
			(layer "B.SilkS")
		)
		(fp_arc
			(start -2.579878 -6.649974)
			(mid -2.477435 -6.897345)
			(end -2.23012 -6.999986)
			(stroke
				(width 0.1524)
				(type default)
			)
			(layer "B.SilkS")
		)
		(fp_poly
			(pts
				(xy -44.204382 3.999992) (xy 7.865618 3.999992) (xy 7.865618 -6.850888) (xy -1.942592 -6.850888)
				(xy -1.942592 -7.0104) (xy -2.539492 -7.0104) (xy -2.539492 -6.850888) (xy -44.204382 -6.850888)
			)
			(stroke
				(width 0)
				(type default)
			)
			(fill no)
			(layer "B.CrtYd")
		)
		(fp_poly
			(pts
				(xy -44.204382 3.999992) (xy 7.865618 3.999992) (xy 7.865618 -6.850888) (xy -1.942592 -6.850888)
				(xy -1.942592 -7.0104) (xy -2.539492 -7.0104) (xy -2.539492 -6.850888) (xy -44.204382 -6.850888)
			)
			(stroke
				(width 0)
				(type default)
			)
			(fill no)
			(layer "F.CrtYd")
		)
		(fp_line
			(start 7.869936 2.500122)
			(end 6.370066 3.999992)
			(stroke
				(width 0.1)
				(type default)
			)
			(layer "B.Fab")
		)
		(fp_line
			(start 7.869936 -5.299964)
			(end 7.869936 2.500122)
			(stroke
				(width 0.1)
				(type default)
			)
			(layer "B.Fab")
		)
		(fp_line
			(start 6.370066 3.999992)
			(end -0.379984 3.999992)
			(stroke
				(width 0.1)
				(type default)
			)
			(layer "B.Fab")
		)
		(fp_line
			(start -0.379984 3.999992)
			(end -1.880108 2.500122)
			(stroke
				(width 0.1)
				(type default)
			)
			(layer "B.Fab")
		)
		(fp_line
			(start -1.764792 -6.850888)
			(end 7.869936 -6.850888)
			(stroke
				(width 0.1)
				(type default)
			)
			(layer "B.Fab")
		)
		(fp_line
			(start -1.880108 2.500122)
			(end -1.880108 -6.649974)
			(stroke
				(width 0.1)
				(type default)
			)
			(layer "B.Fab")
		)
		(fp_line
			(start -2.579878 2.500122)
			(end -4.080002 3.999992)
			(stroke
				(width 0.1)
				(type default)
			)
			(layer "B.Fab")
		)
		(fp_line
			(start -2.579878 -6.649974)
			(end -2.579878 2.500122)
			(stroke
				(width 0.1)
				(type default)
			)
			(layer "B.Fab")
		)
		(fp_line
			(start -4.080002 3.999992)
			(end -42.7101 3.999992)
			(stroke
				(width 0.1)
				(type default)
			)
			(layer "B.Fab")
		)
		(fp_line
			(start -42.7101 3.999992)
			(end -44.20997 2.500122)
			(stroke
				(width 0.1)
				(type default)
			)
			(layer "B.Fab")
		)
		(fp_line
			(start -44.20997 2.500122)
			(end -44.20997 -5.299964)
			(stroke
				(width 0.1)
				(type default)
			)
			(layer "B.Fab")
		)
		(fp_line
			(start -44.20997 -6.850888)
			(end -2.704592 -6.850888)
			(stroke
				(width 0.1)
				(type default)
			)
			(layer "B.Fab")
		)
		(fp_arc
			(start -2.23012 -6.999986)
			(mid -1.98262 -6.897472)
			(end -1.880108 -6.649974)
			(stroke
				(width 0.1)
				(type default)
			)
			(layer "B.Fab")
		)
		(fp_arc
			(start -2.579878 -6.649974)
			(mid -2.477435 -6.897345)
			(end -2.23012 -6.999986)
			(stroke
				(width 0.1)
				(type default)
			)
			(layer "B.Fab")
		)
		(fp_line
			(start 7.869936 2.500122)
			(end 6.370066 3.999992)
			(stroke
				(width 0.1)
				(type default)
			)
			(layer "F.Fab")
		)
		(fp_line
			(start 7.869936 -5.299964)
			(end 7.869936 2.500122)
			(stroke
				(width 0.1)
				(type default)
			)
			(layer "F.Fab")
		)
		(fp_line
			(start 6.370066 3.999992)
			(end -0.379984 3.999992)
			(stroke
				(width 0.1)
				(type default)
			)
			(layer "F.Fab")
		)
		(fp_line
			(start -0.379984 3.999992)
			(end -1.880108 2.500122)
			(stroke
				(width 0.1)
				(type default)
			)
			(layer "F.Fab")
		)
		(fp_line
			(start -1.764792 -6.850888)
			(end 7.869936 -6.850888)
			(stroke
				(width 0.1)
				(type default)
			)
			(layer "F.Fab")
		)
		(fp_line
			(start -1.880108 2.500122)
			(end -1.880108 -6.649974)
			(stroke
				(width 0.1)
				(type default)
			)
			(layer "F.Fab")
		)
		(fp_line
			(start -2.579878 2.500122)
			(end -4.080002 3.999992)
			(stroke
				(width 0.1)
				(type default)
			)
			(layer "F.Fab")
		)
		(fp_line
			(start -2.579878 -6.649974)
			(end -2.579878 2.500122)
			(stroke
				(width 0.1)
				(type default)
			)
			(layer "F.Fab")
		)
		(fp_line
			(start -4.080002 3.999992)
			(end -42.7101 3.999992)
			(stroke
				(width 0.1)
				(type default)
			)
			(layer "F.Fab")
		)
		(fp_line
			(start -42.7101 3.999992)
			(end -44.20997 2.500122)
			(stroke
				(width 0.1)
				(type default)
			)
			(layer "F.Fab")
		)
		(fp_line
			(start -44.20997 2.500122)
			(end -44.20997 -5.299964)
			(stroke
				(width 0.1)
				(type default)
			)
			(layer "F.Fab")
		)
		(fp_line
			(start -44.20997 -6.850888)
			(end -2.704592 -6.850888)
			(stroke
				(width 0.1)
				(type default)
			)
			(layer "F.Fab")
		)
		(fp_arc
			(start -2.23012 -6.999986)
			(mid -1.98262 -6.897472)
			(end -1.880108 -6.649974)
			(stroke
				(width 0.1)
				(type default)
			)
			(layer "F.Fab")
		)
		(fp_arc
			(start -2.579878 -6.649974)
			(mid -2.477435 -6.897345)
			(end -2.23012 -6.999986)
			(stroke
				(width 0.1)
				(type default)
			)
			(layer "F.Fab")
		)
		(fp_text user "S6"
			(at 7.735316 -7.92099 0)
			(unlocked yes)
			(layer "F.SilkS")
			(effects
				(font
					(size 0.7874 0.5842)
					(thickness 0.1524)
				)
				(justify left)
			)
		)
		(fp_text user "S1"
			(at 0.41021 -7.76859 0)
			(unlocked yes)
			(layer "F.SilkS")
			(effects
				(font
					(size 0.7874 0.5842)
					(thickness 0.1524)
				)
				(justify left)
			)
		)
		(fp_text user "P4"
			(at -5.83819 -8.415528 0)
			(unlocked yes)
			(layer "F.SilkS")
			(effects
				(font
					(size 0.7874 0.5842)
					(thickness 0.1524)
				)
				(justify left)
			)
		)
		(fp_text user "P1"
			(at -37.393372 -8.592312 0)
			(unlocked yes)
			(layer "F.SilkS")
			(effects
				(font
					(size 0.7874 0.5842)
					(thickness 0.1524)
				)
				(justify left)
			)
		)
		(fp_text user "S7"
			(at 6.56844 -7.71779 0)
			(unlocked yes)
			(layer "B.SilkS")
			(effects
				(font
					(size 0.7874 0.5842)
					(thickness 0.1524)
				)
				(justify left mirror)
			)
		)
		(fp_text user "S12"
			(at -1.53289 -7.66699 0)
			(unlocked yes)
			(layer "B.SilkS")
			(effects
				(font
					(size 0.7874 0.5842)
					(thickness 0.1524)
				)
				(justify left mirror)
			)
		)
		(fp_text user "P5"
			(at -7.20979 -8.161528 0)
			(unlocked yes)
			(layer "B.SilkS")
			(effects
				(font
					(size 0.7874 0.5842)
					(thickness 0.1524)
				)
				(justify left mirror)
			)
		)
		(fp_text user "P8"
			(at -39.552372 -8.566912 0)
			(unlocked yes)
			(layer "B.SilkS")
			(effects
				(font
					(size 0.7874 0.5842)
					(thickness 0.1524)
				)
				(justify left mirror)
			)
		)
		(fp_text user "S7"
			(at 6.939788 -6.09727 180)
			(unlocked yes)
			(layer "B.Fab")
			(effects
				(font
					(size 0.7874 0.5842)
					(thickness 0.000001)
				)
				(justify left mirror)
			)
		)
		(fp_text user "S12"
			(at 0.893318 -6.09727 180)
			(unlocked yes)
			(layer "B.Fab")
			(effects
				(font
					(size 0.7874 0.5842)
					(thickness 0.000001)
				)
				(justify left mirror)
			)
		)
		(fp_text user "P5"
			(at -6.586982 -6.059932 180)
			(unlocked yes)
			(layer "B.Fab")
			(effects
				(font
					(size 0.7874 0.5842)
					(thickness 0.000001)
				)
				(justify left mirror)
			)
		)
		(fp_text user "P8"
			(at -37.338 -6.010148 180)
			(unlocked yes)
			(layer "B.Fab")
			(effects
				(font
					(size 0.7874 0.5842)
					(thickness 0.000001)
				)
				(justify left mirror)
			)
		)
		(fp_text user "S6"
			(at 5.442712 -6.14807 180)
			(unlocked yes)
			(layer "F.Fab")
			(effects
				(font
					(size 0.7874 0.5842)
					(thickness 0.000001)
				)
				(justify left)
			)
		)
		(fp_text user "S1"
			(at -0.668782 -6.14807 180)
			(unlocked yes)
			(layer "F.Fab")
			(effects
				(font
					(size 0.7874 0.5842)
					(thickness 0.000001)
				)
				(justify left)
			)
		)
		(fp_text user "P4"
			(at -8.110982 -6.110732 180)
			(unlocked yes)
			(layer "F.Fab")
			(effects
				(font
					(size 0.7874 0.5842)
					(thickness 0.000001)
				)
				(justify left)
			)
		)
		(fp_text user "P1"
			(at -38.5318 -6.060948 180)
			(unlocked yes)
			(layer "F.Fab")
			(effects
				(font
					(size 0.7874 0.5842)
					(thickness 0.000001)
				)
				(justify left)
			)
		)
		(pad "P1" smd rect
			(at -37.79012 -0.649986 90)
			(size 6.2992 9.4742)
			(layers "F.Cu" "F.Mask" "F.Paste")
			(net "GND")
		)
		(pad "P2" smd rect
			(at -27.63012 -0.649986 90)
			(size 6.2992 9.4742)
			(layers "F.Cu" "F.Mask" "F.Paste")
			(net "GND")
		)
		(pad "P3" smd rect
			(at -17.47012 -0.649986 90)
			(size 6.2992 9.4742)
			(layers "F.Cu" "F.Mask" "F.Paste")
			(net "P12V")
		)
		(pad "P4" smd rect
			(at -7.31012 -0.649986 90)
			(size 6.2992 9.4742)
			(layers "F.Cu" "F.Mask" "F.Paste")
			(net "P12V")
		)
		(pad "P5" smd rect
			(at -7.31012 -0.649986 90)
			(size 6.2992 9.4742)
			(layers "F.Cu" "F.Mask" "F.Paste")
			(net "P12V")
		)
		(pad "P6" smd rect
			(at -17.47012 -0.649986 90)
			(size 6.2992 9.4742)
			(layers "F.Cu" "F.Mask" "F.Paste")
			(net "P12V")
		)
		(pad "P7" smd rect
			(at -27.63012 -0.649986 90)
			(size 6.2992 9.4742)
			(layers "F.Cu" "F.Mask" "F.Paste")
			(net "GND")
		)
		(pad "P8" smd rect
			(at -37.79012 -0.649986 90)
			(size 6.2992 9.4742)
			(layers "F.Cu" "F.Mask" "F.Paste")
			(net "GND")
		)
		(pad "S1" smd rect
			(at 0 0 180)
			(size 0.8128 5.0038)
			(layers "F.Cu" "F.Mask" "F.Paste")
			(net "NODE1_TXD")
		)
		(pad "S2" smd rect
			(at 1.27 0 180)
			(size 0.8128 5.0038)
			(layers "F.Cu" "F.Mask" "F.Paste")
			(net "NODE1_RXD")
		)
		(pad "S3" smd rect
			(at 2.54 0 180)
			(size 0.8128 5.0038)
			(layers "F.Cu" "F.Mask" "F.Paste")
			(net "NODE1_EN")
		)
		(pad "S4" smd rect
			(at 3.81 0 180)
			(size 0.8128 5.0038)
			(layers "F.Cu" "F.Mask" "F.Paste")
			(net "NODE2_EN")
		)
		(pad "S5" smd rect
			(at 5.08 0 180)
			(size 0.8128 5.0038)
			(layers "F.Cu" "F.Mask" "F.Paste")
			(net "NODE2_TXD")
		)
		(pad "S6" smd rect
			(at 6.35 0 180)
			(size 0.8128 5.0038)
			(layers "F.Cu" "F.Mask" "F.Paste")
			(net "NODE2_RXD")
		)
		(pad "S7" smd rect
			(at 6.35 0 180)
			(size 0.8128 5.0038)
			(layers "F.Cu" "F.Mask" "F.Paste")
			(net "NODE4_RXD")
		)
		(pad "S8" smd rect
			(at 5.08 0 180)
			(size 0.8128 5.0038)
			(layers "F.Cu" "F.Mask" "F.Paste")
			(net "NODE4_TXD")
		)
		(pad "S9" smd rect
			(at 3.81 0 180)
			(size 0.8128 5.0038)
			(layers "F.Cu" "F.Mask" "F.Paste")
			(net "NODE4_EN")
		)
		(pad "S10" smd rect
			(at 2.54 0 180)
			(size 0.8128 5.0038)
			(layers "F.Cu" "F.Mask" "F.Paste")
			(net "NODE3_EN")
		)
		(pad "S11" smd rect
			(at 1.27 0 180)
			(size 0.8128 5.0038)
			(layers "F.Cu" "F.Mask" "F.Paste")
			(net "NODE3_RXD")
		)
		(pad "S12" smd rect
			(at 0 0 180)
			(size 0.8128 5.0038)
			(layers "F.Cu" "F.Mask" "F.Paste")
			(net "NODE3_TXD")
		)
		(zone
			(layers "F.Cu" "B.Cu" "In1.Cu" "In2.Cu" "In3.Cu" "In4.Cu" "In5.Cu" "In6.Cu")
			(hatch none 0.5)
			(connect_pads
				(clearance 0)
			)
			(min_thickness 0.25)
			(keepout
				(tracks allowed)
				(vias not_allowed)
				(pads allowed)
				(copperpour not_allowed)
				(footprints allowed)
			)
			(placement
				(enabled no)
				(sheetname "")
			)
			(fill
				(thermal_gap 0.5)
				(thermal_bridge_width 0.5)
				(island_removal_mode 0)
			)
			(polygon
				(pts
					(xy 9.049004 -45.467524) (xy 9.049004 -51.868324) (xy 1.759204 -51.868324) (xy 1.759204 -45.467524)
				)
			)
		)
		(zone
			(layers "F.Cu" "B.Cu" "In1.Cu" "In2.Cu" "In3.Cu" "In4.Cu" "In5.Cu" "In6.Cu")
			(hatch none 0.5)
			(connect_pads
				(clearance 0)
			)
			(min_thickness 0.25)
			(keepout
				(tracks allowed)
				(vias not_allowed)
				(pads allowed)
				(copperpour not_allowed)
				(footprints allowed)
			)
			(placement
				(enabled no)
				(sheetname "")
			)
			(fill
				(thermal_gap 0.5)
				(thermal_bridge_width 0.5)
				(island_removal_mode 0)
			)
			(polygon
				(pts
					(xy 51.166014 -51.86553) (xy 11.084814 -51.86553) (xy 11.084814 -44.169838) (xy 51.166014 -44.169838)
				)
			)
		)
		(zone
			(layers "F.Cu" "B.Cu" "In1.Cu" "In2.Cu" "In3.Cu" "In4.Cu" "In5.Cu" "In6.Cu")
			(hatch none 0.5)
			(connect_pads
				(clearance 0)
			)
			(min_thickness 0.25)
			(keepout
				(tracks not_allowed)
				(vias allowed)
				(pads allowed)
				(copperpour not_allowed)
				(footprints allowed)
			)
			(placement
				(enabled no)
				(sheetname "")
			)
			(fill
				(thermal_gap 0.5)
				(thermal_bridge_width 0.5)
				(island_removal_mode 0)
			)
			(polygon
				(pts
					(xy 51.269392 -53.300122) (xy 52.780184 -51.78933) (xy 52.780184 -45.449744) (xy 51.162966 -45.449744)
					(xy 51.162966 -51.86553) (xy 41.551606 -51.86553) (xy 41.551606 -45.449744) (xy 41.002966 -45.449744)
					(xy 41.002966 -51.86553) (xy 31.391606 -51.86553) (xy 31.391606 -45.449744) (xy 30.842966 -45.449744)
					(xy 30.842966 -51.863244) (xy 21.429726 -51.863244) (xy 21.427186 -51.86553) (xy 21.231606 -51.86553)
					(xy 21.231606 -45.449744) (xy 20.685506 -45.449744) (xy 20.685506 -51.863244) (xy 11.269726 -51.863244)
					(xy 11.269726 -51.86553) (xy 11.200892 -51.86553) (xy 12.635738 -53.300122)
				)
			)
		)
		(zone
			(layers "F.Cu" "B.Cu" "In1.Cu" "In2.Cu" "In3.Cu" "In4.Cu" "In5.Cu" "In6.Cu")
			(hatch none 0.5)
			(connect_pads
				(clearance 0)
			)
			(min_thickness 0.25)
			(keepout
				(tracks not_allowed)
				(vias allowed)
				(pads allowed)
				(copperpour not_allowed)
				(footprints allowed)
			)
			(placement
				(enabled no)
				(sheetname "")
			)
			(fill
				(thermal_gap 0.5)
				(thermal_bridge_width 0.5)
				(island_removal_mode 0)
			)
			(polygon
				(pts
					(xy 8.93953 -53.300122) (xy 10.450322 -51.78933) (xy 10.450322 -46.74743) (xy 9.040114 -46.74743)
					(xy 9.040114 -51.86553) (xy 8.100314 -51.86553) (xy 8.100314 -46.74743) (xy 7.770114 -46.74743)
					(xy 7.770114 -51.86553) (xy 6.830314 -51.86553) (xy 6.830314 -46.74743) (xy 6.500114 -46.74743)
					(xy 6.500114 -51.86553) (xy 5.560314 -51.86553) (xy 5.560314 -46.74743) (xy 5.230114 -46.74743)
					(xy 5.230114 -51.86553) (xy 4.290314 -51.86553) (xy 4.290314 -46.74743) (xy 3.960114 -46.74743)
					(xy 3.960114 -51.86553) (xy 3.020314 -51.86553) (xy 3.020314 -46.74743) (xy 2.690114 -46.74743)
					(xy 2.690114 -51.86553) (xy 1.750314 -51.86553) (xy 1.750314 -46.74743) (xy 0.700278 -46.74743)
					(xy 0.700278 -51.78933) (xy 2.21107 -53.300122)
				)
			)
		)
	)
	(footprint ""
		(layer "F.Cu")
		(at 300.810168 -41.500044 180)
		(property "Reference" "H6"
			(at -0.156464 -5.33654 0)
			(unlocked yes)
			(layer "F.SilkS")
			(effects
				(font
					(size 0.7874 0.5842)
					(thickness 0.1524)
				)
				(justify left)
			)
		)
		(property "Value" ""
			(at 0 0 180)
			(layer "F.Fab")
			(effects
				(font
					(size 1.27 1.27)
				)
			)
		)
		(duplicate_pad_numbers_are_jumpers no)
		(fp_poly
			(pts
				(arc
					(start 3.999992 5.999988)
					(mid 0 9.99998)
					(end -3.999992 5.999988)
				)
				(arc
					(start -3.999992 0)
					(mid 0 -3.999992)
					(end 3.999992 0)
				)
			)
			(stroke
				(width 0)
				(type default)
			)
			(fill no)
			(layer "B.CrtYd")
		)
		(fp_poly
			(pts
				(arc
					(start 3.999992 5.999988)
					(mid 0 9.99998)
					(end -3.999992 5.999988)
				)
				(arc
					(start -3.999992 0)
					(mid 0 -3.999992)
					(end 3.999992 0)
				)
			)
			(stroke
				(width 0)
				(type default)
			)
			(fill no)
			(layer "F.CrtYd")
		)
		(pad "" np_thru_hole circle
			(at 0 0 180)
			(size 3.5052 3.5052)
			(drill 3.5052)
			(layers "*.Cu" "*.Mask")
			(clearance 0.381)
			(thermal_gap 0.381)
		)
		(zone
			(layers "F.Cu" "B.Cu" "In1.Cu" "In2.Cu" "In3.Cu" "In4.Cu" "In5.Cu" "In6.Cu")
			(hatch none 0.5)
			(connect_pads
				(clearance 0)
			)
			(min_thickness 0.25)
			(keepout
				(tracks not_allowed)
				(vias allowed)
				(pads allowed)
				(copperpour not_allowed)
				(footprints allowed)
			)
			(placement
				(enabled no)
				(sheetname "")
			)
			(fill
				(thermal_gap 0.5)
				(thermal_bridge_width 0.5)
				(island_removal_mode 0)
			)
			(polygon
				(pts
					(arc
						(start 298.398438 -44.952666)
						(mid 300.810168 -51.007954)
						(end 303.221898 -44.952666)
					)
					(arc
						(start 303.221898 -44.952666)
						(mid 303.108269 -44.789805)
						(end 303.068228 -44.595288)
					)
					(arc
						(start 303.068228 -41.500044)
						(mid 300.810168 -39.241984)
						(end 298.552108 -41.500044)
					)
					(arc
						(start 298.552108 -44.595288)
						(mid 298.512122 -44.789828)
						(end 298.398438 -44.952666)
					)
				)
			)
		)
	)
	(footprint ""
		(layer "F.Cu")
		(at 351.177352 -22.159468)
		(property "Reference" "R70"
			(at -58.908696 -4.409948 0)
			(unlocked yes)
			(layer "F.SilkS")
			(effects
				(font
					(size 0.7874 0.5842)
					(thickness 0.1524)
				)
				(justify left)
			)
		)
		(property "Value" ""
			(at 0 0 0)
			(layer "F.Fab")
			(effects
				(font
					(size 1.27 1.27)
				)
			)
		)
		(duplicate_pad_numbers_are_jumpers no)
		(fp_line
			(start -0.7874 -0.4064)
			(end 0.7874 -0.4064)
			(stroke
				(width 0.1524)
				(type default)
			)
			(layer "F.SilkS")
		)
		(fp_line
			(start -0.7874 0.4064)
			(end -0.7874 -0.4064)
			(stroke
				(width 0.1524)
				(type default)
			)
			(layer "F.SilkS")
		)
		(fp_line
			(start 0.7874 -0.4064)
			(end 0.7874 0.4064)
			(stroke
				(width 0.1524)
				(type default)
			)
			(layer "F.SilkS")
		)
		(fp_line
			(start 0.7874 0.4064)
			(end -0.7874 0.4064)
			(stroke
				(width 0.1524)
				(type default)
			)
			(layer "F.SilkS")
		)
		(fp_poly
			(pts
				(xy -0.508 0.2794) (xy -0.508 0.2286) (xy -0.635 0.2286) (xy -0.635 -0.254) (xy -0.5334 -0.254)
				(xy -0.5334 -0.2794) (xy 0.5334 -0.2794) (xy 0.5334 -0.254) (xy 0.635 -0.254) (xy 0.635 0.254) (xy 0.5334 0.254)
				(xy 0.5334 0.2794)
			)
			(stroke
				(width 0)
				(type default)
			)
			(fill no)
			(layer "F.CrtYd")
		)
		(pad "1" smd rect
			(at 0.40005 0)
			(size 0.4572 0.508)
			(layers "F.Cu" "F.Mask" "F.Paste")
			(net "ENET10G_3_LOS")
		)
		(pad "2" smd rect
			(at -0.40005 0)
			(size 0.4572 0.508)
			(layers "F.Cu" "F.Mask" "F.Paste")
			(net "SFP3_PRESENT_N")
		)
	)
	(footprint ""
		(layer "F.Cu")
		(at 145.2118 -3.048 90)
		(property "Reference" "C18"
			(at -2.2606 -8.194548 90)
			(unlocked yes)
			(layer "F.SilkS")
			(effects
				(font
					(size 0.7874 0.5842)
					(thickness 0.1524)
				)
				(justify left)
			)
		)
		(property "Value" ""
			(at 0 0 90)
			(layer "F.Fab")
			(effects
				(font
					(size 1.27 1.27)
				)
			)
		)
		(duplicate_pad_numbers_are_jumpers no)
		(fp_line
			(start 0.7874 -0.4064)
			(end 0.7874 0.4064)
			(stroke
				(width 0.1524)
				(type default)
			)
			(layer "F.SilkS")
		)
		(fp_line
			(start -0.7874 -0.4064)
			(end 0.7874 -0.4064)
			(stroke
				(width 0.1524)
				(type default)
			)
			(layer "F.SilkS")
		)
		(fp_line
			(start 0 0.381)
			(end 0 -0.381)
			(stroke
				(width 0.1524)
				(type default)
			)
			(layer "F.SilkS")
		)
		(fp_line
			(start 0.7874 0.4064)
			(end -0.7874 0.4064)
			(stroke
				(width 0.1524)
				(type default)
			)
			(layer "F.SilkS")
		)
		(fp_line
			(start -0.7874 0.4064)
			(end -0.7874 -0.4064)
			(stroke
				(width 0.1524)
				(type default)
			)
			(layer "F.SilkS")
		)
		(fp_poly
			(pts
				(xy -0.5334 0.254) (xy -0.635 0.254) (xy -0.635 0.2286) (xy -0.635 -0.254) (xy -0.5334 -0.254) (xy -0.5334 -0.2794)
				(xy 0.5334 -0.2794) (xy 0.5334 -0.254) (xy 0.635 -0.254) (xy 0.635 0.254) (xy 0.5334 0.254) (xy 0.5334 0.2794)
				(xy -0.508 0.2794) (xy -0.5334 0.2794)
			)
			(stroke
				(width 0)
				(type default)
			)
			(fill no)
			(layer "F.CrtYd")
		)
		(pad "1" smd rect
			(at 0.40005 0 90)
			(size 0.4572 0.508)
			(layers "F.Cu" "F.Mask" "F.Paste")
			(net "P3V3_10G_1_VCCT")
		)
		(pad "2" smd rect
			(at -0.40005 0 90)
			(size 0.4572 0.508)
			(layers "F.Cu" "F.Mask" "F.Paste")
			(net "GND")
		)
	)
	(footprint ""
		(layer "F.Cu")
		(at 29.029152 -23.484332 180)
		(property "Reference" "JP7"
			(at 0.527304 -1.935734 0)
			(unlocked yes)
			(layer "F.SilkS")
			(effects
				(font
					(size 0.7874 0.5842)
					(thickness 0.1524)
				)
				(justify left)
			)
		)
		(property "Value" ""
			(at 0 0 180)
			(layer "F.Fab")
			(effects
				(font
					(size 1.27 1.27)
				)
			)
		)
		(duplicate_pad_numbers_are_jumpers no)
		(fp_line
			(start 2.54 1.27)
			(end -2.54 1.27)
			(stroke
				(width 0.1524)
				(type default)
			)
			(layer "F.SilkS")
		)
		(fp_line
			(start 2.54 -1.27)
			(end 2.54 1.27)
			(stroke
				(width 0.1524)
				(type default)
			)
			(layer "F.SilkS")
		)
		(fp_line
			(start -2.54 1.27)
			(end -2.54 -1.27)
			(stroke
				(width 0.1524)
				(type default)
			)
			(layer "F.SilkS")
		)
		(fp_line
			(start -2.54 -1.27)
			(end 2.54 -1.27)
			(stroke
				(width 0.1524)
				(type default)
			)
			(layer "F.SilkS")
		)
		(fp_poly
			(pts
				(xy -2.71018 0.089916) (xy -4.03098 -0.494284) (xy -4.03098 0.724916)
			)
			(stroke
				(width 0)
				(type default)
			)
			(fill yes)
			(layer "F.SilkS")
		)
		(fp_poly
			(pts
				(xy -2.1082 -0.8382) (xy -2.1082 0.8382) (xy 2.1082 0.8382) (xy 2.1082 -0.8382)
			)
			(stroke
				(width 0)
				(type default)
			)
			(fill no)
			(layer "B.CrtYd")
		)
		(fp_rect
			(start -2.54 1.27)
			(end 2.54 -1.27)
			(stroke
				(width 0)
				(type default)
			)
			(fill no)
			(layer "F.CrtYd")
		)
		(fp_line
			(start 2.54 1.27)
			(end -2.54 1.27)
			(stroke
				(width 0.1)
				(type default)
			)
			(layer "F.Fab")
		)
		(fp_line
			(start 2.54 -1.27)
			(end 2.54 1.27)
			(stroke
				(width 0.1)
				(type default)
			)
			(layer "F.Fab")
		)
		(fp_line
			(start -2.54 1.27)
			(end -2.54 -1.27)
			(stroke
				(width 0.1)
				(type default)
			)
			(layer "F.Fab")
		)
		(fp_line
			(start -2.54 -1.27)
			(end 2.54 -1.27)
			(stroke
				(width 0.1)
				(type default)
			)
			(layer "F.Fab")
		)
		(fp_text user "2"
			(at 3.473704 0.045466 0)
			(unlocked yes)
			(layer "F.SilkS")
			(effects
				(font
					(size 0.7874 0.5842)
					(thickness 0.1524)
				)
				(justify left)
			)
		)
		(fp_text user "1"
			(at -2.825496 -0.894334 0)
			(unlocked yes)
			(layer "F.SilkS")
			(effects
				(font
					(size 0.7874 0.5842)
					(thickness 0.1524)
				)
				(justify left)
			)
		)
		(fp_text user "2"
			(at 2.457704 -0.233934 0)
			(unlocked yes)
			(layer "B.SilkS")
			(effects
				(font
					(size 0.7874 0.5842)
					(thickness 0.1524)
				)
				(justify left mirror)
			)
		)
		(fp_text user "1"
			(at -2.825496 -0.132334 0)
			(unlocked yes)
			(layer "B.SilkS")
			(effects
				(font
					(size 0.7874 0.5842)
					(thickness 0.1524)
				)
				(justify left mirror)
			)
		)
		(pad "1" thru_hole rect
			(at -1.27 0 180)
			(size 1.6764 1.6764)
			(drill 1.1684)
			(layers "*.Cu" "*.Mask")
			(remove_unused_layers no)
			(net "NODE4_EN")
			(clearance 0)
			(padstack
				(mode front_inner_back)
				(layer "Inner"
					(shape circle)
					(size 1.6764 1.6764)
					(clearance 0)
				)
				(layer "B.Cu"
					(shape rect)
					(size 1.6764 1.6764)
					(clearance 0)
				)
			)
		)
		(pad "2" thru_hole circle
			(at 1.27 0 180)
			(size 1.6764 1.6764)
			(drill 1.1684)
			(layers "*.Cu" "*.Mask")
			(remove_unused_layers no)
			(net "N39395053")
			(clearance 0)
		)
	)
	(footprint ""
		(layer "F.Cu")
		(at 144.0942 -3.048 90)
		(property "Reference" "C22"
			(at -2.286 -8.143748 90)
			(unlocked yes)
			(layer "F.SilkS")
			(effects
				(font
					(size 0.7874 0.5842)
					(thickness 0.1524)
				)
				(justify left)
			)
		)
		(property "Value" ""
			(at 0 0 90)
			(layer "F.Fab")
			(effects
				(font
					(size 1.27 1.27)
				)
			)
		)
		(duplicate_pad_numbers_are_jumpers no)
		(fp_line
			(start 0.7874 -0.4064)
			(end 0.7874 0.4064)
			(stroke
				(width 0.1524)
				(type default)
			)
			(layer "F.SilkS")
		)
		(fp_line
			(start -0.7874 -0.4064)
			(end 0.7874 -0.4064)
			(stroke
				(width 0.1524)
				(type default)
			)
			(layer "F.SilkS")
		)
		(fp_line
			(start 0 0.381)
			(end 0 -0.381)
			(stroke
				(width 0.1524)
				(type default)
			)
			(layer "F.SilkS")
		)
		(fp_line
			(start 0.7874 0.4064)
			(end -0.7874 0.4064)
			(stroke
				(width 0.1524)
				(type default)
			)
			(layer "F.SilkS")
		)
		(fp_line
			(start -0.7874 0.4064)
			(end -0.7874 -0.4064)
			(stroke
				(width 0.1524)
				(type default)
			)
			(layer "F.SilkS")
		)
		(fp_poly
			(pts
				(xy -0.5334 0.254) (xy -0.635 0.254) (xy -0.635 0.2286) (xy -0.635 -0.254) (xy -0.5334 -0.254) (xy -0.5334 -0.2794)
				(xy 0.5334 -0.2794) (xy 0.5334 -0.254) (xy 0.635 -0.254) (xy 0.635 0.254) (xy 0.5334 0.254) (xy 0.5334 0.2794)
				(xy -0.508 0.2794) (xy -0.5334 0.2794)
			)
			(stroke
				(width 0)
				(type default)
			)
			(fill no)
			(layer "F.CrtYd")
		)
		(pad "1" smd rect
			(at 0.40005 0 90)
			(size 0.4572 0.508)
			(layers "F.Cu" "F.Mask" "F.Paste")
			(net "P3V3_10G_1_VCCR")
		)
		(pad "2" smd rect
			(at -0.40005 0 90)
			(size 0.4572 0.508)
			(layers "F.Cu" "F.Mask" "F.Paste")
			(net "GND")
		)
	)
	(footprint ""
		(layer "F.Cu")
		(at 27.167332 -16.383 90)
		(property "Reference" "R91"
			(at -3.7846 -0.117348 90)
			(unlocked yes)
			(layer "F.SilkS")
			(effects
				(font
					(size 0.7874 0.5842)
					(thickness 0.1524)
				)
				(justify left)
			)
		)
		(property "Value" ""
			(at 0 0 90)
			(layer "F.Fab")
			(effects
				(font
					(size 1.27 1.27)
				)
			)
		)
		(duplicate_pad_numbers_are_jumpers no)
		(fp_line
			(start 0.7874 -0.4064)
			(end 0.7874 0.4064)
			(stroke
				(width 0.1524)
				(type default)
			)
			(layer "F.SilkS")
		)
		(fp_line
			(start -0.7874 -0.4064)
			(end 0.7874 -0.4064)
			(stroke
				(width 0.1524)
				(type default)
			)
			(layer "F.SilkS")
		)
		(fp_line
			(start 0.7874 0.4064)
			(end -0.7874 0.4064)
			(stroke
				(width 0.1524)
				(type default)
			)
			(layer "F.SilkS")
		)
		(fp_line
			(start -0.7874 0.4064)
			(end -0.7874 -0.4064)
			(stroke
				(width 0.1524)
				(type default)
			)
			(layer "F.SilkS")
		)
		(fp_poly
			(pts
				(xy -0.508 0.2794) (xy -0.508 0.2286) (xy -0.635 0.2286) (xy -0.635 -0.254) (xy -0.5334 -0.254)
				(xy -0.5334 -0.2794) (xy 0.5334 -0.2794) (xy 0.5334 -0.254) (xy 0.635 -0.254) (xy 0.635 0.254) (xy 0.5334 0.254)
				(xy 0.5334 0.2794)
			)
			(stroke
				(width 0)
				(type default)
			)
			(fill no)
			(layer "F.CrtYd")
		)
		(pad "1" smd rect
			(at 0.40005 0 90)
			(size 0.4572 0.508)
			(layers "F.Cu" "F.Mask" "F.Paste")
			(net "N39398095")
		)
		(pad "2" smd rect
			(at -0.40005 0 90)
			(size 0.4572 0.508)
			(layers "F.Cu" "F.Mask" "F.Paste")
			(net "GND")
		)
	)
	(footprint ""
		(layer "F.Cu")
		(at 89.515696 -23.621746 -90)
		(property "Reference" "C1"
			(at -1.168908 5.040122 90)
			(unlocked yes)
			(layer "F.SilkS")
			(effects
				(font
					(size 0.7874 0.5842)
					(thickness 0.1524)
				)
			)
		)
		(property "Value" ""
			(at 0 0 270)
			(layer "F.Fab")
			(effects
				(font
					(size 1.27 1.27)
				)
			)
		)
		(duplicate_pad_numbers_are_jumpers no)
		(fp_line
			(start -1.2954 0.5842)
			(end -1.2954 -0.5842)
			(stroke
				(width 0.1524)
				(type default)
			)
			(layer "F.SilkS")
		)
		(fp_line
			(start 1.2954 0.5842)
			(end -1.2954 0.5842)
			(stroke
				(width 0.1524)
				(type default)
			)
			(layer "F.SilkS")
		)
		(fp_line
			(start -1.2954 -0.5842)
			(end 1.2954 -0.5842)
			(stroke
				(width 0.1524)
				(type default)
			)
			(layer "F.SilkS")
		)
		(fp_line
			(start 0 -0.5842)
			(end 0 0.5842)
			(stroke
				(width 0.1524)
				(type default)
			)
			(layer "F.SilkS")
		)
		(fp_line
			(start 1.2954 -0.5842)
			(end 1.2954 0.5842)
			(stroke
				(width 0.1524)
				(type default)
			)
			(layer "F.SilkS")
		)
		(fp_poly
			(pts
				(xy 0.8636 -0.4572) (xy 0.8636 -0.3556) (xy 1.143 -0.3556) (xy 1.143 0.3556) (xy 0.8636 0.3556)
				(xy 0.8636 0.4572) (xy -0.8636 0.4572) (xy -0.8636 0.3556) (xy -1.143 0.3556) (xy -1.143 -0.3556)
				(xy -0.8636 -0.3556) (xy -0.8636 -0.4572)
			)
			(stroke
				(width 0)
				(type default)
			)
			(fill no)
			(layer "F.CrtYd")
		)
		(fp_line
			(start -0.884936 0.504952)
			(end -0.884936 -0.504952)
			(stroke
				(width 0.1)
				(type default)
			)
			(layer "F.Fab")
		)
		(fp_line
			(start 0.884936 0.504952)
			(end -0.884936 0.504952)
			(stroke
				(width 0.1)
				(type default)
			)
			(layer "F.Fab")
		)
		(fp_line
			(start -0.884936 -0.504952)
			(end 0.884936 -0.504952)
			(stroke
				(width 0.1)
				(type default)
			)
			(layer "F.Fab")
		)
		(fp_line
			(start 0.884936 -0.504952)
			(end 0.884936 0.504952)
			(stroke
				(width 0.1)
				(type default)
			)
			(layer "F.Fab")
		)
		(pad "1" smd rect
			(at 0.7366 0)
			(size 0.7112 0.8128)
			(layers "F.Cu" "F.Mask" "F.Paste")
			(net "P12V")
		)
		(pad "2" smd rect
			(at -0.7366 0)
			(size 0.7112 0.8128)
			(layers "F.Cu" "F.Mask" "F.Paste")
			(net "GND")
		)
	)
	(footprint ""
		(layer "F.Cu")
		(at 370.614956 -49.795176)
		(property "Reference" "J17"
			(at 4.685538 2.36982 90)
			(unlocked yes)
			(layer "F.SilkS")
			(effects
				(font
					(size 0.7874 0.5842)
					(thickness 0.1524)
				)
				(justify left)
			)
		)
		(property "Value" ""
			(at 0 0 0)
			(layer "F.Fab")
			(effects
				(font
					(size 1.27 1.27)
				)
			)
		)
		(duplicate_pad_numbers_are_jumpers no)
		(fp_line
			(start -18.2499 -9.99998)
			(end 3.999992 -9.99998)
			(stroke
				(width 0.1524)
				(type default)
			)
			(layer "F.SilkS")
		)
		(fp_line
			(start -18.2499 45.299884)
			(end -18.2499 -9.99998)
			(stroke
				(width 0.1524)
				(type default)
			)
			(layer "F.SilkS")
		)
		(fp_line
			(start -16.665956 45.299884)
			(end -18.2499 45.299884)
			(stroke
				(width 0.1524)
				(type default)
			)
			(layer "F.SilkS")
		)
		(fp_line
			(start -15.249906 -6.999986)
			(end 0.999998 -6.999986)
			(stroke
				(width 0.1524)
				(type default)
			)
			(layer "F.SilkS")
		)
		(fp_line
			(start -15.249906 42.29989)
			(end -15.249906 -6.999986)
			(stroke
				(width 0.1524)
				(type default)
			)
			(layer "F.SilkS")
		)
		(fp_line
			(start -13.24991 26.800048)
			(end -13.24991 41.299892)
			(stroke
				(width 0.1524)
				(type default)
			)
			(layer "F.SilkS")
		)
		(fp_line
			(start -13.24991 41.299892)
			(end -12.6746 41.299892)
			(stroke
				(width 0.1524)
				(type default)
			)
			(layer "F.SilkS")
		)
		(fp_line
			(start -12.319 42.29989)
			(end -15.249906 42.29989)
			(stroke
				(width 0.1524)
				(type default)
			)
			(layer "F.SilkS")
		)
		(fp_line
			(start -11.176 41.299892)
			(end -10.919968 41.299892)
			(stroke
				(width 0.1524)
				(type default)
			)
			(layer "F.SilkS")
		)
		(fp_line
			(start -10.919968 41.299892)
			(end -10.919968 42.29989)
			(stroke
				(width 0.1524)
				(type default)
			)
			(layer "F.SilkS")
		)
		(fp_line
			(start -10.919968 42.29989)
			(end -11.5316 42.29989)
			(stroke
				(width 0.1524)
				(type default)
			)
			(layer "F.SilkS")
		)
		(fp_line
			(start -3.32994 41.299892)
			(end -3.0734 41.299892)
			(stroke
				(width 0.1524)
				(type default)
			)
			(layer "F.SilkS")
		)
		(fp_line
			(start -3.32994 42.29989)
			(end -3.32994 41.299892)
			(stroke
				(width 0.1524)
				(type default)
			)
			(layer "F.SilkS")
		)
		(fp_line
			(start -2.7178 42.29989)
			(end -3.32994 42.29989)
			(stroke
				(width 0.1524)
				(type default)
			)
			(layer "F.SilkS")
		)
		(fp_line
			(start -1.5748 41.299892)
			(end -0.999998 41.299892)
			(stroke
				(width 0.1524)
				(type default)
			)
			(layer "F.SilkS")
		)
		(fp_line
			(start -0.999998 26.800048)
			(end -13.24991 26.800048)
			(stroke
				(width 0.1524)
				(type default)
			)
			(layer "F.SilkS")
		)
		(fp_line
			(start -0.999998 41.299892)
			(end -0.999998 26.800048)
			(stroke
				(width 0.1524)
				(type default)
			)
			(layer "F.SilkS")
		)
		(fp_line
			(start 0.999998 -6.999986)
			(end 0.999998 42.29989)
			(stroke
				(width 0.1524)
				(type default)
			)
			(layer "F.SilkS")
		)
		(fp_line
			(start 0.999998 42.29989)
			(end -1.9558 42.29989)
			(stroke
				(width 0.1524)
				(type default)
			)
			(layer "F.SilkS")
		)
		(fp_line
			(start 3.999992 -9.99998)
			(end 3.999992 45.299884)
			(stroke
				(width 0.1524)
				(type default)
			)
			(layer "F.SilkS")
		)
		(fp_line
			(start 3.999992 45.299884)
			(end -8.995156 45.299884)
			(stroke
				(width 0.1524)
				(type default)
			)
			(layer "F.SilkS")
		)
		(fp_poly
			(pts
				(xy 4.2164 4.1275) (xy 7.6454 5.2705) (xy 7.6454 2.9845)
			)
			(stroke
				(width 0)
				(type default)
			)
			(fill yes)
			(layer "F.SilkS")
		)
		(fp_line
			(start -18.2499 -9.99998)
			(end 3.999992 -9.99998)
			(stroke
				(width 0.1524)
				(type default)
			)
			(layer "B.SilkS")
		)
		(fp_line
			(start -18.2499 27.112976)
			(end -18.2499 -9.99998)
			(stroke
				(width 0.1524)
				(type default)
			)
			(layer "B.SilkS")
		)
		(fp_line
			(start -18.2499 37.907976)
			(end -18.2499 28.078176)
			(stroke
				(width 0.1524)
				(type default)
			)
			(layer "B.SilkS")
		)
		(fp_line
			(start -18.2499 44.181776)
			(end -18.2499 43.419776)
			(stroke
				(width 0.1524)
				(type default)
			)
			(layer "B.SilkS")
		)
		(fp_line
			(start 3.999992 -9.99998)
			(end 3.999992 45.299884)
			(stroke
				(width 0.1524)
				(type default)
			)
			(layer "B.SilkS")
		)
		(fp_line
			(start 3.999992 45.299884)
			(end -16.691356 45.299884)
			(stroke
				(width 0.1524)
				(type default)
			)
			(layer "B.SilkS")
		)
		(fp_poly
			(pts
				(xy -15.0876 8.6614) (xy -13.4112 8.6614) (xy -13.4112 10.3378) (xy -15.0876 10.3378)
			)
			(stroke
				(width 0)
				(type default)
			)
			(fill no)
			(layer "B.CrtYd")
		)
		(fp_poly
			(pts
				(xy -15.0876 18.669) (xy -13.4112 18.669) (xy -13.4112 20.3454) (xy -15.0876 20.3454)
			)
			(stroke
				(width 0)
				(type default)
			)
			(fill no)
			(layer "B.CrtYd")
		)
		(fp_poly
			(pts
				(xy -15.0876 28.6512) (xy -13.4112 28.6512) (xy -13.4112 30.3276) (xy -15.0876 30.3276)
			)
			(stroke
				(width 0)
				(type default)
			)
			(fill no)
			(layer "B.CrtYd")
		)
		(fp_poly
			(pts
				(xy -15.0876 38.6588) (xy -13.4112 38.6588) (xy -13.4112 40.3352) (xy -15.0876 40.3352)
			)
			(stroke
				(width 0)
				(type default)
			)
			(fill no)
			(layer "B.CrtYd")
		)
		(fp_poly
			(pts
				(xy -14.986 26.5684) (xy -13.5128 26.5684) (xy -13.5128 28.0416) (xy -14.986 28.0416)
			)
			(stroke
				(width 0)
				(type default)
			)
			(fill no)
			(layer "B.CrtYd")
		)
		(fp_poly
			(pts
				(xy -14.986 31.2674) (xy -13.5128 31.2674) (xy -13.5128 32.7406) (xy -14.986 32.7406)
			)
			(stroke
				(width 0)
				(type default)
			)
			(fill no)
			(layer "B.CrtYd")
		)
		(fp_poly
			(pts
				(xy -14.986 36.2712) (xy -13.5128 36.2712) (xy -13.5128 37.7444) (xy -14.986 37.7444)
			)
			(stroke
				(width 0)
				(type default)
			)
			(fill no)
			(layer "B.CrtYd")
		)
		(fp_poly
			(pts
				(xy -12.6746 40.8686) (xy -11.2014 40.8686) (xy -11.2014 42.3418) (xy -12.6746 42.3418)
			)
			(stroke
				(width 0)
				(type default)
			)
			(fill no)
			(layer "B.CrtYd")
		)
		(fp_poly
			(pts
				(xy -11.9126 23.6728) (xy -10.2362 23.6728) (xy -10.2362 25.3492) (xy -11.9126 25.3492)
			)
			(stroke
				(width 0)
				(type default)
			)
			(fill no)
			(layer "B.CrtYd")
		)
		(fp_poly
			(pts
				(xy -9.4488 3.6576) (xy -7.7724 3.6576) (xy -7.7724 5.334) (xy -9.4488 5.334)
			)
			(stroke
				(width 0)
				(type default)
			)
			(fill no)
			(layer "B.CrtYd")
		)
		(fp_poly
			(pts
				(xy -7.874 40.8686) (xy -6.4008 40.8686) (xy -6.4008 42.3418) (xy -7.874 42.3418)
			)
			(stroke
				(width 0)
				(type default)
			)
			(fill no)
			(layer "B.CrtYd")
		)
		(fp_poly
			(pts
				(xy -6.5278 23.6728) (xy -4.8514 23.6728) (xy -4.8514 25.3492) (xy -6.5278 25.3492)
			)
			(stroke
				(width 0)
				(type default)
			)
			(fill no)
			(layer "B.CrtYd")
		)
		(fp_poly
			(pts
				(xy -3.0734 40.8686) (xy -1.6002 40.8686) (xy -1.6002 42.3418) (xy -3.0734 42.3418)
			)
			(stroke
				(width 0)
				(type default)
			)
			(fill no)
			(layer "B.CrtYd")
		)
		(fp_poly
			(pts
				(xy -0.8382 3.6576) (xy 0.8382 3.6576) (xy 0.8382 5.334) (xy -0.8382 5.334)
			)
			(stroke
				(width 0)
				(type default)
			)
			(fill no)
			(layer "B.CrtYd")
		)
		(fp_poly
			(pts
				(xy -0.8382 23.6728) (xy 0.8382 23.6728) (xy 0.8382 25.3492) (xy -0.8382 25.3492)
			)
			(stroke
				(width 0)
				(type default)
			)
			(fill no)
			(layer "B.CrtYd")
		)
		(fp_poly
			(pts
				(xy -0.7366 26.5684) (xy 0.7366 26.5684) (xy 0.7366 28.0416) (xy -0.7366 28.0416)
			)
			(stroke
				(width 0)
				(type default)
			)
			(fill no)
			(layer "B.CrtYd")
		)
		(fp_poly
			(pts
				(xy -0.7366 31.2674) (xy 0.7366 31.2674) (xy 0.7366 32.7406) (xy -0.7366 32.7406)
			)
			(stroke
				(width 0)
				(type default)
			)
			(fill no)
			(layer "B.CrtYd")
		)
		(fp_poly
			(pts
				(xy -0.7366 36.2712) (xy 0.7366 36.2712) (xy 0.7366 37.7444) (xy -0.7366 37.7444)
			)
			(stroke
				(width 0)
				(type default)
			)
			(fill no)
			(layer "B.CrtYd")
		)
		(fp_poly
			(pts
				(xy -0.6858 33.8074) (xy 0.6858 33.8074) (xy 0.6858 35.179) (xy -0.6858 35.179)
			)
			(stroke
				(width 0)
				(type default)
			)
			(fill no)
			(layer "B.CrtYd")
		)
		(fp_poly
			(pts
				(xy 0.8382 14.5542) (xy 0.8382 13.6652) (xy 0 13.6652) (xy -0.8382 13.6652) (xy -0.8382 15.3416)
				(xy 0.8382 15.3416)
			)
			(stroke
				(width 0)
				(type default)
			)
			(fill no)
			(layer "B.CrtYd")
		)
		(fp_rect
			(start -8.130032 42.29989)
			(end -6.130036 41.299892)
			(stroke
				(width 0)
				(type default)
			)
			(fill no)
			(layer "F.CrtYd")
		)
		(fp_poly
			(pts
				(xy 0.999998 -6.999986) (xy 0.999998 42.29989) (xy -3.32994 42.29989) (xy -3.32994 41.299892) (xy -0.999998 41.299892)
				(xy -0.999998 26.800048) (xy -13.24991 26.800048) (xy -13.24991 41.299892) (xy -10.919968 41.299892)
				(xy -10.919968 42.29989) (xy -15.249906 42.29989) (xy -15.249906 -6.999986)
			)
			(stroke
				(width 0)
				(type default)
			)
			(fill no)
			(layer "F.CrtYd")
		)
		(fp_line
			(start -15.249906 -6.999986)
			(end 0.999998 -6.999986)
			(stroke
				(width 0.1)
				(type default)
			)
			(layer "F.Fab")
		)
		(fp_line
			(start -15.249906 0)
			(end 0.999998 0)
			(stroke
				(width 0.1)
				(type default)
			)
			(layer "F.Fab")
		)
		(fp_line
			(start -15.249906 41.999916)
			(end -15.249906 -6.999986)
			(stroke
				(width 0.1)
				(type default)
			)
			(layer "F.Fab")
		)
		(fp_line
			(start -15.249906 42.29989)
			(end -15.249906 0)
			(stroke
				(width 0.1)
				(type default)
			)
			(layer "F.Fab")
		)
		(fp_line
			(start -13.24991 26.800048)
			(end -13.24991 41.299892)
			(stroke
				(width 0.1)
				(type default)
			)
			(layer "F.Fab")
		)
		(fp_line
			(start -13.24991 41.299892)
			(end -10.919968 41.299892)
			(stroke
				(width 0.1)
				(type default)
			)
			(layer "F.Fab")
		)
		(fp_line
			(start -10.919968 41.299892)
			(end -10.919968 42.29989)
			(stroke
				(width 0.1)
				(type default)
			)
			(layer "F.Fab")
		)
		(fp_line
			(start -10.919968 42.29989)
			(end -15.249906 42.29989)
			(stroke
				(width 0.1)
				(type default)
			)
			(layer "F.Fab")
		)
		(fp_line
			(start -3.32994 41.299892)
			(end -0.999998 41.299892)
			(stroke
				(width 0.1)
				(type default)
			)
			(layer "F.Fab")
		)
		(fp_line
			(start -3.32994 42.29989)
			(end -3.32994 41.299892)
			(stroke
				(width 0.1)
				(type default)
			)
			(layer "F.Fab")
		)
		(fp_line
			(start -0.999998 26.800048)
			(end -13.24991 26.800048)
			(stroke
				(width 0.1)
				(type default)
			)
			(layer "F.Fab")
		)
		(fp_line
			(start -0.999998 41.299892)
			(end -0.999998 26.800048)
			(stroke
				(width 0.1)
				(type default)
			)
			(layer "F.Fab")
		)
		(fp_line
			(start 0.999998 -6.999986)
			(end 0.999998 41.999916)
			(stroke
				(width 0.1)
				(type default)
			)
			(layer "F.Fab")
		)
		(fp_line
			(start 0.999998 0)
			(end 0.999998 42.29989)
			(stroke
				(width 0.1)
				(type default)
			)
			(layer "F.Fab")
		)
		(fp_line
			(start 0.999998 41.999916)
			(end -15.249906 41.999916)
			(stroke
				(width 0.1)
				(type default)
			)
			(layer "F.Fab")
		)
		(fp_line
			(start 0.999998 42.29989)
			(end -3.32994 42.29989)
			(stroke
				(width 0.1)
				(type default)
			)
			(layer "F.Fab")
		)
		(fp_text user "PRESS-FIT"
			(at 2.62001 24.668988 90)
			(unlocked yes)
			(layer "F.SilkS")
			(effects
				(font
					(size 1.6002 1.1938)
					(thickness 0.1524)
				)
				(justify left)
			)
		)
		(fp_text user "PRESS-FIT"
			(at 2.211578 24.380952 270)
			(unlocked yes)
			(layer "B.SilkS")
			(effects
				(font
					(size 1.6002 1.1938)
					(thickness 0.1524)
				)
				(justify left mirror)
			)
		)
		(pad "1" thru_hole circle
			(at 0 4.500118)
			(size 1.5494 1.5494)
			(drill 1.0414)
			(layers "*.Cu" "*.Mask")
			(remove_unused_layers no)
			(net "GND")
			(clearance 0)
		)
		(pad "2" thru_hole circle
			(at -8.58012 4.500118)
			(size 1.5494 1.5494)
			(drill 1.0414)
			(layers "*.Cu" "*.Mask")
			(remove_unused_layers no)
			(net "GND")
			(clearance 0)
		)
		(pad "3" thru_hole circle
			(at 0 14.500098)
			(size 1.5494 1.5494)
			(drill 1.0414)
			(layers "*.Cu" "*.Mask")
			(remove_unused_layers no)
			(net "GND")
			(clearance 0)
		)
		(pad "4" thru_hole circle
			(at -14.249908 9.500108)
			(size 1.5494 1.5494)
			(drill 1.0414)
			(layers "*.Cu" "*.Mask")
			(remove_unused_layers no)
			(net "GND")
			(clearance 0)
		)
		(pad "5" thru_hole circle
			(at -14.249908 19.500088)
			(size 1.5494 1.5494)
			(drill 1.0414)
			(layers "*.Cu" "*.Mask")
			(remove_unused_layers no)
			(net "GND")
			(clearance 0)
		)
		(pad "6" thru_hole circle
			(at 0 24.500078)
			(size 1.5494 1.5494)
			(drill 1.0414)
			(layers "*.Cu" "*.Mask")
			(remove_unused_layers no)
			(net "GND")
			(clearance 0)
		)
		(pad "7" thru_hole circle
			(at -5.679948 24.500078)
			(size 1.5494 1.5494)
			(drill 1.0414)
			(layers "*.Cu" "*.Mask")
			(remove_unused_layers no)
			(net "GND")
			(clearance 0)
		)
		(pad "8" thru_hole circle
			(at -11.079988 24.500078)
			(size 1.5494 1.5494)
			(drill 1.0414)
			(layers "*.Cu" "*.Mask")
			(remove_unused_layers no)
			(net "GND")
			(clearance 0)
		)
		(pad "9" thru_hole circle
			(at -14.249908 29.500068)
			(size 1.5494 1.5494)
			(drill 1.0414)
			(layers "*.Cu" "*.Mask")
			(remove_unused_layers no)
			(net "GND")
			(clearance 0)
		)
		(pad "10" thru_hole circle
			(at -14.249908 39.500048)
			(size 1.5494 1.5494)
			(drill 1.0414)
			(layers "*.Cu" "*.Mask")
			(remove_unused_layers no)
			(net "GND")
			(clearance 0)
		)
		(pad "11" thru_hole circle
			(at 0 27.29992)
			(size 1.3462 1.3462)
			(drill 0.9398)
			(layers "*.Cu" "*.Mask")
			(remove_unused_layers no)
			(net "GND")
			(clearance 0.0508)
			(thermal_gap 0.0508)
		)
		(pad "12" thru_hole circle
			(at 0 31.999936)
			(size 1.3462 1.3462)
			(drill 0.9398)
			(layers "*.Cu" "*.Mask")
			(remove_unused_layers no)
			(net "GND")
			(clearance 0.0508)
			(thermal_gap 0.0508)
		)
		(pad "13" thru_hole circle
			(at 0 36.999926)
			(size 1.3462 1.3462)
			(drill 0.9398)
			(layers "*.Cu" "*.Mask")
			(remove_unused_layers no)
			(net "GND")
			(clearance 0.0508)
			(thermal_gap 0.0508)
		)
		(pad "14" thru_hole circle
			(at -2.329942 41.60012)
			(size 1.3462 1.3462)
			(drill 0.9398)
			(layers "*.Cu" "*.Mask")
			(remove_unused_layers no)
			(net "GND")
			(clearance 0.0508)
			(thermal_gap 0.0508)
		)
		(pad "15" thru_hole circle
			(at -7.130034 41.60012)
			(size 1.3462 1.3462)
			(drill 0.9398)
			(layers "*.Cu" "*.Mask")
			(remove_unused_layers no)
			(net "GND")
			(clearance 0.0508)
			(thermal_gap 0.0508)
		)
		(pad "16" thru_hole circle
			(at -11.929872 41.60012)
			(size 1.3462 1.3462)
			(drill 0.9398)
			(layers "*.Cu" "*.Mask")
			(remove_unused_layers no)
			(net "GND")
			(clearance 0.0508)
			(thermal_gap 0.0508)
		)
		(pad "17" thru_hole circle
			(at -14.249908 27.29992)
			(size 1.3462 1.3462)
			(drill 0.9398)
			(layers "*.Cu" "*.Mask")
			(remove_unused_layers no)
			(net "GND")
			(clearance 0.0508)
			(thermal_gap 0.0508)
		)
		(pad "18" thru_hole circle
			(at -14.249908 31.999936)
			(size 1.3462 1.3462)
			(drill 0.9398)
			(layers "*.Cu" "*.Mask")
			(remove_unused_layers no)
			(net "GND")
			(clearance 0.0508)
			(thermal_gap 0.0508)
		)
		(pad "19" thru_hole circle
			(at -14.249908 36.999926)
			(size 1.3462 1.3462)
			(drill 0.9398)
			(layers "*.Cu" "*.Mask")
			(remove_unused_layers no)
			(net "GND")
			(clearance 0.0508)
			(thermal_gap 0.0508)
		)
		(pad "20" thru_hole circle
			(at 0 34.500058)
			(size 1.2446 1.2446)
			(drill 0.8382)
			(layers "*.Cu" "*.Mask")
			(remove_unused_layers no)
			(net "GND")
			(clearance 0.0508)
			(thermal_gap 0.0508)
		)
		(zone
			(layer "F.Cu")
			(hatch none 0.5)
			(connect_pads
				(clearance 0)
			)
			(min_thickness 0.25)
			(keepout
				(tracks not_allowed)
				(vias allowed)
				(pads allowed)
				(copperpour not_allowed)
				(footprints allowed)
			)
			(placement
				(enabled no)
				(sheetname "")
			)
			(fill
				(thermal_gap 0.5)
				(thermal_bridge_width 0.5)
				(island_removal_mode 0)
			)
			(polygon
				(pts
					(xy 362.484924 -7.495286) (xy 364.48492 -7.495286) (xy 364.48492 -8.495284) (xy 362.484924 -8.495284)
				)
			)
		)
		(zone
			(layer "F.Cu")
			(hatch none 0.5)
			(connect_pads
				(clearance 0)
			)
			(min_thickness 0.25)
			(keepout
				(tracks not_allowed)
				(vias allowed)
				(pads allowed)
				(copperpour not_allowed)
				(footprints allowed)
			)
			(placement
				(enabled no)
				(sheetname "")
			)
			(fill
				(thermal_gap 0.5)
				(thermal_bridge_width 0.5)
				(island_removal_mode 0)
			)
			(polygon
				(pts
					(xy 371.614954 -49.795176) (xy 371.614954 -7.495286) (xy 367.285016 -7.495286) (xy 367.285016 -8.495284)
					(xy 369.614958 -8.495284) (xy 369.614958 -22.995128) (xy 357.365046 -22.995128) (xy 357.365046 -8.495284)
					(xy 359.694988 -8.495284) (xy 359.694988 -7.495286) (xy 355.36505 -7.495286) (xy 355.3714 -49.795176)
				)
			)
		)
		(zone
			(layers "F.Cu" "B.Cu" "In1.Cu" "In2.Cu" "In3.Cu" "In4.Cu" "In5.Cu" "In6.Cu")
			(hatch none 0.5)
			(connect_pads
				(clearance 0)
			)
			(min_thickness 0.25)
			(keepout
				(tracks allowed)
				(vias not_allowed)
				(pads allowed)
				(copperpour not_allowed)
				(footprints allowed)
			)
			(placement
				(enabled no)
				(sheetname "")
			)
			(fill
				(thermal_gap 0.5)
				(thermal_bridge_width 0.5)
				(island_removal_mode 0)
			)
			(polygon
				(pts
					(xy 355.527356 -39.457376) (xy 357.203756 -39.457376) (xy 357.203756 -41.133776) (xy 355.527356 -41.133776)
				)
			)
		)
		(zone
			(layers "F.Cu" "B.Cu" "In1.Cu" "In2.Cu" "In3.Cu" "In4.Cu" "In5.Cu" "In6.Cu")
			(hatch none 0.5)
			(connect_pads
				(clearance 0)
			)
			(min_thickness 0.25)
			(keepout
				(tracks allowed)
				(vias not_allowed)
				(pads allowed)
				(copperpour not_allowed)
				(footprints allowed)
			)
			(placement
				(enabled no)
				(sheetname "")
			)
			(fill
				(thermal_gap 0.5)
				(thermal_bridge_width 0.5)
				(island_removal_mode 0)
			)
			(polygon
				(pts
					(xy 355.527356 -29.449776) (xy 357.203756 -29.449776) (xy 357.203756 -31.126176) (xy 355.527356 -31.126176)
				)
			)
		)
		(zone
			(layers "F.Cu" "B.Cu" "In1.Cu" "In2.Cu" "In3.Cu" "In4.Cu" "In5.Cu" "In6.Cu")
			(hatch none 0.5)
			(connect_pads
				(clearance 0)
			)
			(min_thickness 0.25)
			(keepout
				(tracks allowed)
				(vias not_allowed)
				(pads allowed)
				(copperpour not_allowed)
				(footprints allowed)
			)
			(placement
				(enabled no)
				(sheetname "")
			)
			(fill
				(thermal_gap 0.5)
				(thermal_bridge_width 0.5)
				(island_removal_mode 0)
			)
			(polygon
				(pts
					(xy 355.527356 -19.467576) (xy 357.203756 -19.467576) (xy 357.203756 -21.143976) (xy 355.527356 -21.143976)
				)
			)
		)
		(zone
			(layers "F.Cu" "B.Cu" "In1.Cu" "In2.Cu" "In3.Cu" "In4.Cu" "In5.Cu" "In6.Cu")
			(hatch none 0.5)
			(connect_pads
				(clearance 0)
			)
			(min_thickness 0.25)
			(keepout
				(tracks allowed)
				(vias not_allowed)
				(pads allowed)
				(copperpour not_allowed)
				(footprints allowed)
			)
			(placement
				(enabled no)
				(sheetname "")
			)
			(fill
				(thermal_gap 0.5)
				(thermal_bridge_width 0.5)
				(island_removal_mode 0)
			)
			(polygon
				(pts
					(xy 355.527356 -9.459976) (xy 357.203756 -9.459976) (xy 357.203756 -11.136376) (xy 355.527356 -11.136376)
				)
			)
		)
		(zone
			(layers "F.Cu" "B.Cu" "In1.Cu" "In2.Cu" "In3.Cu" "In4.Cu" "In5.Cu" "In6.Cu")
			(hatch none 0.5)
			(connect_pads
				(clearance 0)
			)
			(min_thickness 0.25)
			(keepout
				(tracks allowed)
				(vias not_allowed)
				(pads allowed)
				(copperpour not_allowed)
				(footprints allowed)
			)
			(placement
				(enabled no)
				(sheetname "")
			)
			(fill
				(thermal_gap 0.5)
				(thermal_bridge_width 0.5)
				(island_removal_mode 0)
			)
			(polygon
				(pts
					(xy 355.628956 -21.753576) (xy 357.102156 -21.753576) (xy 357.102156 -23.226776) (xy 355.628956 -23.226776)
				)
			)
		)
		(zone
			(layers "F.Cu" "B.Cu" "In1.Cu" "In2.Cu" "In3.Cu" "In4.Cu" "In5.Cu" "In6.Cu")
			(hatch none 0.5)
			(connect_pads
				(clearance 0)
			)
			(min_thickness 0.25)
			(keepout
				(tracks allowed)
				(vias not_allowed)
				(pads allowed)
				(copperpour not_allowed)
				(footprints allowed)
			)
			(placement
				(enabled no)
				(sheetname "")
			)
			(fill
				(thermal_gap 0.5)
				(thermal_bridge_width 0.5)
				(island_removal_mode 0)
			)
			(polygon
				(pts
					(xy 355.628956 -17.054576) (xy 357.102156 -17.054576) (xy 357.102156 -18.527776) (xy 355.628956 -18.527776)
				)
			)
		)
		(zone
			(layers "F.Cu" "B.Cu" "In1.Cu" "In2.Cu" "In3.Cu" "In4.Cu" "In5.Cu" "In6.Cu")
			(hatch none 0.5)
			(connect_pads
				(clearance 0)
			)
			(min_thickness 0.25)
			(keepout
				(tracks allowed)
				(vias not_allowed)
				(pads allowed)
				(copperpour not_allowed)
				(footprints allowed)
			)
			(placement
				(enabled no)
				(sheetname "")
			)
			(fill
				(thermal_gap 0.5)
				(thermal_bridge_width 0.5)
				(island_removal_mode 0)
			)
			(polygon
				(pts
					(xy 355.628956 -12.050776) (xy 357.102156 -12.050776) (xy 357.102156 -13.523976) (xy 355.628956 -13.523976)
				)
			)
		)
		(zone
			(layers "F.Cu" "B.Cu" "In1.Cu" "In2.Cu" "In3.Cu" "In4.Cu" "In5.Cu" "In6.Cu")
			(hatch none 0.5)
			(connect_pads
				(clearance 0)
			)
			(min_thickness 0.25)
			(keepout
				(tracks allowed)
				(vias not_allowed)
				(pads allowed)
				(copperpour not_allowed)
				(footprints allowed)
			)
			(placement
				(enabled no)
				(sheetname "")
			)
			(fill
				(thermal_gap 0.5)
				(thermal_bridge_width 0.5)
				(island_removal_mode 0)
			)
			(polygon
				(pts
					(xy 357.940356 -7.453376) (xy 359.413556 -7.453376) (xy 359.413556 -8.926576) (xy 357.940356 -8.926576)
				)
			)
		)
		(zone
			(layers "F.Cu" "B.Cu" "In1.Cu" "In2.Cu" "In3.Cu" "In4.Cu" "In5.Cu" "In6.Cu")
			(hatch none 0.5)
			(connect_pads
				(clearance 0)
			)
			(min_thickness 0.25)
			(keepout
				(tracks allowed)
				(vias not_allowed)
				(pads allowed)
				(copperpour not_allowed)
				(footprints allowed)
			)
			(placement
				(enabled no)
				(sheetname "")
			)
			(fill
				(thermal_gap 0.5)
				(thermal_bridge_width 0.5)
				(island_removal_mode 0)
			)
			(polygon
				(pts
					(xy 358.702356 -24.445976) (xy 360.378756 -24.445976) (xy 360.378756 -26.122376) (xy 358.702356 -26.122376)
				)
			)
		)
		(zone
			(layers "F.Cu" "B.Cu" "In1.Cu" "In2.Cu" "In3.Cu" "In4.Cu" "In5.Cu" "In6.Cu")
			(hatch none 0.5)
			(connect_pads
				(clearance 0)
			)
			(min_thickness 0.25)
			(keepout
				(tracks allowed)
				(vias not_allowed)
				(pads allowed)
				(copperpour not_allowed)
				(footprints allowed)
			)
			(placement
				(enabled no)
				(sheetname "")
			)
			(fill
				(thermal_gap 0.5)
				(thermal_bridge_width 0.5)
				(island_removal_mode 0)
			)
			(polygon
				(pts
					(xy 361.166156 -44.461176) (xy 362.842556 -44.461176) (xy 362.842556 -46.137576) (xy 361.166156 -46.137576)
				)
			)
		)
		(zone
			(layers "F.Cu" "B.Cu" "In1.Cu" "In2.Cu" "In3.Cu" "In4.Cu" "In5.Cu" "In6.Cu")
			(hatch none 0.5)
			(connect_pads
				(clearance 0)
			)
			(min_thickness 0.25)
			(keepout
				(tracks allowed)
				(vias not_allowed)
				(pads allowed)
				(copperpour not_allowed)
				(footprints allowed)
			)
			(placement
				(enabled no)
				(sheetname "")
			)
			(fill
				(thermal_gap 0.5)
				(thermal_bridge_width 0.5)
				(island_removal_mode 0)
			)
			(polygon
				(pts
					(xy 362.740956 -7.453376) (xy 364.214156 -7.453376) (xy 364.214156 -8.926576) (xy 362.740956 -8.926576)
				)
			)
		)
		(zone
			(layers "F.Cu" "B.Cu" "In1.Cu" "In2.Cu" "In3.Cu" "In4.Cu" "In5.Cu" "In6.Cu")
			(hatch none 0.5)
			(connect_pads
				(clearance 0)
			)
			(min_thickness 0.25)
			(keepout
				(tracks allowed)
				(vias not_allowed)
				(pads allowed)
				(copperpour not_allowed)
				(footprints allowed)
			)
			(placement
				(enabled no)
				(sheetname "")
			)
			(fill
				(thermal_gap 0.5)
				(thermal_bridge_width 0.5)
				(island_removal_mode 0)
			)
			(polygon
				(pts
					(xy 364.087156 -24.445976) (xy 365.763556 -24.445976) (xy 365.763556 -26.122376) (xy 364.087156 -26.122376)
				)
			)
		)
		(zone
			(layers "F.Cu" "B.Cu" "In1.Cu" "In2.Cu" "In3.Cu" "In4.Cu" "In5.Cu" "In6.Cu")
			(hatch none 0.5)
			(connect_pads
				(clearance 0)
			)
			(min_thickness 0.25)
			(keepout
				(tracks allowed)
				(vias not_allowed)
				(pads allowed)
				(copperpour not_allowed)
				(footprints allowed)
			)
			(placement
				(enabled no)
				(sheetname "")
			)
			(fill
				(thermal_gap 0.5)
				(thermal_bridge_width 0.5)
				(island_removal_mode 0)
			)
			(polygon
				(pts
					(xy 367.541556 -7.453376) (xy 369.014756 -7.453376) (xy 369.014756 -8.926576) (xy 367.541556 -8.926576)
				)
			)
		)
		(zone
			(layers "F.Cu" "B.Cu" "In1.Cu" "In2.Cu" "In3.Cu" "In4.Cu" "In5.Cu" "In6.Cu")
			(hatch none 0.5)
			(connect_pads
				(clearance 0)
			)
			(min_thickness 0.25)
			(keepout
				(tracks allowed)
				(vias not_allowed)
				(pads allowed)
				(copperpour not_allowed)
				(footprints allowed)
			)
			(placement
				(enabled no)
				(sheetname "")
			)
			(fill
				(thermal_gap 0.5)
				(thermal_bridge_width 0.5)
				(island_removal_mode 0)
			)
			(polygon
				(pts
					(xy 369.776756 -44.461176) (xy 371.453156 -44.461176) (xy 371.453156 -46.137576) (xy 369.776756 -46.137576)
				)
			)
		)
		(zone
			(layers "F.Cu" "B.Cu" "In1.Cu" "In2.Cu" "In3.Cu" "In4.Cu" "In5.Cu" "In6.Cu")
			(hatch none 0.5)
			(connect_pads
				(clearance 0)
			)
			(min_thickness 0.25)
			(keepout
				(tracks allowed)
				(vias not_allowed)
				(pads allowed)
				(copperpour not_allowed)
				(footprints allowed)
			)
			(placement
				(enabled no)
				(sheetname "")
			)
			(fill
				(thermal_gap 0.5)
				(thermal_bridge_width 0.5)
				(island_removal_mode 0)
			)
			(polygon
				(pts
					(xy 369.776756 -24.445976) (xy 371.453156 -24.445976) (xy 371.453156 -26.122376) (xy 369.776756 -26.122376)
				)
			)
		)
		(zone
			(layers "F.Cu" "B.Cu" "In1.Cu" "In2.Cu" "In3.Cu" "In4.Cu" "In5.Cu" "In6.Cu")
			(hatch none 0.5)
			(connect_pads
				(clearance 0)
			)
			(min_thickness 0.25)
			(keepout
				(tracks allowed)
				(vias not_allowed)
				(pads allowed)
				(copperpour not_allowed)
				(footprints allowed)
			)
			(placement
				(enabled no)
				(sheetname "")
			)
			(fill
				(thermal_gap 0.5)
				(thermal_bridge_width 0.5)
				(island_removal_mode 0)
			)
			(polygon
				(pts
					(xy 369.878356 -21.753576) (xy 371.351556 -21.753576) (xy 371.351556 -23.226776) (xy 369.878356 -23.226776)
				)
			)
		)
		(zone
			(layers "F.Cu" "B.Cu" "In1.Cu" "In2.Cu" "In3.Cu" "In4.Cu" "In5.Cu" "In6.Cu")
			(hatch none 0.5)
			(connect_pads
				(clearance 0)
			)
			(min_thickness 0.25)
			(keepout
				(tracks allowed)
				(vias not_allowed)
				(pads allowed)
				(copperpour not_allowed)
				(footprints allowed)
			)
			(placement
				(enabled no)
				(sheetname "")
			)
			(fill
				(thermal_gap 0.5)
				(thermal_bridge_width 0.5)
				(island_removal_mode 0)
			)
			(polygon
				(pts
					(xy 369.878356 -17.054576) (xy 371.351556 -17.054576) (xy 371.351556 -18.527776) (xy 369.878356 -18.527776)
				)
			)
		)
		(zone
			(layers "F.Cu" "B.Cu" "In1.Cu" "In2.Cu" "In3.Cu" "In4.Cu" "In5.Cu" "In6.Cu")
			(hatch none 0.5)
			(connect_pads
				(clearance 0)
			)
			(min_thickness 0.25)
			(keepout
				(tracks allowed)
				(vias not_allowed)
				(pads allowed)
				(copperpour not_allowed)
				(footprints allowed)
			)
			(placement
				(enabled no)
				(sheetname "")
			)
			(fill
				(thermal_gap 0.5)
				(thermal_bridge_width 0.5)
				(island_removal_mode 0)
			)
			(polygon
				(pts
					(xy 369.878356 -12.050776) (xy 371.351556 -12.050776) (xy 371.351556 -13.523976) (xy 369.878356 -13.523976)
				)
			)
		)
		(zone
			(layers "F.Cu" "B.Cu" "In1.Cu" "In2.Cu" "In3.Cu" "In4.Cu" "In5.Cu" "In6.Cu")
			(hatch none 0.5)
			(connect_pads
				(clearance 0)
			)
			(min_thickness 0.25)
			(keepout
				(tracks allowed)
				(vias not_allowed)
				(pads allowed)
				(copperpour not_allowed)
				(footprints allowed)
			)
			(placement
				(enabled no)
				(sheetname "")
			)
			(fill
				(thermal_gap 0.5)
				(thermal_bridge_width 0.5)
				(island_removal_mode 0)
			)
			(polygon
				(pts
					(xy 369.929156 -14.616176) (xy 371.300756 -14.616176) (xy 371.300756 -15.987776) (xy 369.929156 -15.987776)
				)
			)
		)
		(zone
			(layers "F.Cu" "B.Cu" "In1.Cu" "In2.Cu" "In3.Cu" "In4.Cu" "In5.Cu" "In6.Cu")
			(hatch none 0.5)
			(connect_pads
				(clearance 0)
			)
			(min_thickness 0.25)
			(keepout
				(tracks allowed)
				(vias not_allowed)
				(pads allowed)
				(copperpour not_allowed)
				(footprints allowed)
			)
			(placement
				(enabled no)
				(sheetname "")
			)
			(fill
				(thermal_gap 0.5)
				(thermal_bridge_width 0.5)
				(island_removal_mode 0)
			)
			(polygon
				(pts
					(xy 371.453156 -35.240976) (xy 371.453156 -36.129976) (xy 369.776756 -36.129976) (xy 369.776756 -34.453576)
					(xy 371.453156 -34.453576)
				)
			)
		)
	)
	(footprint ""
		(layer "F.Cu")
		(at 306.319936 -14.999716)
		(property "Reference" "J9"
			(at -4.966208 -7.545832 0)
			(unlocked yes)
			(layer "F.SilkS")
			(effects
				(font
					(size 0.7874 0.5842)
					(thickness 0.1524)
				)
				(justify left)
			)
		)
		(property "Value" ""
			(at 0 0 0)
			(layer "F.Fab")
			(effects
				(font
					(size 1.27 1.27)
				)
			)
		)
		(duplicate_pad_numbers_are_jumpers no)
		(fp_line
			(start -4.92506 -6.849872)
			(end 12.925044 -6.849872)
			(stroke
				(width 0.1524)
				(type default)
			)
			(layer "F.SilkS")
		)
		(fp_line
			(start -4.92506 28.450032)
			(end -4.92506 -6.849872)
			(stroke
				(width 0.1524)
				(type default)
			)
			(layer "F.SilkS")
		)
		(fp_line
			(start -1.925066 -3.850132)
			(end 9.92505 -3.850132)
			(stroke
				(width 0.1524)
				(type default)
			)
			(layer "F.SilkS")
		)
		(fp_line
			(start -1.925066 25.450038)
			(end -1.925066 -3.850132)
			(stroke
				(width 0.1524)
				(type default)
			)
			(layer "F.SilkS")
		)
		(fp_line
			(start 9.92505 -3.850132)
			(end 9.92505 25.450038)
			(stroke
				(width 0.1524)
				(type default)
			)
			(layer "F.SilkS")
		)
		(fp_line
			(start 9.92505 25.450038)
			(end -1.925066 25.450038)
			(stroke
				(width 0.1524)
				(type default)
			)
			(layer "F.SilkS")
		)
		(fp_line
			(start 12.925044 -6.849872)
			(end 12.925044 28.450032)
			(stroke
				(width 0.1524)
				(type default)
			)
			(layer "F.SilkS")
		)
		(fp_line
			(start 12.925044 28.450032)
			(end -4.92506 28.450032)
			(stroke
				(width 0.1524)
				(type default)
			)
			(layer "F.SilkS")
		)
		(fp_line
			(start -4.92506 -6.849872)
			(end 12.925044 -6.849872)
			(stroke
				(width 0.1524)
				(type default)
			)
			(layer "B.SilkS")
		)
		(fp_line
			(start -4.92506 28.450032)
			(end -4.92506 -6.849872)
			(stroke
				(width 0.1524)
				(type default)
			)
			(layer "B.SilkS")
		)
		(fp_line
			(start 12.925044 -6.849872)
			(end 12.925044 28.450032)
			(stroke
				(width 0.1524)
				(type default)
			)
			(layer "B.SilkS")
		)
		(fp_line
			(start 12.925044 28.450032)
			(end -4.92506 28.450032)
			(stroke
				(width 0.1524)
				(type default)
			)
			(layer "B.SilkS")
		)
		(fp_poly
			(pts
				(xy -0.635508 -0.646684) (xy -0.635508 4.636516) (xy 2.641092 4.636516) (xy 2.641092 -0.646684)
			)
			(stroke
				(width 0)
				(type default)
			)
			(fill no)
			(layer "B.CrtYd")
		)
		(fp_poly
			(pts
				(xy -0.635508 7.354316) (xy 2.641092 7.354316) (xy 2.641092 12.637516) (xy -0.635508 12.637516)
			)
			(stroke
				(width 0)
				(type default)
			)
			(fill no)
			(layer "B.CrtYd")
		)
		(fp_poly
			(pts
				(xy 5.358892 -0.646684) (xy 8.635492 -0.646684) (xy 8.635492 4.636516) (xy 5.358892 4.636516)
			)
			(stroke
				(width 0)
				(type default)
			)
			(fill no)
			(layer "B.CrtYd")
		)
		(fp_poly
			(pts
				(xy 5.358892 7.354316) (xy 8.635492 7.354316) (xy 8.635492 12.637516) (xy 5.358892 12.637516)
			)
			(stroke
				(width 0)
				(type default)
			)
			(fill no)
			(layer "B.CrtYd")
		)
		(fp_poly
			(pts
				(arc
					(start 5.333492 5.500116)
					(mid 2.666492 5.500116)
					(end 5.333492 5.500116)
				)
			)
			(stroke
				(width 0)
				(type default)
			)
			(fill no)
			(layer "B.CrtYd")
		)
		(fp_poly
			(pts
				(xy -1.925066 25.450038) (xy 9.92505 25.450038) (xy 9.92505 -3.850132) (xy -1.925066 -3.850132)
			)
			(stroke
				(width 0)
				(type default)
			)
			(fill no)
			(layer "F.CrtYd")
		)
		(fp_line
			(start -4.92506 -6.849872)
			(end 12.925044 -6.849872)
			(stroke
				(width 0.1)
				(type default)
			)
			(layer "B.Fab")
		)
		(fp_line
			(start -4.92506 28.450032)
			(end -4.92506 -6.849872)
			(stroke
				(width 0.1)
				(type default)
			)
			(layer "B.Fab")
		)
		(fp_line
			(start 12.925044 -6.849872)
			(end 12.925044 28.450032)
			(stroke
				(width 0.1)
				(type default)
			)
			(layer "B.Fab")
		)
		(fp_line
			(start 12.925044 28.450032)
			(end -4.92506 28.450032)
			(stroke
				(width 0.1)
				(type default)
			)
			(layer "B.Fab")
		)
		(fp_line
			(start -1.925066 -3.850132)
			(end 9.92505 -3.850132)
			(stroke
				(width 0.1)
				(type default)
			)
			(layer "F.Fab")
		)
		(fp_line
			(start -1.925066 25.450038)
			(end -1.925066 -3.850132)
			(stroke
				(width 0.1)
				(type default)
			)
			(layer "F.Fab")
		)
		(fp_line
			(start 9.92505 -3.850132)
			(end 9.92505 25.450038)
			(stroke
				(width 0.1)
				(type default)
			)
			(layer "F.Fab")
		)
		(fp_line
			(start 9.92505 25.450038)
			(end -1.925066 25.450038)
			(stroke
				(width 0.1)
				(type default)
			)
			(layer "F.Fab")
		)
		(fp_poly
			(pts
				(xy -2.057908 -0.079502) (xy -3.962908 -0.841502) (xy -3.962908 0.682498)
			)
			(stroke
				(width 0)
				(type default)
			)
			(fill yes)
			(layer "F.Fab")
		)
		(fp_text user "A2"
			(at -3.797808 1.908048 0)
			(unlocked yes)
			(layer "F.SilkS")
			(effects
				(font
					(size 0.7874 0.5842)
					(thickness 0.1524)
				)
				(justify left)
			)
		)
		(fp_text user "A3"
			(at -3.797808 3.908044 0)
			(unlocked yes)
			(layer "F.SilkS")
			(effects
				(font
					(size 0.7874 0.5842)
					(thickness 0.1524)
				)
				(justify left)
			)
		)
		(fp_text user "D1"
			(at -3.797808 7.908036 0)
			(unlocked yes)
			(layer "F.SilkS")
			(effects
				(font
					(size 0.7874 0.5842)
					(thickness 0.1524)
				)
				(justify left)
			)
		)
		(fp_text user "D2"
			(at -3.797808 9.908032 0)
			(unlocked yes)
			(layer "F.SilkS")
			(effects
				(font
					(size 0.7874 0.5842)
					(thickness 0.1524)
				)
				(justify left)
			)
		)
		(fp_text user "D3"
			(at -3.797808 11.908282 0)
			(unlocked yes)
			(layer "F.SilkS")
			(effects
				(font
					(size 0.7874 0.5842)
					(thickness 0.1524)
				)
				(justify left)
			)
		)
		(fp_text user "PRESS-FIT"
			(at -2.743708 -5.760974 0)
			(unlocked yes)
			(layer "F.SilkS")
			(effects
				(font
					(size 1.6002 1.1938)
					(thickness 0.1524)
				)
				(justify left)
			)
		)
		(fp_text user "A1"
			(at -0.597408 -4.409948 0)
			(unlocked yes)
			(layer "F.SilkS")
			(effects
				(font
					(size 0.7874 0.5842)
					(thickness 0.1524)
				)
				(justify left)
			)
		)
		(fp_text user "C3"
			(at 10.273792 11.679682 0)
			(unlocked yes)
			(layer "F.SilkS")
			(effects
				(font
					(size 0.7874 0.5842)
					(thickness 0.1524)
				)
				(justify left)
			)
		)
		(fp_text user "C1"
			(at 10.375392 8.187436 0)
			(unlocked yes)
			(layer "F.SilkS")
			(effects
				(font
					(size 0.7874 0.5842)
					(thickness 0.1524)
				)
				(justify left)
			)
		)
		(fp_text user "C2"
			(at 10.426192 9.908032 0)
			(unlocked yes)
			(layer "F.SilkS")
			(effects
				(font
					(size 0.7874 0.5842)
					(thickness 0.1524)
				)
				(justify left)
			)
		)
		(fp_text user "B2"
			(at 10.534396 2.570988 90)
			(unlocked yes)
			(layer "F.SilkS")
			(effects
				(font
					(size 0.7874 0.5842)
					(thickness 0.1524)
				)
				(justify left)
			)
		)
		(fp_text user "B3"
			(at 10.553192 4.679188 90)
			(unlocked yes)
			(layer "F.SilkS")
			(effects
				(font
					(size 0.7874 0.5842)
					(thickness 0.1524)
				)
				(justify left)
			)
		)
		(fp_text user "B1"
			(at 10.5664 0.310388 90)
			(unlocked yes)
			(layer "F.SilkS")
			(effects
				(font
					(size 0.7874 0.5842)
					(thickness 0.1524)
				)
				(justify left)
			)
		)
		(fp_text user "A1"
			(at -0.902208 -0.091948 0)
			(unlocked yes)
			(layer "B.SilkS")
			(effects
				(font
					(size 0.7874 0.5842)
					(thickness 0.1524)
				)
				(justify left mirror)
			)
		)
		(fp_text user "A2"
			(at -0.902208 1.908048 0)
			(unlocked yes)
			(layer "B.SilkS")
			(effects
				(font
					(size 0.7874 0.5842)
					(thickness 0.1524)
				)
				(justify left mirror)
			)
		)
		(fp_text user "A3"
			(at -0.902208 3.908044 0)
			(unlocked yes)
			(layer "B.SilkS")
			(effects
				(font
					(size 0.7874 0.5842)
					(thickness 0.1524)
				)
				(justify left mirror)
			)
		)
		(fp_text user "D1"
			(at -0.902208 7.908036 0)
			(unlocked yes)
			(layer "B.SilkS")
			(effects
				(font
					(size 0.7874 0.5842)
					(thickness 0.1524)
				)
				(justify left mirror)
			)
		)
		(fp_text user "D2"
			(at -0.902208 9.908032 0)
			(unlocked yes)
			(layer "B.SilkS")
			(effects
				(font
					(size 0.7874 0.5842)
					(thickness 0.1524)
				)
				(justify left mirror)
			)
		)
		(fp_text user "D3"
			(at -0.902208 11.908282 0)
			(unlocked yes)
			(layer "B.SilkS")
			(effects
				(font
					(size 0.7874 0.5842)
					(thickness 0.1524)
				)
				(justify left mirror)
			)
		)
		(fp_text user "B1"
			(at 10.273792 -0.091948 0)
			(unlocked yes)
			(layer "B.SilkS")
			(effects
				(font
					(size 0.7874 0.5842)
					(thickness 0.1524)
				)
				(justify left mirror)
			)
		)
		(fp_text user "B2"
			(at 10.273792 1.908048 0)
			(unlocked yes)
			(layer "B.SilkS")
			(effects
				(font
					(size 0.7874 0.5842)
					(thickness 0.1524)
				)
				(justify left mirror)
			)
		)
		(fp_text user "B3"
			(at 10.273792 3.908044 0)
			(unlocked yes)
			(layer "B.SilkS")
			(effects
				(font
					(size 0.7874 0.5842)
					(thickness 0.1524)
				)
				(justify left mirror)
			)
		)
		(fp_text user "C1"
			(at 10.273792 7.908036 0)
			(unlocked yes)
			(layer "B.SilkS")
			(effects
				(font
					(size 0.7874 0.5842)
					(thickness 0.1524)
				)
				(justify left mirror)
			)
		)
		(fp_text user "C2"
			(at 10.273792 9.908032 0)
			(unlocked yes)
			(layer "B.SilkS")
			(effects
				(font
					(size 0.7874 0.5842)
					(thickness 0.1524)
				)
				(justify left mirror)
			)
		)
		(fp_text user "C3"
			(at 10.273792 11.908282 0)
			(unlocked yes)
			(layer "B.SilkS")
			(effects
				(font
					(size 0.7874 0.5842)
					(thickness 0.1524)
				)
				(justify left mirror)
			)
		)
		(fp_text user "PRESS-FIT"
			(at 11.251692 -5.430774 0)
			(unlocked yes)
			(layer "B.SilkS")
			(effects
				(font
					(size 1.6002 1.1938)
					(thickness 0.1524)
				)
				(justify left mirror)
			)
		)
		(fp_text user "A1"
			(at -0.902208 -0.091948 0)
			(unlocked yes)
			(layer "B.Fab")
			(effects
				(font
					(size 0.7874 0.5842)
					(thickness 0.000001)
				)
				(justify left mirror)
			)
		)
		(fp_text user "A2"
			(at -0.902208 1.908048 0)
			(unlocked yes)
			(layer "B.Fab")
			(effects
				(font
					(size 0.7874 0.5842)
					(thickness 0.000001)
				)
				(justify left mirror)
			)
		)
		(fp_text user "A3"
			(at -0.902208 3.908044 0)
			(unlocked yes)
			(layer "B.Fab")
			(effects
				(font
					(size 0.7874 0.5842)
					(thickness 0.000001)
				)
				(justify left mirror)
			)
		)
		(fp_text user "D1"
			(at -0.902208 7.908036 0)
			(unlocked yes)
			(layer "B.Fab")
			(effects
				(font
					(size 0.7874 0.5842)
					(thickness 0.000001)
				)
				(justify left mirror)
			)
		)
		(fp_text user "D2"
			(at -0.902208 9.908032 0)
			(unlocked yes)
			(layer "B.Fab")
			(effects
				(font
					(size 0.7874 0.5842)
					(thickness 0.000001)
				)
				(justify left mirror)
			)
		)
		(fp_text user "D3"
			(at -0.902208 11.908282 0)
			(unlocked yes)
			(layer "B.Fab")
			(effects
				(font
					(size 0.7874 0.5842)
					(thickness 0.000001)
				)
				(justify left mirror)
			)
		)
		(fp_text user "B1"
			(at 10.273792 -0.091948 0)
			(unlocked yes)
			(layer "B.Fab")
			(effects
				(font
					(size 0.7874 0.5842)
					(thickness 0.000001)
				)
				(justify left mirror)
			)
		)
		(fp_text user "B2"
			(at 10.273792 1.908048 0)
			(unlocked yes)
			(layer "B.Fab")
			(effects
				(font
					(size 0.7874 0.5842)
					(thickness 0.000001)
				)
				(justify left mirror)
			)
		)
		(fp_text user "B3"
			(at 10.273792 3.908044 0)
			(unlocked yes)
			(layer "B.Fab")
			(effects
				(font
					(size 0.7874 0.5842)
					(thickness 0.000001)
				)
				(justify left mirror)
			)
		)
		(fp_text user "C1"
			(at 10.273792 7.908036 0)
			(unlocked yes)
			(layer "B.Fab")
			(effects
				(font
					(size 0.7874 0.5842)
					(thickness 0.000001)
				)
				(justify left mirror)
			)
		)
		(fp_text user "C2"
			(at 10.273792 9.908032 0)
			(unlocked yes)
			(layer "B.Fab")
			(effects
				(font
					(size 0.7874 0.5842)
					(thickness 0.000001)
				)
				(justify left mirror)
			)
		)
		(fp_text user "C3"
			(at 10.273792 11.908282 0)
			(unlocked yes)
			(layer "B.Fab")
			(effects
				(font
					(size 0.7874 0.5842)
					(thickness 0.000001)
				)
				(justify left mirror)
			)
		)
		(fp_text user "PRESS-FIT"
			(at 11.251692 -5.430774 0)
			(unlocked yes)
			(layer "B.Fab")
			(effects
				(font
					(size 1.6002 1.1938)
					(thickness 0.000001)
				)
				(justify left mirror)
			)
		)
		(fp_text user "A2"
			(at -3.797808 1.908048 0)
			(unlocked yes)
			(layer "F.Fab")
			(effects
				(font
					(size 0.7874 0.5842)
					(thickness 0.000001)
				)
				(justify left)
			)
		)
		(fp_text user "A3"
			(at -3.797808 3.908044 0)
			(unlocked yes)
			(layer "F.Fab")
			(effects
				(font
					(size 0.7874 0.5842)
					(thickness 0.000001)
				)
				(justify left)
			)
		)
		(fp_text user "D1"
			(at -3.797808 7.908036 0)
			(unlocked yes)
			(layer "F.Fab")
			(effects
				(font
					(size 0.7874 0.5842)
					(thickness 0.000001)
				)
				(justify left)
			)
		)
		(fp_text user "D2"
			(at -3.797808 9.908032 0)
			(unlocked yes)
			(layer "F.Fab")
			(effects
				(font
					(size 0.7874 0.5842)
					(thickness 0.000001)
				)
				(justify left)
			)
		)
		(fp_text user "D3"
			(at -3.797808 11.908282 0)
			(unlocked yes)
			(layer "F.Fab")
			(effects
				(font
					(size 0.7874 0.5842)
					(thickness 0.000001)
				)
				(justify left)
			)
		)
		(fp_text user "A1"
			(at -3.518408 -1.412748 0)
			(unlocked yes)
			(layer "F.Fab")
			(effects
				(font
					(size 0.7874 0.5842)
					(thickness 0.000001)
				)
				(justify left)
			)
		)
		(fp_text user "PRESS-FIT"
			(at -2.819908 -5.430774 0)
			(unlocked yes)
			(layer "F.Fab")
			(effects
				(font
					(size 1.6002 1.1938)
					(thickness 0.000001)
				)
				(justify left)
			)
		)
		(fp_text user "B1"
			(at 10.426192 -0.091948 0)
			(unlocked yes)
			(layer "F.Fab")
			(effects
				(font
					(size 0.7874 0.5842)
					(thickness 0.000001)
				)
				(justify left)
			)
		)
		(fp_text user "B2"
			(at 10.426192 1.908048 0)
			(unlocked yes)
			(layer "F.Fab")
			(effects
				(font
					(size 0.7874 0.5842)
					(thickness 0.000001)
				)
				(justify left)
			)
		)
		(fp_text user "B3"
			(at 10.426192 3.908044 0)
			(unlocked yes)
			(layer "F.Fab")
			(effects
				(font
					(size 0.7874 0.5842)
					(thickness 0.000001)
				)
				(justify left)
			)
		)
		(fp_text user "C1"
			(at 10.426192 7.908036 0)
			(unlocked yes)
			(layer "F.Fab")
			(effects
				(font
					(size 0.7874 0.5842)
					(thickness 0.000001)
				)
				(justify left)
			)
		)
		(fp_text user "C2"
			(at 10.426192 9.908032 0)
			(unlocked yes)
			(layer "F.Fab")
			(effects
				(font
					(size 0.7874 0.5842)
					(thickness 0.000001)
				)
				(justify left)
			)
		)
		(fp_text user "C3"
			(at 10.426192 11.908282 0)
			(unlocked yes)
			(layer "F.Fab")
			(effects
				(font
					(size 0.7874 0.5842)
					(thickness 0.000001)
				)
				(justify left)
			)
		)
		(pad "" np_thru_hole circle
			(at 3.999992 5.500116)
			(size 2.159 2.159)
			(drill 2.159)
			(layers "*.Cu" "*.Mask")
			(clearance 0.381)
			(thermal_gap 0.381)
		)
		(pad "A1" thru_hole rect
			(at 0 0)
			(size 1.1684 1.1684)
			(drill 0.762)
			(layers "*.Cu" "*.Mask")
			(remove_unused_layers no)
			(net "GND")
			(clearance 0.0508)
			(thermal_gap 0.0508)
			(padstack
				(mode front_inner_back)
				(layer "Inner"
					(shape circle)
					(size 1.1684 1.1684)
					(clearance 0.0508)
				)
				(layer "B.Cu"
					(shape rect)
					(size 1.1684 1.1684)
					(clearance 0.0508)
				)
			)
		)
		(pad "A2" thru_hole circle
			(at 0 1.999996)
			(size 1.1684 1.1684)
			(drill 0.762)
			(layers "*.Cu" "*.Mask")
			(remove_unused_layers no)
			(net "GND")
			(clearance 0.0508)
			(thermal_gap 0.0508)
		)
		(pad "A3" thru_hole circle
			(at 0 3.999992)
			(size 1.1684 1.1684)
			(drill 0.762)
			(layers "*.Cu" "*.Mask")
			(remove_unused_layers no)
			(net "GND")
			(clearance 0.0508)
			(thermal_gap 0.0508)
		)
		(pad "A4" thru_hole circle
			(at 1.999996 0)
			(size 1.1684 1.1684)
			(drill 0.762)
			(layers "*.Cu" "*.Mask")
			(remove_unused_layers no)
			(net "GND")
			(clearance 0.0508)
			(thermal_gap 0.0508)
		)
		(pad "A5" thru_hole circle
			(at 1.999996 1.999996)
			(size 1.1684 1.1684)
			(drill 0.762)
			(layers "*.Cu" "*.Mask")
			(remove_unused_layers no)
			(net "GND")
			(clearance 0.0508)
			(thermal_gap 0.0508)
		)
		(pad "A6" thru_hole circle
			(at 1.999996 3.999992)
			(size 1.1684 1.1684)
			(drill 0.762)
			(layers "*.Cu" "*.Mask")
			(remove_unused_layers no)
			(net "GND")
			(clearance 0.0508)
			(thermal_gap 0.0508)
		)
		(pad "B1" thru_hole circle
			(at 7.999984 0)
			(size 1.1684 1.1684)
			(drill 0.762)
			(layers "*.Cu" "*.Mask")
			(remove_unused_layers no)
			(net "P12V")
			(clearance 0.0508)
			(thermal_gap 0.0508)
		)
		(pad "B2" thru_hole circle
			(at 7.999984 1.999996)
			(size 1.1684 1.1684)
			(drill 0.762)
			(layers "*.Cu" "*.Mask")
			(remove_unused_layers no)
			(net "P12V")
			(clearance 0.0508)
			(thermal_gap 0.0508)
		)
		(pad "B3" thru_hole circle
			(at 7.999984 3.999992)
			(size 1.1684 1.1684)
			(drill 0.762)
			(layers "*.Cu" "*.Mask")
			(remove_unused_layers no)
			(net "P12V")
			(clearance 0.0508)
			(thermal_gap 0.0508)
		)
		(pad "B4" thru_hole circle
			(at 5.999988 0)
			(size 1.1684 1.1684)
			(drill 0.762)
			(layers "*.Cu" "*.Mask")
			(remove_unused_layers no)
			(net "P12V")
			(clearance 0.0508)
			(thermal_gap 0.0508)
		)
		(pad "B5" thru_hole circle
			(at 5.999988 1.999996)
			(size 1.1684 1.1684)
			(drill 0.762)
			(layers "*.Cu" "*.Mask")
			(remove_unused_layers no)
			(net "P12V")
			(clearance 0.0508)
			(thermal_gap 0.0508)
		)
		(pad "B6" thru_hole circle
			(at 5.999988 3.999992)
			(size 1.1684 1.1684)
			(drill 0.762)
			(layers "*.Cu" "*.Mask")
			(remove_unused_layers no)
			(net "P12V")
			(clearance 0.0508)
			(thermal_gap 0.0508)
		)
		(pad "C1" thru_hole circle
			(at 7.999984 7.999984)
			(size 1.1684 1.1684)
			(drill 0.762)
			(layers "*.Cu" "*.Mask")
			(remove_unused_layers no)
			(net "P12V")
			(clearance 0.0508)
			(thermal_gap 0.0508)
		)
		(pad "C2" thru_hole circle
			(at 7.999984 9.99998)
			(size 1.1684 1.1684)
			(drill 0.762)
			(layers "*.Cu" "*.Mask")
			(remove_unused_layers no)
			(net "P12V")
			(clearance 0.0508)
			(thermal_gap 0.0508)
		)
		(pad "C3" thru_hole circle
			(at 7.999984 11.999976)
			(size 1.1684 1.1684)
			(drill 0.762)
			(layers "*.Cu" "*.Mask")
			(remove_unused_layers no)
			(net "P12V")
			(clearance 0.0508)
			(thermal_gap 0.0508)
		)
		(pad "C4" thru_hole circle
			(at 5.999988 7.999984)
			(size 1.1684 1.1684)
			(drill 0.762)
			(layers "*.Cu" "*.Mask")
			(remove_unused_layers no)
			(net "P12V")
			(clearance 0.0508)
			(thermal_gap 0.0508)
		)
		(pad "C5" thru_hole circle
			(at 5.999988 9.99998)
			(size 1.1684 1.1684)
			(drill 0.762)
			(layers "*.Cu" "*.Mask")
			(remove_unused_layers no)
			(net "P12V")
			(clearance 0.0508)
			(thermal_gap 0.0508)
		)
		(pad "C6" thru_hole circle
			(at 5.999988 11.999976)
			(size 1.1684 1.1684)
			(drill 0.762)
			(layers "*.Cu" "*.Mask")
			(remove_unused_layers no)
			(net "P12V")
			(clearance 0.0508)
			(thermal_gap 0.0508)
		)
		(pad "D1" thru_hole circle
			(at 0 7.999984)
			(size 1.1684 1.1684)
			(drill 0.762)
			(layers "*.Cu" "*.Mask")
			(remove_unused_layers no)
			(net "GND")
			(clearance 0.0508)
			(thermal_gap 0.0508)
		)
		(pad "D2" thru_hole circle
			(at 0 9.99998)
			(size 1.1684 1.1684)
			(drill 0.762)
			(layers "*.Cu" "*.Mask")
			(remove_unused_layers no)
			(net "GND")
			(clearance 0.0508)
			(thermal_gap 0.0508)
		)
		(pad "D3" thru_hole circle
			(at 0 11.999976)
			(size 1.1684 1.1684)
			(drill 0.762)
			(layers "*.Cu" "*.Mask")
			(remove_unused_layers no)
			(net "GND")
			(clearance 0.0508)
			(thermal_gap 0.0508)
		)
		(pad "D4" thru_hole circle
			(at 1.999996 7.999984)
			(size 1.1684 1.1684)
			(drill 0.762)
			(layers "*.Cu" "*.Mask")
			(remove_unused_layers no)
			(net "GND")
			(clearance 0.0508)
			(thermal_gap 0.0508)
		)
		(pad "D5" thru_hole circle
			(at 1.999996 9.99998)
			(size 1.1684 1.1684)
			(drill 0.762)
			(layers "*.Cu" "*.Mask")
			(remove_unused_layers no)
			(net "GND")
			(clearance 0.0508)
			(thermal_gap 0.0508)
		)
		(pad "D6" thru_hole circle
			(at 1.999996 11.999976)
			(size 1.1684 1.1684)
			(drill 0.762)
			(layers "*.Cu" "*.Mask")
			(remove_unused_layers no)
			(net "GND")
			(clearance 0.0508)
			(thermal_gap 0.0508)
		)
		(zone
			(layers "F.Cu" "B.Cu" "In1.Cu" "In2.Cu" "In3.Cu" "In4.Cu" "In5.Cu" "In6.Cu")
			(hatch none 0.5)
			(connect_pads
				(clearance 0)
			)
			(min_thickness 0.25)
			(keepout
				(tracks not_allowed)
				(vias allowed)
				(pads allowed)
				(copperpour not_allowed)
				(footprints allowed)
			)
			(placement
				(enabled no)
				(sheetname "")
			)
			(fill
				(thermal_gap 0.5)
				(thermal_bridge_width 0.5)
				(island_removal_mode 0)
			)
			(polygon
				(pts
					(arc
						(start 311.805574 -9.4996)
						(mid 308.834282 -9.4996)
						(end 311.805574 -9.4996)
					)
				)
			)
		)
		(zone
			(layer "B.Cu")
			(hatch none 0.5)
			(connect_pads
				(clearance 0)
			)
			(min_thickness 0.25)
			(keepout
				(tracks allowed)
				(vias not_allowed)
				(pads allowed)
				(copperpour not_allowed)
				(footprints allowed)
			)
			(placement
				(enabled no)
				(sheetname "")
			)
			(fill
				(thermal_gap 0.5)
				(thermal_bridge_width 0.5)
				(island_removal_mode 0)
			)
			(polygon
				(pts
					(xy 305.684428 -10.3632) (xy 308.961028 -10.3632) (xy 308.961028 -15.6464) (xy 305.684428 -15.6464)
				)
			)
		)
		(zone
			(layer "B.Cu")
			(hatch none 0.5)
			(connect_pads
				(clearance 0)
			)
			(min_thickness 0.25)
			(keepout
				(tracks allowed)
				(vias not_allowed)
				(pads allowed)
				(copperpour not_allowed)
				(footprints allowed)
			)
			(placement
				(enabled no)
				(sheetname "")
			)
			(fill
				(thermal_gap 0.5)
				(thermal_bridge_width 0.5)
				(island_removal_mode 0)
			)
			(polygon
				(pts
					(xy 305.684428 -2.3622) (xy 308.961028 -2.3622) (xy 308.961028 -7.6454) (xy 305.684428 -7.6454)
				)
			)
		)
		(zone
			(layer "B.Cu")
			(hatch none 0.5)
			(connect_pads
				(clearance 0)
			)
			(min_thickness 0.25)
			(keepout
				(tracks allowed)
				(vias not_allowed)
				(pads allowed)
				(copperpour not_allowed)
				(footprints allowed)
			)
			(placement
				(enabled no)
				(sheetname "")
			)
			(fill
				(thermal_gap 0.5)
				(thermal_bridge_width 0.5)
				(island_removal_mode 0)
			)
			(polygon
				(pts
					(xy 311.678828 -10.3632) (xy 314.955428 -10.3632) (xy 314.955428 -15.6464) (xy 311.678828 -15.6464)
				)
			)
		)
		(zone
			(layer "B.Cu")
			(hatch none 0.5)
			(connect_pads
				(clearance 0)
			)
			(min_thickness 0.25)
			(keepout
				(tracks allowed)
				(vias not_allowed)
				(pads allowed)
				(copperpour not_allowed)
				(footprints allowed)
			)
			(placement
				(enabled no)
				(sheetname "")
			)
			(fill
				(thermal_gap 0.5)
				(thermal_bridge_width 0.5)
				(island_removal_mode 0)
			)
			(polygon
				(pts
					(xy 311.678828 -2.3622) (xy 314.955428 -2.3622) (xy 314.955428 -7.6454) (xy 311.678828 -7.6454)
				)
			)
		)
		(zone
			(layer "B.Cu")
			(hatch none 0.5)
			(connect_pads
				(clearance 0)
			)
			(min_thickness 0.25)
			(keepout
				(tracks allowed)
				(vias not_allowed)
				(pads allowed)
				(copperpour not_allowed)
				(footprints allowed)
			)
			(placement
				(enabled no)
				(sheetname "")
			)
			(fill
				(thermal_gap 0.5)
				(thermal_bridge_width 0.5)
				(island_removal_mode 0)
			)
			(polygon
				(pts
					(arc
						(start 311.653428 -9.4996)
						(mid 308.986428 -9.4996)
						(end 311.653428 -9.4996)
					)
				)
			)
		)
	)
	(footprint ""
		(layer "F.Cu")
		(at 313.07024 -26.126694)
		(property "Reference" "R32"
			(at -6.604 -1.565148 0)
			(unlocked yes)
			(layer "F.SilkS")
			(effects
				(font
					(size 0.7874 0.5842)
					(thickness 0.1524)
				)
				(justify left)
			)
		)
		(property "Value" ""
			(at 0 0 0)
			(layer "F.Fab")
			(effects
				(font
					(size 1.27 1.27)
				)
			)
		)
		(duplicate_pad_numbers_are_jumpers no)
		(fp_line
			(start -0.7874 -0.4064)
			(end 0.7874 -0.4064)
			(stroke
				(width 0.1524)
				(type default)
			)
			(layer "F.SilkS")
		)
		(fp_line
			(start -0.7874 0.4064)
			(end -0.7874 -0.4064)
			(stroke
				(width 0.1524)
				(type default)
			)
			(layer "F.SilkS")
		)
		(fp_line
			(start 0.7874 -0.4064)
			(end 0.7874 0.4064)
			(stroke
				(width 0.1524)
				(type default)
			)
			(layer "F.SilkS")
		)
		(fp_line
			(start 0.7874 0.4064)
			(end -0.7874 0.4064)
			(stroke
				(width 0.1524)
				(type default)
			)
			(layer "F.SilkS")
		)
		(fp_poly
			(pts
				(xy -0.508 0.2794) (xy -0.508 0.2286) (xy -0.635 0.2286) (xy -0.635 -0.254) (xy -0.5334 -0.254)
				(xy -0.5334 -0.2794) (xy 0.5334 -0.2794) (xy 0.5334 -0.254) (xy 0.635 -0.254) (xy 0.635 0.254) (xy 0.5334 0.254)
				(xy 0.5334 0.2794)
			)
			(stroke
				(width 0)
				(type default)
			)
			(fill no)
			(layer "F.CrtYd")
		)
		(pad "1" smd rect
			(at 0.40005 0)
			(size 0.4572 0.508)
			(layers "F.Cu" "F.Mask" "F.Paste")
			(net "P3V3_BLAD2")
		)
		(pad "2" smd rect
			(at -0.40005 0)
			(size 0.4572 0.508)
			(layers "F.Cu" "F.Mask" "F.Paste")
			(net "ENET10G_4_RS1")
		)
	)
	(footprint ""
		(layer "F.Cu")
		(at 92.331286 -35.377628 180)
		(property "Reference" "FS4"
			(at 2.872232 4.248404 0)
			(unlocked yes)
			(layer "F.SilkS")
			(effects
				(font
					(size 0.7874 0.5842)
					(thickness 0.1524)
				)
				(justify left)
			)
		)
		(property "Value" ""
			(at 0 0 180)
			(layer "F.Fab")
			(effects
				(font
					(size 1.27 1.27)
				)
			)
		)
		(duplicate_pad_numbers_are_jumpers no)
		(fp_line
			(start 3.550412 1.050036)
			(end -0.650494 1.050036)
			(stroke
				(width 0.1524)
				(type default)
			)
			(layer "F.SilkS")
		)
		(fp_line
			(start 3.550412 -1.050036)
			(end 3.550412 1.050036)
			(stroke
				(width 0.1524)
				(type default)
			)
			(layer "F.SilkS")
		)
		(fp_line
			(start -0.650494 1.050036)
			(end -0.650494 -1.050036)
			(stroke
				(width 0.1524)
				(type default)
			)
			(layer "F.SilkS")
		)
		(fp_line
			(start -0.650494 -1.050036)
			(end 3.550412 -1.050036)
			(stroke
				(width 0.1524)
				(type default)
			)
			(layer "F.SilkS")
		)
		(fp_poly
			(pts
				(xy 3.228086 -0.9652) (xy 3.228086 -1.100074) (xy -0.327914 -1.100074) (xy -0.327914 -0.9652) (xy -0.556514 -0.9652)
				(xy -0.556514 0.9652) (xy -0.327914 0.9652) (xy -0.327914 1.100074) (xy 3.228086 1.100074) (xy 3.228086 0.9652)
				(xy 3.456686 0.9652) (xy 3.456686 -0.9652)
			)
			(stroke
				(width 0)
				(type default)
			)
			(fill no)
			(layer "F.CrtYd")
		)
		(fp_text user "2"
			(at 4.434586 0.286004 0)
			(unlocked yes)
			(layer "F.SilkS")
			(effects
				(font
					(size 0.7874 0.5842)
					(thickness 0.1524)
				)
				(justify left)
			)
		)
		(fp_text user "1"
			(at -0.645414 -1.415796 0)
			(unlocked yes)
			(layer "F.SilkS")
			(effects
				(font
					(size 0.7874 0.5842)
					(thickness 0.1524)
				)
				(justify left)
			)
		)
		(pad "1" smd rect
			(at 0 0 180)
			(size 1.016 1.8034)
			(layers "F.Cu" "F.Mask" "F.Paste")
			(net "P3V3_BLAD1")
		)
		(pad "2" smd rect
			(at 2.899918 0 180)
			(size 1.016 1.8034)
			(layers "F.Cu" "F.Mask" "F.Paste")
			(net "P3V3_10G_2_VCCR_L")
		)
	)
	(footprint ""
		(layer "F.Cu")
		(at 85.320124 -14.999716)
		(property "Reference" "J3"
			(at -4.966208 -7.545832 0)
			(unlocked yes)
			(layer "F.SilkS")
			(effects
				(font
					(size 0.7874 0.5842)
					(thickness 0.1524)
				)
				(justify left)
			)
		)
		(property "Value" ""
			(at 0 0 0)
			(layer "F.Fab")
			(effects
				(font
					(size 1.27 1.27)
				)
			)
		)
		(duplicate_pad_numbers_are_jumpers no)
		(fp_line
			(start -4.92506 -6.849872)
			(end 12.925044 -6.849872)
			(stroke
				(width 0.1524)
				(type default)
			)
			(layer "F.SilkS")
		)
		(fp_line
			(start -4.92506 28.450032)
			(end -4.92506 -6.849872)
			(stroke
				(width 0.1524)
				(type default)
			)
			(layer "F.SilkS")
		)
		(fp_line
			(start -1.925066 -3.850132)
			(end 9.92505 -3.850132)
			(stroke
				(width 0.1524)
				(type default)
			)
			(layer "F.SilkS")
		)
		(fp_line
			(start -1.925066 25.450038)
			(end -1.925066 -3.850132)
			(stroke
				(width 0.1524)
				(type default)
			)
			(layer "F.SilkS")
		)
		(fp_line
			(start 9.92505 -3.850132)
			(end 9.92505 25.450038)
			(stroke
				(width 0.1524)
				(type default)
			)
			(layer "F.SilkS")
		)
		(fp_line
			(start 9.92505 25.450038)
			(end -1.925066 25.450038)
			(stroke
				(width 0.1524)
				(type default)
			)
			(layer "F.SilkS")
		)
		(fp_line
			(start 12.925044 -6.849872)
			(end 12.925044 28.450032)
			(stroke
				(width 0.1524)
				(type default)
			)
			(layer "F.SilkS")
		)
		(fp_line
			(start 12.925044 28.450032)
			(end -4.92506 28.450032)
			(stroke
				(width 0.1524)
				(type default)
			)
			(layer "F.SilkS")
		)
		(fp_poly
			(pts
				(xy 0.00889 -7.013956) (xy 0.77089 -8.918956) (xy -0.75311 -8.918956)
			)
			(stroke
				(width 0)
				(type default)
			)
			(fill yes)
			(layer "F.SilkS")
		)
		(fp_line
			(start -4.92506 -6.849872)
			(end 12.925044 -6.849872)
			(stroke
				(width 0.1524)
				(type default)
			)
			(layer "B.SilkS")
		)
		(fp_line
			(start -4.92506 28.450032)
			(end -4.92506 -6.849872)
			(stroke
				(width 0.1524)
				(type default)
			)
			(layer "B.SilkS")
		)
		(fp_line
			(start 12.925044 -6.849872)
			(end 12.925044 28.450032)
			(stroke
				(width 0.1524)
				(type default)
			)
			(layer "B.SilkS")
		)
		(fp_line
			(start 12.925044 28.450032)
			(end -4.92506 28.450032)
			(stroke
				(width 0.1524)
				(type default)
			)
			(layer "B.SilkS")
		)
		(fp_poly
			(pts
				(xy -0.635508 -0.646684) (xy -0.635508 4.636516) (xy 2.641092 4.636516) (xy 2.641092 -0.646684)
			)
			(stroke
				(width 0)
				(type default)
			)
			(fill no)
			(layer "B.CrtYd")
		)
		(fp_poly
			(pts
				(xy -0.635508 7.354316) (xy 2.641092 7.354316) (xy 2.641092 12.637516) (xy -0.635508 12.637516)
			)
			(stroke
				(width 0)
				(type default)
			)
			(fill no)
			(layer "B.CrtYd")
		)
		(fp_poly
			(pts
				(xy 5.358892 -0.646684) (xy 8.635492 -0.646684) (xy 8.635492 4.636516) (xy 5.358892 4.636516)
			)
			(stroke
				(width 0)
				(type default)
			)
			(fill no)
			(layer "B.CrtYd")
		)
		(fp_poly
			(pts
				(xy 5.358892 7.354316) (xy 8.635492 7.354316) (xy 8.635492 12.637516) (xy 5.358892 12.637516)
			)
			(stroke
				(width 0)
				(type default)
			)
			(fill no)
			(layer "B.CrtYd")
		)
		(fp_poly
			(pts
				(arc
					(start 5.333492 5.500116)
					(mid 2.666492 5.499608)
					(end 5.333492 5.500116)
				)
			)
			(stroke
				(width 0)
				(type default)
			)
			(fill no)
			(layer "B.CrtYd")
		)
		(fp_poly
			(pts
				(xy -1.925066 25.450038) (xy 9.92505 25.450038) (xy 9.92505 -3.850132) (xy -1.925066 -3.850132)
			)
			(stroke
				(width 0)
				(type default)
			)
			(fill no)
			(layer "F.CrtYd")
		)
		(fp_line
			(start -4.92506 -6.849872)
			(end 12.925044 -6.849872)
			(stroke
				(width 0.1)
				(type default)
			)
			(layer "B.Fab")
		)
		(fp_line
			(start -4.92506 28.450032)
			(end -4.92506 -6.849872)
			(stroke
				(width 0.1)
				(type default)
			)
			(layer "B.Fab")
		)
		(fp_line
			(start 12.925044 -6.849872)
			(end 12.925044 28.450032)
			(stroke
				(width 0.1)
				(type default)
			)
			(layer "B.Fab")
		)
		(fp_line
			(start 12.925044 28.450032)
			(end -4.92506 28.450032)
			(stroke
				(width 0.1)
				(type default)
			)
			(layer "B.Fab")
		)
		(fp_line
			(start -1.925066 -3.850132)
			(end 9.92505 -3.850132)
			(stroke
				(width 0.1)
				(type default)
			)
			(layer "F.Fab")
		)
		(fp_line
			(start -1.925066 25.450038)
			(end -1.925066 -3.850132)
			(stroke
				(width 0.1)
				(type default)
			)
			(layer "F.Fab")
		)
		(fp_line
			(start 9.92505 -3.850132)
			(end 9.92505 25.450038)
			(stroke
				(width 0.1)
				(type default)
			)
			(layer "F.Fab")
		)
		(fp_line
			(start 9.92505 25.450038)
			(end -1.925066 25.450038)
			(stroke
				(width 0.1)
				(type default)
			)
			(layer "F.Fab")
		)
		(fp_poly
			(pts
				(xy -2.057908 -0.079502) (xy -3.962908 -0.841502) (xy -3.962908 0.682498)
			)
			(stroke
				(width 0)
				(type default)
			)
			(fill yes)
			(layer "F.Fab")
		)
		(fp_text user "A2"
			(at -3.797808 1.908048 0)
			(unlocked yes)
			(layer "F.SilkS")
			(effects
				(font
					(size 0.7874 0.5842)
					(thickness 0.1524)
				)
				(justify left)
			)
		)
		(fp_text user "A3"
			(at -3.797808 3.908044 0)
			(unlocked yes)
			(layer "F.SilkS")
			(effects
				(font
					(size 0.7874 0.5842)
					(thickness 0.1524)
				)
				(justify left)
			)
		)
		(fp_text user "D1"
			(at -3.797808 7.908036 0)
			(unlocked yes)
			(layer "F.SilkS")
			(effects
				(font
					(size 0.7874 0.5842)
					(thickness 0.1524)
				)
				(justify left)
			)
		)
		(fp_text user "D2"
			(at -3.797808 9.908032 0)
			(unlocked yes)
			(layer "F.SilkS")
			(effects
				(font
					(size 0.7874 0.5842)
					(thickness 0.1524)
				)
				(justify left)
			)
		)
		(fp_text user "D3"
			(at -3.797808 11.908282 0)
			(unlocked yes)
			(layer "F.SilkS")
			(effects
				(font
					(size 0.7874 0.5842)
					(thickness 0.1524)
				)
				(justify left)
			)
		)
		(fp_text user "PRESS-FIT"
			(at -2.921508 -5.608574 0)
			(unlocked yes)
			(layer "F.SilkS")
			(effects
				(font
					(size 1.6002 1.1938)
					(thickness 0.1524)
				)
				(justify left)
			)
		)
		(fp_text user "A1"
			(at -0.902208 -4.460748 0)
			(unlocked yes)
			(layer "F.SilkS")
			(effects
				(font
					(size 0.7874 0.5842)
					(thickness 0.1524)
				)
				(justify left)
			)
		)
		(fp_text user "C3"
			(at 10.172192 12.035282 0)
			(unlocked yes)
			(layer "F.SilkS")
			(effects
				(font
					(size 0.7874 0.5842)
					(thickness 0.1524)
				)
				(justify left)
			)
		)
		(fp_text user "C1"
			(at 10.197592 8.111236 0)
			(unlocked yes)
			(layer "F.SilkS")
			(effects
				(font
					(size 0.7874 0.5842)
					(thickness 0.1524)
				)
				(justify left)
			)
		)
		(fp_text user "C2"
			(at 10.324592 9.882632 0)
			(unlocked yes)
			(layer "F.SilkS")
			(effects
				(font
					(size 0.7874 0.5842)
					(thickness 0.1524)
				)
				(justify left)
			)
		)
		(fp_text user "B2"
			(at 10.554208 2.4638 90)
			(unlocked yes)
			(layer "F.SilkS")
			(effects
				(font
					(size 0.7874 0.5842)
					(thickness 0.1524)
				)
				(justify left)
			)
		)
		(fp_text user "B1"
			(at 10.560812 -0.0254 90)
			(unlocked yes)
			(layer "F.SilkS")
			(effects
				(font
					(size 0.7874 0.5842)
					(thickness 0.1524)
				)
				(justify left)
			)
		)
		(fp_text user "B3"
			(at 10.598404 4.6736 90)
			(unlocked yes)
			(layer "F.SilkS")
			(effects
				(font
					(size 0.7874 0.5842)
					(thickness 0.1524)
				)
				(justify left)
			)
		)
		(fp_text user "A1"
			(at -0.902208 -0.091948 0)
			(unlocked yes)
			(layer "B.SilkS")
			(effects
				(font
					(size 0.7874 0.5842)
					(thickness 0.1524)
				)
				(justify left mirror)
			)
		)
		(fp_text user "A2"
			(at -0.902208 1.908048 0)
			(unlocked yes)
			(layer "B.SilkS")
			(effects
				(font
					(size 0.7874 0.5842)
					(thickness 0.1524)
				)
				(justify left mirror)
			)
		)
		(fp_text user "A3"
			(at -0.902208 3.908044 0)
			(unlocked yes)
			(layer "B.SilkS")
			(effects
				(font
					(size 0.7874 0.5842)
					(thickness 0.1524)
				)
				(justify left mirror)
			)
		)
		(fp_text user "D1"
			(at -0.902208 7.908036 0)
			(unlocked yes)
			(layer "B.SilkS")
			(effects
				(font
					(size 0.7874 0.5842)
					(thickness 0.1524)
				)
				(justify left mirror)
			)
		)
		(fp_text user "D2"
			(at -0.902208 9.908032 0)
			(unlocked yes)
			(layer "B.SilkS")
			(effects
				(font
					(size 0.7874 0.5842)
					(thickness 0.1524)
				)
				(justify left mirror)
			)
		)
		(fp_text user "D3"
			(at -0.902208 11.908282 0)
			(unlocked yes)
			(layer "B.SilkS")
			(effects
				(font
					(size 0.7874 0.5842)
					(thickness 0.1524)
				)
				(justify left mirror)
			)
		)
		(fp_text user "B1"
			(at 10.273792 -0.091948 0)
			(unlocked yes)
			(layer "B.SilkS")
			(effects
				(font
					(size 0.7874 0.5842)
					(thickness 0.1524)
				)
				(justify left mirror)
			)
		)
		(fp_text user "B2"
			(at 10.273792 1.908048 0)
			(unlocked yes)
			(layer "B.SilkS")
			(effects
				(font
					(size 0.7874 0.5842)
					(thickness 0.1524)
				)
				(justify left mirror)
			)
		)
		(fp_text user "B3"
			(at 10.273792 3.908044 0)
			(unlocked yes)
			(layer "B.SilkS")
			(effects
				(font
					(size 0.7874 0.5842)
					(thickness 0.1524)
				)
				(justify left mirror)
			)
		)
		(fp_text user "C1"
			(at 10.273792 7.908036 0)
			(unlocked yes)
			(layer "B.SilkS")
			(effects
				(font
					(size 0.7874 0.5842)
					(thickness 0.1524)
				)
				(justify left mirror)
			)
		)
		(fp_text user "C2"
			(at 10.273792 9.908032 0)
			(unlocked yes)
			(layer "B.SilkS")
			(effects
				(font
					(size 0.7874 0.5842)
					(thickness 0.1524)
				)
				(justify left mirror)
			)
		)
		(fp_text user "C3"
			(at 10.273792 11.908282 0)
			(unlocked yes)
			(layer "B.SilkS")
			(effects
				(font
					(size 0.7874 0.5842)
					(thickness 0.1524)
				)
				(justify left mirror)
			)
		)
		(fp_text user "PRESS-FIT"
			(at 11.251692 -5.430774 0)
			(unlocked yes)
			(layer "B.SilkS")
			(effects
				(font
					(size 1.6002 1.1938)
					(thickness 0.1524)
				)
				(justify left mirror)
			)
		)
		(fp_text user "A1"
			(at -0.902208 -0.091948 0)
			(unlocked yes)
			(layer "B.Fab")
			(effects
				(font
					(size 0.7874 0.5842)
					(thickness 0.000001)
				)
				(justify left mirror)
			)
		)
		(fp_text user "A2"
			(at -0.902208 1.908048 0)
			(unlocked yes)
			(layer "B.Fab")
			(effects
				(font
					(size 0.7874 0.5842)
					(thickness 0.000001)
				)
				(justify left mirror)
			)
		)
		(fp_text user "A3"
			(at -0.902208 3.908044 0)
			(unlocked yes)
			(layer "B.Fab")
			(effects
				(font
					(size 0.7874 0.5842)
					(thickness 0.000001)
				)
				(justify left mirror)
			)
		)
		(fp_text user "D1"
			(at -0.902208 7.908036 0)
			(unlocked yes)
			(layer "B.Fab")
			(effects
				(font
					(size 0.7874 0.5842)
					(thickness 0.000001)
				)
				(justify left mirror)
			)
		)
		(fp_text user "D2"
			(at -0.902208 9.908032 0)
			(unlocked yes)
			(layer "B.Fab")
			(effects
				(font
					(size 0.7874 0.5842)
					(thickness 0.000001)
				)
				(justify left mirror)
			)
		)
		(fp_text user "D3"
			(at -0.902208 11.908282 0)
			(unlocked yes)
			(layer "B.Fab")
			(effects
				(font
					(size 0.7874 0.5842)
					(thickness 0.000001)
				)
				(justify left mirror)
			)
		)
		(fp_text user "B1"
			(at 10.273792 -0.091948 0)
			(unlocked yes)
			(layer "B.Fab")
			(effects
				(font
					(size 0.7874 0.5842)
					(thickness 0.000001)
				)
				(justify left mirror)
			)
		)
		(fp_text user "B2"
			(at 10.273792 1.908048 0)
			(unlocked yes)
			(layer "B.Fab")
			(effects
				(font
					(size 0.7874 0.5842)
					(thickness 0.000001)
				)
				(justify left mirror)
			)
		)
		(fp_text user "B3"
			(at 10.273792 3.908044 0)
			(unlocked yes)
			(layer "B.Fab")
			(effects
				(font
					(size 0.7874 0.5842)
					(thickness 0.000001)
				)
				(justify left mirror)
			)
		)
		(fp_text user "C1"
			(at 10.273792 7.908036 0)
			(unlocked yes)
			(layer "B.Fab")
			(effects
				(font
					(size 0.7874 0.5842)
					(thickness 0.000001)
				)
				(justify left mirror)
			)
		)
		(fp_text user "C2"
			(at 10.273792 9.908032 0)
			(unlocked yes)
			(layer "B.Fab")
			(effects
				(font
					(size 0.7874 0.5842)
					(thickness 0.000001)
				)
				(justify left mirror)
			)
		)
		(fp_text user "C3"
			(at 10.273792 11.908282 0)
			(unlocked yes)
			(layer "B.Fab")
			(effects
				(font
					(size 0.7874 0.5842)
					(thickness 0.000001)
				)
				(justify left mirror)
			)
		)
		(fp_text user "PRESS-FIT"
			(at 11.251692 -5.430774 0)
			(unlocked yes)
			(layer "B.Fab")
			(effects
				(font
					(size 1.6002 1.1938)
					(thickness 0.000001)
				)
				(justify left mirror)
			)
		)
		(fp_text user "A2"
			(at -3.797808 1.908048 0)
			(unlocked yes)
			(layer "F.Fab")
			(effects
				(font
					(size 0.7874 0.5842)
					(thickness 0.000001)
				)
				(justify left)
			)
		)
		(fp_text user "A3"
			(at -3.797808 3.908044 0)
			(unlocked yes)
			(layer "F.Fab")
			(effects
				(font
					(size 0.7874 0.5842)
					(thickness 0.000001)
				)
				(justify left)
			)
		)
		(fp_text user "D1"
			(at -3.797808 7.908036 0)
			(unlocked yes)
			(layer "F.Fab")
			(effects
				(font
					(size 0.7874 0.5842)
					(thickness 0.000001)
				)
				(justify left)
			)
		)
		(fp_text user "D2"
			(at -3.797808 9.908032 0)
			(unlocked yes)
			(layer "F.Fab")
			(effects
				(font
					(size 0.7874 0.5842)
					(thickness 0.000001)
				)
				(justify left)
			)
		)
		(fp_text user "D3"
			(at -3.797808 11.908282 0)
			(unlocked yes)
			(layer "F.Fab")
			(effects
				(font
					(size 0.7874 0.5842)
					(thickness 0.000001)
				)
				(justify left)
			)
		)
		(fp_text user "A1"
			(at -3.518408 -1.412748 0)
			(unlocked yes)
			(layer "F.Fab")
			(effects
				(font
					(size 0.7874 0.5842)
					(thickness 0.000001)
				)
				(justify left)
			)
		)
		(fp_text user "PRESS-FIT"
			(at -2.819908 -5.430774 0)
			(unlocked yes)
			(layer "F.Fab")
			(effects
				(font
					(size 1.6002 1.1938)
					(thickness 0.000001)
				)
				(justify left)
			)
		)
		(fp_text user "B1"
			(at 10.426192 -0.091948 0)
			(unlocked yes)
			(layer "F.Fab")
			(effects
				(font
					(size 0.7874 0.5842)
					(thickness 0.000001)
				)
				(justify left)
			)
		)
		(fp_text user "B2"
			(at 10.426192 1.908048 0)
			(unlocked yes)
			(layer "F.Fab")
			(effects
				(font
					(size 0.7874 0.5842)
					(thickness 0.000001)
				)
				(justify left)
			)
		)
		(fp_text user "B3"
			(at 10.426192 3.908044 0)
			(unlocked yes)
			(layer "F.Fab")
			(effects
				(font
					(size 0.7874 0.5842)
					(thickness 0.000001)
				)
				(justify left)
			)
		)
		(fp_text user "C1"
			(at 10.426192 7.908036 0)
			(unlocked yes)
			(layer "F.Fab")
			(effects
				(font
					(size 0.7874 0.5842)
					(thickness 0.000001)
				)
				(justify left)
			)
		)
		(fp_text user "C2"
			(at 10.426192 9.908032 0)
			(unlocked yes)
			(layer "F.Fab")
			(effects
				(font
					(size 0.7874 0.5842)
					(thickness 0.000001)
				)
				(justify left)
			)
		)
		(fp_text user "C3"
			(at 10.426192 11.908282 0)
			(unlocked yes)
			(layer "F.Fab")
			(effects
				(font
					(size 0.7874 0.5842)
					(thickness 0.000001)
				)
				(justify left)
			)
		)
		(pad "" np_thru_hole circle
			(at 3.999992 5.500116)
			(size 2.159 2.159)
			(drill 2.159)
			(layers "*.Cu" "*.Mask")
			(clearance 0.381)
			(thermal_gap 0.381)
		)
		(pad "A1" thru_hole rect
			(at 0 0)
			(size 1.1684 1.1684)
			(drill 0.762)
			(layers "*.Cu" "*.Mask")
			(remove_unused_layers no)
			(net "GND")
			(clearance 0.0508)
			(thermal_gap 0.0508)
			(padstack
				(mode front_inner_back)
				(layer "Inner"
					(shape circle)
					(size 1.1684 1.1684)
					(clearance 0.0508)
				)
				(layer "B.Cu"
					(shape rect)
					(size 1.1684 1.1684)
					(clearance 0.0508)
				)
			)
		)
		(pad "A2" thru_hole circle
			(at 0 1.999996)
			(size 1.1684 1.1684)
			(drill 0.762)
			(layers "*.Cu" "*.Mask")
			(remove_unused_layers no)
			(net "GND")
			(clearance 0.0508)
			(thermal_gap 0.0508)
		)
		(pad "A3" thru_hole circle
			(at 0 3.999992)
			(size 1.1684 1.1684)
			(drill 0.762)
			(layers "*.Cu" "*.Mask")
			(remove_unused_layers no)
			(net "GND")
			(clearance 0.0508)
			(thermal_gap 0.0508)
		)
		(pad "A4" thru_hole circle
			(at 1.999996 0)
			(size 1.1684 1.1684)
			(drill 0.762)
			(layers "*.Cu" "*.Mask")
			(remove_unused_layers no)
			(net "GND")
			(clearance 0.0508)
			(thermal_gap 0.0508)
		)
		(pad "A5" thru_hole circle
			(at 1.999996 1.999996)
			(size 1.1684 1.1684)
			(drill 0.762)
			(layers "*.Cu" "*.Mask")
			(remove_unused_layers no)
			(net "GND")
			(clearance 0.0508)
			(thermal_gap 0.0508)
		)
		(pad "A6" thru_hole circle
			(at 1.999996 3.999992)
			(size 1.1684 1.1684)
			(drill 0.762)
			(layers "*.Cu" "*.Mask")
			(remove_unused_layers no)
			(net "GND")
			(clearance 0.0508)
			(thermal_gap 0.0508)
		)
		(pad "B1" thru_hole circle
			(at 7.999984 0)
			(size 1.1684 1.1684)
			(drill 0.762)
			(layers "*.Cu" "*.Mask")
			(remove_unused_layers no)
			(net "P12V")
			(clearance 0.0508)
			(thermal_gap 0.0508)
		)
		(pad "B2" thru_hole circle
			(at 7.999984 1.999996)
			(size 1.1684 1.1684)
			(drill 0.762)
			(layers "*.Cu" "*.Mask")
			(remove_unused_layers no)
			(net "P12V")
			(clearance 0.0508)
			(thermal_gap 0.0508)
		)
		(pad "B3" thru_hole circle
			(at 7.999984 3.999992)
			(size 1.1684 1.1684)
			(drill 0.762)
			(layers "*.Cu" "*.Mask")
			(remove_unused_layers no)
			(net "P12V")
			(clearance 0.0508)
			(thermal_gap 0.0508)
		)
		(pad "B4" thru_hole circle
			(at 5.999988 0)
			(size 1.1684 1.1684)
			(drill 0.762)
			(layers "*.Cu" "*.Mask")
			(remove_unused_layers no)
			(net "P12V")
			(clearance 0.0508)
			(thermal_gap 0.0508)
		)
		(pad "B5" thru_hole circle
			(at 5.999988 1.999996)
			(size 1.1684 1.1684)
			(drill 0.762)
			(layers "*.Cu" "*.Mask")
			(remove_unused_layers no)
			(net "P12V")
			(clearance 0.0508)
			(thermal_gap 0.0508)
		)
		(pad "B6" thru_hole circle
			(at 5.999988 3.999992)
			(size 1.1684 1.1684)
			(drill 0.762)
			(layers "*.Cu" "*.Mask")
			(remove_unused_layers no)
			(net "P12V")
			(clearance 0.0508)
			(thermal_gap 0.0508)
		)
		(pad "C1" thru_hole circle
			(at 7.999984 7.999984)
			(size 1.1684 1.1684)
			(drill 0.762)
			(layers "*.Cu" "*.Mask")
			(remove_unused_layers no)
			(net "P12V")
			(clearance 0.0508)
			(thermal_gap 0.0508)
		)
		(pad "C2" thru_hole circle
			(at 7.999984 9.99998)
			(size 1.1684 1.1684)
			(drill 0.762)
			(layers "*.Cu" "*.Mask")
			(remove_unused_layers no)
			(net "P12V")
			(clearance 0.0508)
			(thermal_gap 0.0508)
		)
		(pad "C3" thru_hole circle
			(at 7.999984 11.999976)
			(size 1.1684 1.1684)
			(drill 0.762)
			(layers "*.Cu" "*.Mask")
			(remove_unused_layers no)
			(net "P12V")
			(clearance 0.0508)
			(thermal_gap 0.0508)
		)
		(pad "C4" thru_hole circle
			(at 5.999988 7.999984)
			(size 1.1684 1.1684)
			(drill 0.762)
			(layers "*.Cu" "*.Mask")
			(remove_unused_layers no)
			(net "P12V")
			(clearance 0.0508)
			(thermal_gap 0.0508)
		)
		(pad "C5" thru_hole circle
			(at 5.999988 9.99998)
			(size 1.1684 1.1684)
			(drill 0.762)
			(layers "*.Cu" "*.Mask")
			(remove_unused_layers no)
			(net "P12V")
			(clearance 0.0508)
			(thermal_gap 0.0508)
		)
		(pad "C6" thru_hole circle
			(at 5.999988 11.999976)
			(size 1.1684 1.1684)
			(drill 0.762)
			(layers "*.Cu" "*.Mask")
			(remove_unused_layers no)
			(net "P12V")
			(clearance 0.0508)
			(thermal_gap 0.0508)
		)
		(pad "D1" thru_hole circle
			(at 0 7.999984)
			(size 1.1684 1.1684)
			(drill 0.762)
			(layers "*.Cu" "*.Mask")
			(remove_unused_layers no)
			(net "GND")
			(clearance 0.0508)
			(thermal_gap 0.0508)
		)
		(pad "D2" thru_hole circle
			(at 0 9.99998)
			(size 1.1684 1.1684)
			(drill 0.762)
			(layers "*.Cu" "*.Mask")
			(remove_unused_layers no)
			(net "GND")
			(clearance 0.0508)
			(thermal_gap 0.0508)
		)
		(pad "D3" thru_hole circle
			(at 0 11.999976)
			(size 1.1684 1.1684)
			(drill 0.762)
			(layers "*.Cu" "*.Mask")
			(remove_unused_layers no)
			(net "GND")
			(clearance 0.0508)
			(thermal_gap 0.0508)
		)
		(pad "D4" thru_hole circle
			(at 1.999996 7.999984)
			(size 1.1684 1.1684)
			(drill 0.762)
			(layers "*.Cu" "*.Mask")
			(remove_unused_layers no)
			(net "GND")
			(clearance 0.0508)
			(thermal_gap 0.0508)
		)
		(pad "D5" thru_hole circle
			(at 1.999996 9.99998)
			(size 1.1684 1.1684)
			(drill 0.762)
			(layers "*.Cu" "*.Mask")
			(remove_unused_layers no)
			(net "GND")
			(clearance 0.0508)
			(thermal_gap 0.0508)
		)
		(pad "D6" thru_hole circle
			(at 1.999996 11.999976)
			(size 1.1684 1.1684)
			(drill 0.762)
			(layers "*.Cu" "*.Mask")
			(remove_unused_layers no)
			(net "GND")
			(clearance 0.0508)
			(thermal_gap 0.0508)
		)
		(zone
			(layers "F.Cu" "B.Cu" "In1.Cu" "In2.Cu" "In3.Cu" "In4.Cu" "In5.Cu" "In6.Cu")
			(hatch none 0.5)
			(connect_pads
				(clearance 0)
			)
			(min_thickness 0.25)
			(keepout
				(tracks not_allowed)
				(vias allowed)
				(pads allowed)
				(copperpour not_allowed)
				(footprints allowed)
			)
			(placement
				(enabled no)
				(sheetname "")
			)
			(fill
				(thermal_gap 0.5)
				(thermal_bridge_width 0.5)
				(island_removal_mode 0)
			)
			(polygon
				(pts
					(arc
						(start 90.806016 -9.4996)
						(mid 87.834216 -9.500108)
						(end 90.806016 -9.4996)
					)
				)
			)
		)
		(zone
			(layer "B.Cu")
			(hatch none 0.5)
			(connect_pads
				(clearance 0)
			)
			(min_thickness 0.25)
			(keepout
				(tracks allowed)
				(vias not_allowed)
				(pads allowed)
				(copperpour not_allowed)
				(footprints allowed)
			)
			(placement
				(enabled no)
				(sheetname "")
			)
			(fill
				(thermal_gap 0.5)
				(thermal_bridge_width 0.5)
				(island_removal_mode 0)
			)
			(polygon
				(pts
					(xy 84.684616 -10.3632) (xy 87.961216 -10.3632) (xy 87.961216 -15.6464) (xy 84.684616 -15.6464)
				)
			)
		)
		(zone
			(layer "B.Cu")
			(hatch none 0.5)
			(connect_pads
				(clearance 0)
			)
			(min_thickness 0.25)
			(keepout
				(tracks allowed)
				(vias not_allowed)
				(pads allowed)
				(copperpour not_allowed)
				(footprints allowed)
			)
			(placement
				(enabled no)
				(sheetname "")
			)
			(fill
				(thermal_gap 0.5)
				(thermal_bridge_width 0.5)
				(island_removal_mode 0)
			)
			(polygon
				(pts
					(xy 84.684616 -2.3622) (xy 87.961216 -2.3622) (xy 87.961216 -7.6454) (xy 84.684616 -7.6454)
				)
			)
		)
		(zone
			(layer "B.Cu")
			(hatch none 0.5)
			(connect_pads
				(clearance 0)
			)
			(min_thickness 0.25)
			(keepout
				(tracks allowed)
				(vias not_allowed)
				(pads allowed)
				(copperpour not_allowed)
				(footprints allowed)
			)
			(placement
				(enabled no)
				(sheetname "")
			)
			(fill
				(thermal_gap 0.5)
				(thermal_bridge_width 0.5)
				(island_removal_mode 0)
			)
			(polygon
				(pts
					(xy 90.679016 -10.3632) (xy 93.955616 -10.3632) (xy 93.955616 -15.6464) (xy 90.679016 -15.6464)
				)
			)
		)
		(zone
			(layer "B.Cu")
			(hatch none 0.5)
			(connect_pads
				(clearance 0)
			)
			(min_thickness 0.25)
			(keepout
				(tracks allowed)
				(vias not_allowed)
				(pads allowed)
				(copperpour not_allowed)
				(footprints allowed)
			)
			(placement
				(enabled no)
				(sheetname "")
			)
			(fill
				(thermal_gap 0.5)
				(thermal_bridge_width 0.5)
				(island_removal_mode 0)
			)
			(polygon
				(pts
					(xy 90.679016 -2.3622) (xy 93.955616 -2.3622) (xy 93.955616 -7.6454) (xy 90.679016 -7.6454)
				)
			)
		)
		(zone
			(layer "B.Cu")
			(hatch none 0.5)
			(connect_pads
				(clearance 0)
			)
			(min_thickness 0.25)
			(keepout
				(tracks allowed)
				(vias not_allowed)
				(pads allowed)
				(copperpour not_allowed)
				(footprints allowed)
			)
			(placement
				(enabled no)
				(sheetname "")
			)
			(fill
				(thermal_gap 0.5)
				(thermal_bridge_width 0.5)
				(island_removal_mode 0)
			)
			(polygon
				(pts
					(arc
						(start 90.653616 -9.4996)
						(mid 87.986616 -9.500108)
						(end 90.653616 -9.4996)
					)
				)
			)
		)
	)
	(footprint ""
		(layer "F.Cu")
		(at 89.41816 -27.574494 180)
		(property "Reference" "R44"
			(at 7.08152 -0.57404 0)
			(unlocked yes)
			(layer "F.SilkS")
			(effects
				(font
					(size 0.7874 0.5842)
					(thickness 0.1524)
				)
				(justify left)
			)
		)
		(property "Value" ""
			(at 0 0 180)
			(layer "F.Fab")
			(effects
				(font
					(size 1.27 1.27)
				)
			)
		)
		(duplicate_pad_numbers_are_jumpers no)
		(fp_line
			(start 0.7874 0.4064)
			(end -0.7874 0.4064)
			(stroke
				(width 0.1524)
				(type default)
			)
			(layer "F.SilkS")
		)
		(fp_line
			(start 0.7874 -0.4064)
			(end 0.7874 0.4064)
			(stroke
				(width 0.1524)
				(type default)
			)
			(layer "F.SilkS")
		)
		(fp_line
			(start -0.7874 0.4064)
			(end -0.7874 -0.4064)
			(stroke
				(width 0.1524)
				(type default)
			)
			(layer "F.SilkS")
		)
		(fp_line
			(start -0.7874 -0.4064)
			(end 0.7874 -0.4064)
			(stroke
				(width 0.1524)
				(type default)
			)
			(layer "F.SilkS")
		)
		(fp_poly
			(pts
				(xy -0.508 0.2794) (xy -0.508 0.2286) (xy -0.635 0.2286) (xy -0.635 -0.254) (xy -0.5334 -0.254)
				(xy -0.5334 -0.2794) (xy 0.5334 -0.2794) (xy 0.5334 -0.254) (xy 0.635 -0.254) (xy 0.635 0.254) (xy 0.5334 0.254)
				(xy 0.5334 0.2794)
			)
			(stroke
				(width 0)
				(type default)
			)
			(fill no)
			(layer "F.CrtYd")
		)
		(pad "1" smd rect
			(at 0.40005 0 180)
			(size 0.4572 0.508)
			(layers "F.Cu" "F.Mask" "F.Paste")
			(net "GND")
		)
		(pad "2" smd rect
			(at -0.40005 0 180)
			(size 0.4572 0.508)
			(layers "F.Cu" "F.Mask" "F.Paste")
			(net "ENET10G_2_RS0")
		)
	)
	(footprint ""
		(layer "F.Cu")
		(at 424.310048 -4.700016 180)
		(property "Reference" "H8"
			(at 1.428496 9.335516 0)
			(unlocked yes)
			(layer "F.SilkS")
			(effects
				(font
					(size 0.7874 0.5842)
					(thickness 0.1524)
				)
				(justify left)
			)
		)
		(property "Value" ""
			(at 0 0 180)
			(layer "F.Fab")
			(effects
				(font
					(size 1.27 1.27)
				)
			)
		)
		(duplicate_pad_numbers_are_jumpers no)
		(fp_circle
			(center 0 0)
			(end -7.999984 0)
			(stroke
				(width 0.1524)
				(type default)
			)
			(fill no)
			(layer "F.SilkS")
		)
		(fp_arc
			(start 7.999984 0)
			(mid 7.10586 3.675167)
			(end 4.623308 6.528816)
			(stroke
				(width 0.1524)
				(type default)
			)
			(layer "B.SilkS")
		)
		(fp_arc
			(start -4.623308 6.528816)
			(mid -3.675236 -7.105871)
			(end 7.999984 0)
			(stroke
				(width 0.1524)
				(type default)
			)
			(layer "B.SilkS")
		)
		(fp_circle
			(center 0 0)
			(end -14.5034 0)
			(stroke
				(width 0.1524)
				(type default)
			)
			(fill no)
			(layer "B.SilkS")
		)
		(fp_poly
			(pts
				(arc
					(start -4.5085 0)
					(mid 4.5085 0)
					(end -4.5085 0)
				)
			)
			(stroke
				(width 0)
				(type default)
			)
			(fill no)
			(layer "F.CrtYd")
		)
		(pad "" np_thru_hole circle
			(at 0 0 180)
			(size 3.6068 3.6068)
			(drill 3.6068)
			(layers "*.Cu" "*.Mask")
			(clearance 0.381)
			(thermal_gap 0.381)
		)
		(pad "2" thru_hole circle
			(at 3.41122 0 180)
			(size 0.762 0.762)
			(drill 0.5588)
			(layers "*.Cu" "*.Mask")
			(remove_unused_layers no)
			(net "GND")
			(clearance 0.1524)
			(thermal_gap 0.1524)
		)
		(pad "3" thru_hole circle
			(at 2.411984 -2.411984 180)
			(size 0.762 0.762)
			(drill 0.5588)
			(layers "*.Cu" "*.Mask")
			(remove_unused_layers no)
			(net "GND")
			(clearance 0.1524)
			(thermal_gap 0.1524)
		)
		(pad "4" thru_hole circle
			(at 0 -3.41122 180)
			(size 0.762 0.762)
			(drill 0.5588)
			(layers "*.Cu" "*.Mask")
			(remove_unused_layers no)
			(net "GND")
			(clearance 0.1524)
			(thermal_gap 0.1524)
		)
		(pad "5" thru_hole circle
			(at -2.411984 -2.411984 180)
			(size 0.762 0.762)
			(drill 0.5588)
			(layers "*.Cu" "*.Mask")
			(remove_unused_layers no)
			(net "GND")
			(clearance 0.1524)
			(thermal_gap 0.1524)
		)
		(pad "6" thru_hole circle
			(at -3.41122 0 180)
			(size 0.762 0.762)
			(drill 0.5588)
			(layers "*.Cu" "*.Mask")
			(remove_unused_layers no)
			(net "GND")
			(clearance 0.1524)
			(thermal_gap 0.1524)
		)
		(pad "7" thru_hole circle
			(at -2.411984 2.411984 180)
			(size 0.762 0.762)
			(drill 0.5588)
			(layers "*.Cu" "*.Mask")
			(remove_unused_layers no)
			(net "GND")
			(clearance 0.1524)
			(thermal_gap 0.1524)
		)
		(pad "8" thru_hole circle
			(at 0 3.41122 180)
			(size 0.762 0.762)
			(drill 0.5588)
			(layers "*.Cu" "*.Mask")
			(remove_unused_layers no)
			(net "GND")
			(clearance 0.1524)
			(thermal_gap 0.1524)
		)
		(pad "9" thru_hole circle
			(at 2.411984 2.411984 180)
			(size 0.762 0.762)
			(drill 0.5588)
			(layers "*.Cu" "*.Mask")
			(remove_unused_layers no)
			(net "GND")
			(clearance 0.1524)
			(thermal_gap 0.1524)
		)
		(zone
			(layer "F.Cu")
			(hatch none 0.5)
			(connect_pads
				(clearance 0)
			)
			(min_thickness 0.25)
			(keepout
				(tracks not_allowed)
				(vias allowed)
				(pads allowed)
				(copperpour not_allowed)
				(footprints allowed)
			)
			(placement
				(enabled no)
				(sheetname "")
			)
			(fill
				(thermal_gap 0.5)
				(thermal_bridge_width 0.5)
				(island_removal_mode 0)
			)
			(polygon
				(pts
					(arc
						(start 424.310048 3.299968)
						(mid 418.653205 0.956827)
						(end 416.310064 -4.700016)
					)
					(arc
						(start 416.310064 -4.700016)
						(mid 418.653205 -10.356859)
						(end 424.310048 -12.7)
					)
					(arc
						(start 424.310048 -9.462516)
						(mid 419.547548 -4.700016)
						(end 424.310048 0.062484)
					)
				)
			)
		)
		(zone
			(layers "F.Cu" "B.Cu" "In1.Cu" "In2.Cu" "In3.Cu" "In4.Cu" "In5.Cu" "In6.Cu")
			(hatch none 0.5)
			(connect_pads
				(clearance 0)
			)
			(min_thickness 0.25)
			(keepout
				(tracks not_allowed)
				(vias allowed)
				(pads allowed)
				(copperpour not_allowed)
				(footprints allowed)
			)
			(placement
				(enabled no)
				(sheetname "")
			)
			(fill
				(thermal_gap 0.5)
				(thermal_bridge_width 0.5)
				(island_removal_mode 0)
			)
			(polygon
				(pts
					(arc
						(start 426.621448 -4.700016)
						(mid 421.998648 -4.700016)
						(end 426.621448 -4.700016)
					)
				)
			)
		)
		(zone
			(layer "B.Cu")
			(hatch none 0.5)
			(connect_pads
				(clearance 0)
			)
			(min_thickness 0.25)
			(keepout
				(tracks not_allowed)
				(vias allowed)
				(pads allowed)
				(copperpour not_allowed)
				(footprints allowed)
			)
			(placement
				(enabled no)
				(sheetname "")
			)
			(fill
				(thermal_gap 0.5)
				(thermal_bridge_width 0.5)
				(island_removal_mode 0)
			)
			(polygon
				(pts
					(arc
						(start 424.310048 -15.225522)
						(mid 421.110024 -13.900028)
						(end 419.78453 -10.700004)
					)
					(arc
						(start 419.78453 -4.700016)
						(mid 421.110024 -1.499992)
						(end 424.310048 -0.174498)
					)
					(arc
						(start 424.310048 0.308102)
						(mid 420.768774 -1.158742)
						(end 419.30193 -4.700016)
					)
					(arc
						(start 419.30193 -10.700004)
						(mid 420.768864 -14.241114)
						(end 424.310048 -15.707868)
					)
				)
			)
		)
	)
	(footprint ""
		(layer "F.Cu")
		(at 365.2266 -3.0988 90)
		(property "Reference" "C30"
			(at -2.3114 -2.174748 90)
			(unlocked yes)
			(layer "F.SilkS")
			(effects
				(font
					(size 0.7874 0.5842)
					(thickness 0.1524)
				)
				(justify left)
			)
		)
		(property "Value" ""
			(at 0 0 90)
			(layer "F.Fab")
			(effects
				(font
					(size 1.27 1.27)
				)
			)
		)
		(duplicate_pad_numbers_are_jumpers no)
		(fp_line
			(start 0.7874 -0.4064)
			(end 0.7874 0.4064)
			(stroke
				(width 0.1524)
				(type default)
			)
			(layer "F.SilkS")
		)
		(fp_line
			(start -0.7874 -0.4064)
			(end 0.7874 -0.4064)
			(stroke
				(width 0.1524)
				(type default)
			)
			(layer "F.SilkS")
		)
		(fp_line
			(start 0 0.381)
			(end 0 -0.381)
			(stroke
				(width 0.1524)
				(type default)
			)
			(layer "F.SilkS")
		)
		(fp_line
			(start 0.7874 0.4064)
			(end -0.7874 0.4064)
			(stroke
				(width 0.1524)
				(type default)
			)
			(layer "F.SilkS")
		)
		(fp_line
			(start -0.7874 0.4064)
			(end -0.7874 -0.4064)
			(stroke
				(width 0.1524)
				(type default)
			)
			(layer "F.SilkS")
		)
		(fp_poly
			(pts
				(xy -0.5334 0.254) (xy -0.635 0.254) (xy -0.635 0.2286) (xy -0.635 -0.254) (xy -0.5334 -0.254) (xy -0.5334 -0.2794)
				(xy 0.5334 -0.2794) (xy 0.5334 -0.254) (xy 0.635 -0.254) (xy 0.635 0.254) (xy 0.5334 0.254) (xy 0.5334 0.2794)
				(xy -0.508 0.2794) (xy -0.5334 0.2794)
			)
			(stroke
				(width 0)
				(type default)
			)
			(fill no)
			(layer "F.CrtYd")
		)
		(pad "1" smd rect
			(at 0.40005 0 90)
			(size 0.4572 0.508)
			(layers "F.Cu" "F.Mask" "F.Paste")
			(net "P3V3_10G_3_VCCR")
		)
		(pad "2" smd rect
			(at -0.40005 0 90)
			(size 0.4572 0.508)
			(layers "F.Cu" "F.Mask" "F.Paste")
			(net "GND")
		)
	)
	(footprint ""
		(layer "F.Cu")
		(at 117.31244 -26.54681)
		(property "Reference" "R14"
			(at -61.341 5.115052 0)
			(unlocked yes)
			(layer "F.SilkS")
			(effects
				(font
					(size 0.7874 0.5842)
					(thickness 0.1524)
				)
				(justify left)
			)
		)
		(property "Value" ""
			(at 0 0 0)
			(layer "F.Fab")
			(effects
				(font
					(size 1.27 1.27)
				)
			)
		)
		(duplicate_pad_numbers_are_jumpers no)
		(fp_line
			(start -0.7874 -0.4064)
			(end 0.7874 -0.4064)
			(stroke
				(width 0.1524)
				(type default)
			)
			(layer "F.SilkS")
		)
		(fp_line
			(start -0.7874 0.4064)
			(end -0.7874 -0.4064)
			(stroke
				(width 0.1524)
				(type default)
			)
			(layer "F.SilkS")
		)
		(fp_line
			(start 0.7874 -0.4064)
			(end 0.7874 0.4064)
			(stroke
				(width 0.1524)
				(type default)
			)
			(layer "F.SilkS")
		)
		(fp_line
			(start 0.7874 0.4064)
			(end -0.7874 0.4064)
			(stroke
				(width 0.1524)
				(type default)
			)
			(layer "F.SilkS")
		)
		(fp_poly
			(pts
				(xy -0.508 0.2794) (xy -0.508 0.2286) (xy -0.635 0.2286) (xy -0.635 -0.254) (xy -0.5334 -0.254)
				(xy -0.5334 -0.2794) (xy 0.5334 -0.2794) (xy 0.5334 -0.254) (xy 0.635 -0.254) (xy 0.635 0.254) (xy 0.5334 0.254)
				(xy 0.5334 0.2794)
			)
			(stroke
				(width 0)
				(type default)
			)
			(fill no)
			(layer "F.CrtYd")
		)
		(pad "1" smd rect
			(at 0.40005 0)
			(size 0.4572 0.508)
			(layers "F.Cu" "F.Mask" "F.Paste")
			(net "P3V3_BLAD1")
		)
		(pad "2" smd rect
			(at -0.40005 0)
			(size 0.4572 0.508)
			(layers "F.Cu" "F.Mask" "F.Paste")
			(net "ENET10G_2_LOS")
		)
	)
	(footprint ""
		(layer "F.Cu")
		(at 119.433848 -22.239732 180)
		(property "Reference" "R68"
			(at 60.737496 -5.195316 0)
			(unlocked yes)
			(layer "F.SilkS")
			(effects
				(font
					(size 0.7874 0.5842)
					(thickness 0.1524)
				)
				(justify left)
			)
		)
		(property "Value" ""
			(at 0 0 180)
			(layer "F.Fab")
			(effects
				(font
					(size 1.27 1.27)
				)
			)
		)
		(duplicate_pad_numbers_are_jumpers no)
		(fp_line
			(start 0.7874 0.4064)
			(end -0.7874 0.4064)
			(stroke
				(width 0.1524)
				(type default)
			)
			(layer "F.SilkS")
		)
		(fp_line
			(start 0.7874 -0.4064)
			(end 0.7874 0.4064)
			(stroke
				(width 0.1524)
				(type default)
			)
			(layer "F.SilkS")
		)
		(fp_line
			(start -0.7874 0.4064)
			(end -0.7874 -0.4064)
			(stroke
				(width 0.1524)
				(type default)
			)
			(layer "F.SilkS")
		)
		(fp_line
			(start -0.7874 -0.4064)
			(end 0.7874 -0.4064)
			(stroke
				(width 0.1524)
				(type default)
			)
			(layer "F.SilkS")
		)
		(fp_poly
			(pts
				(xy -0.508 0.2794) (xy -0.508 0.2286) (xy -0.635 0.2286) (xy -0.635 -0.254) (xy -0.5334 -0.254)
				(xy -0.5334 -0.2794) (xy 0.5334 -0.2794) (xy 0.5334 -0.254) (xy 0.635 -0.254) (xy 0.635 0.254) (xy 0.5334 0.254)
				(xy 0.5334 0.2794)
			)
			(stroke
				(width 0)
				(type default)
			)
			(fill no)
			(layer "F.CrtYd")
		)
		(pad "1" smd rect
			(at 0.40005 0 180)
			(size 0.4572 0.508)
			(layers "F.Cu" "F.Mask" "F.Paste")
			(net "ENET10G_2_LOS")
		)
		(pad "2" smd rect
			(at -0.40005 0 180)
			(size 0.4572 0.508)
			(layers "F.Cu" "F.Mask" "F.Paste")
			(net "SFP2_PRESENT_N")
		)
	)
	(footprint ""
		(layer "F.Cu")
		(at 27.167332 -19.7358 -90)
		(property "Reference" "R90"
			(at 0.889 -5.364988 90)
			(unlocked yes)
			(layer "F.SilkS")
			(effects
				(font
					(size 0.7874 0.5842)
					(thickness 0.1524)
				)
				(justify left)
			)
		)
		(property "Value" ""
			(at 0 0 270)
			(layer "F.Fab")
			(effects
				(font
					(size 1.27 1.27)
				)
			)
		)
		(duplicate_pad_numbers_are_jumpers no)
		(fp_line
			(start -0.7874 0.4064)
			(end -0.7874 -0.4064)
			(stroke
				(width 0.1524)
				(type default)
			)
			(layer "F.SilkS")
		)
		(fp_line
			(start 0.7874 0.4064)
			(end -0.7874 0.4064)
			(stroke
				(width 0.1524)
				(type default)
			)
			(layer "F.SilkS")
		)
		(fp_line
			(start -0.7874 -0.4064)
			(end 0.7874 -0.4064)
			(stroke
				(width 0.1524)
				(type default)
			)
			(layer "F.SilkS")
		)
		(fp_line
			(start 0.7874 -0.4064)
			(end 0.7874 0.4064)
			(stroke
				(width 0.1524)
				(type default)
			)
			(layer "F.SilkS")
		)
		(fp_poly
			(pts
				(xy -0.508 0.2794) (xy -0.508 0.2286) (xy -0.635 0.2286) (xy -0.635 -0.254) (xy -0.5334 -0.254)
				(xy -0.5334 -0.2794) (xy 0.5334 -0.2794) (xy 0.5334 -0.254) (xy 0.635 -0.254) (xy 0.635 0.254) (xy 0.5334 0.254)
				(xy 0.5334 0.2794)
			)
			(stroke
				(width 0)
				(type default)
			)
			(fill no)
			(layer "F.CrtYd")
		)
		(pad "1" smd rect
			(at 0.40005 0 270)
			(size 0.4572 0.508)
			(layers "F.Cu" "F.Mask" "F.Paste")
			(net "N39398095")
		)
		(pad "2" smd rect
			(at -0.40005 0 270)
			(size 0.4572 0.508)
			(layers "F.Cu" "F.Mask" "F.Paste")
			(net "P12V")
		)
	)
	(footprint ""
		(layer "F.Cu")
		(at 122.747532 -21.750782 -90)
		(property "Reference" "R57"
			(at 6.163564 59.709812 90)
			(unlocked yes)
			(layer "F.SilkS")
			(effects
				(font
					(size 0.7874 0.5842)
					(thickness 0.1524)
				)
				(justify left)
			)
		)
		(property "Value" ""
			(at 0 0 270)
			(layer "F.Fab")
			(effects
				(font
					(size 1.27 1.27)
				)
			)
		)
		(duplicate_pad_numbers_are_jumpers no)
		(fp_line
			(start -0.7874 0.4064)
			(end -0.7874 -0.4064)
			(stroke
				(width 0.1524)
				(type default)
			)
			(layer "F.SilkS")
		)
		(fp_line
			(start 0.7874 0.4064)
			(end -0.7874 0.4064)
			(stroke
				(width 0.1524)
				(type default)
			)
			(layer "F.SilkS")
		)
		(fp_line
			(start -0.7874 -0.4064)
			(end 0.7874 -0.4064)
			(stroke
				(width 0.1524)
				(type default)
			)
			(layer "F.SilkS")
		)
		(fp_line
			(start 0.7874 -0.4064)
			(end 0.7874 0.4064)
			(stroke
				(width 0.1524)
				(type default)
			)
			(layer "F.SilkS")
		)
		(fp_poly
			(pts
				(xy -0.508 0.2794) (xy -0.508 0.2286) (xy -0.635 0.2286) (xy -0.635 -0.254) (xy -0.5334 -0.254)
				(xy -0.5334 -0.2794) (xy 0.5334 -0.2794) (xy 0.5334 -0.254) (xy 0.635 -0.254) (xy 0.635 0.254) (xy 0.5334 0.254)
				(xy 0.5334 0.2794)
			)
			(stroke
				(width 0)
				(type default)
			)
			(fill no)
			(layer "F.CrtYd")
		)
		(pad "1" smd rect
			(at 0.40005 0 270)
			(size 0.4572 0.508)
			(layers "F.Cu" "F.Mask" "F.Paste")
			(net "SKU_PIN_BLAD1_2")
		)
		(pad "2" smd rect
			(at -0.40005 0 270)
			(size 0.4572 0.508)
			(layers "F.Cu" "F.Mask" "F.Paste")
			(net "P3V3_BLAD1")
		)
	)
	(footprint ""
		(layer "F.Cu")
		(at 154.89936 -22.899878 180)
		(property "Reference" "R1"
			(at -33.93948 -17.844008 0)
			(unlocked yes)
			(layer "F.SilkS")
			(effects
				(font
					(size 0.7874 0.5842)
					(thickness 0.1524)
				)
				(justify left)
			)
		)
		(property "Value" ""
			(at 0 0 180)
			(layer "F.Fab")
			(effects
				(font
					(size 1.27 1.27)
				)
			)
		)
		(duplicate_pad_numbers_are_jumpers no)
		(fp_line
			(start 0.7874 0.4064)
			(end -0.7874 0.4064)
			(stroke
				(width 0.1524)
				(type default)
			)
			(layer "F.SilkS")
		)
		(fp_line
			(start 0.7874 -0.4064)
			(end 0.7874 0.4064)
			(stroke
				(width 0.1524)
				(type default)
			)
			(layer "F.SilkS")
		)
		(fp_line
			(start -0.7874 0.4064)
			(end -0.7874 -0.4064)
			(stroke
				(width 0.1524)
				(type default)
			)
			(layer "F.SilkS")
		)
		(fp_line
			(start -0.7874 -0.4064)
			(end 0.7874 -0.4064)
			(stroke
				(width 0.1524)
				(type default)
			)
			(layer "F.SilkS")
		)
		(fp_poly
			(pts
				(xy -0.508 0.2794) (xy -0.508 0.2286) (xy -0.635 0.2286) (xy -0.635 -0.254) (xy -0.5334 -0.254)
				(xy -0.5334 -0.2794) (xy 0.5334 -0.2794) (xy 0.5334 -0.254) (xy 0.635 -0.254) (xy 0.635 0.254) (xy 0.5334 0.254)
				(xy 0.5334 0.2794)
			)
			(stroke
				(width 0)
				(type default)
			)
			(fill no)
			(layer "F.CrtYd")
		)
		(pad "1" smd rect
			(at 0.40005 0 180)
			(size 0.4572 0.508)
			(layers "F.Cu" "F.Mask" "F.Paste")
			(net "P3V3_BLAD1")
		)
		(pad "2" smd rect
			(at -0.40005 0 180)
			(size 0.4572 0.508)
			(layers "F.Cu" "F.Mask" "F.Paste")
			(net "ENET10G_1_TX_FAULT")
		)
	)
	(footprint ""
		(layer "F.Cu")
		(at 127.141732 -21.750782 90)
		(property "Reference" "R38"
			(at -6.1722 -60.467748 90)
			(unlocked yes)
			(layer "F.SilkS")
			(effects
				(font
					(size 0.7874 0.5842)
					(thickness 0.1524)
				)
				(justify left)
			)
		)
		(property "Value" ""
			(at 0 0 90)
			(layer "F.Fab")
			(effects
				(font
					(size 1.27 1.27)
				)
			)
		)
		(duplicate_pad_numbers_are_jumpers no)
		(fp_line
			(start 0.7874 -0.4064)
			(end 0.7874 0.4064)
			(stroke
				(width 0.1524)
				(type default)
			)
			(layer "F.SilkS")
		)
		(fp_line
			(start -0.7874 -0.4064)
			(end 0.7874 -0.4064)
			(stroke
				(width 0.1524)
				(type default)
			)
			(layer "F.SilkS")
		)
		(fp_line
			(start 0.7874 0.4064)
			(end -0.7874 0.4064)
			(stroke
				(width 0.1524)
				(type default)
			)
			(layer "F.SilkS")
		)
		(fp_line
			(start -0.7874 0.4064)
			(end -0.7874 -0.4064)
			(stroke
				(width 0.1524)
				(type default)
			)
			(layer "F.SilkS")
		)
		(fp_poly
			(pts
				(xy -0.508 0.2794) (xy -0.508 0.2286) (xy -0.635 0.2286) (xy -0.635 -0.254) (xy -0.5334 -0.254)
				(xy -0.5334 -0.2794) (xy 0.5334 -0.2794) (xy 0.5334 -0.254) (xy 0.635 -0.254) (xy 0.635 0.254) (xy 0.5334 0.254)
				(xy 0.5334 0.2794)
			)
			(stroke
				(width 0)
				(type default)
			)
			(fill no)
			(layer "F.CrtYd")
		)
		(pad "1" smd rect
			(at 0.40005 0 90)
			(size 0.4572 0.508)
			(layers "F.Cu" "F.Mask" "F.Paste")
			(net "GND")
		)
		(pad "2" smd rect
			(at -0.40005 0 90)
			(size 0.4572 0.508)
			(layers "F.Cu" "F.Mask" "F.Paste")
			(net "SKU_PIN_BLAD1_1")
		)
	)
	(footprint ""
		(layer "F.Cu")
		(at 159.047942 -34.3154 90)
		(property "Reference" "L1"
			(at -22.733 32.882078 90)
			(unlocked yes)
			(layer "F.SilkS")
			(effects
				(font
					(size 0.7874 0.5842)
					(thickness 0.1524)
				)
				(justify left)
			)
		)
		(property "Value" ""
			(at 0 0 90)
			(layer "F.Fab")
			(effects
				(font
					(size 1.27 1.27)
				)
			)
		)
		(duplicate_pad_numbers_are_jumpers no)
		(fp_line
			(start -1.905 -0.8636)
			(end 1.905 -0.8636)
			(stroke
				(width 0.1524)
				(type default)
			)
			(layer "F.SilkS")
		)
		(fp_line
			(start 1.905 0.8382)
			(end 1.905 -0.8382)
			(stroke
				(width 0.1524)
				(type default)
			)
			(layer "F.SilkS")
		)
		(fp_line
			(start 0.127 0.8382)
			(end 0.127 -0.8382)
			(stroke
				(width 0.1524)
				(type default)
			)
			(layer "F.SilkS")
		)
		(fp_line
			(start -0.127 0.8382)
			(end -0.127 -0.8382)
			(stroke
				(width 0.1524)
				(type default)
			)
			(layer "F.SilkS")
		)
		(fp_line
			(start -1.905 0.8382)
			(end -1.905 -0.8382)
			(stroke
				(width 0.1524)
				(type default)
			)
			(layer "F.SilkS")
		)
		(fp_line
			(start 1.905 0.8636)
			(end -1.905 0.8636)
			(stroke
				(width 0.1524)
				(type default)
			)
			(layer "F.SilkS")
		)
		(fp_rect
			(start -1.524 0.7112)
			(end 1.524 -0.7366)
			(stroke
				(width 0)
				(type default)
			)
			(fill no)
			(layer "F.CrtYd")
		)
		(pad "1" smd rect
			(at 0.94996 0 90)
			(size 1.1176 1.3716)
			(layers "F.Cu" "F.Mask" "F.Paste")
			(net "P3V3_10G_1_VCCT_L")
		)
		(pad "2" smd rect
			(at -0.94996 0 90)
			(size 1.1176 1.3716)
			(layers "F.Cu" "F.Mask" "F.Paste")
			(net "P3V3_10G_1_VCCT")
		)
	)
	(footprint ""
		(layer "F.Cu")
		(at 172.48505 -28.4099 180)
		(property "Reference" "U3"
			(at -6.976364 -9.255252 0)
			(unlocked yes)
			(layer "F.SilkS")
			(effects
				(font
					(size 0.7874 0.5842)
					(thickness 0.1524)
				)
				(justify left)
			)
		)
		(property "Value" ""
			(at 0 0 180)
			(layer "F.Fab")
			(effects
				(font
					(size 1.27 1.27)
				)
			)
		)
		(duplicate_pad_numbers_are_jumpers no)
		(fp_line
			(start 6.949948 8.32993)
			(end 6.949948 5.7912)
			(stroke
				(width 0.1524)
				(type default)
			)
			(layer "F.SilkS")
		)
		(fp_line
			(start 6.949948 4.572)
			(end 6.949948 0)
			(stroke
				(width 0.1524)
				(type default)
			)
			(layer "F.SilkS")
		)
		(fp_line
			(start 6.949948 0)
			(end 6.949948 -3.670046)
			(stroke
				(width 0.1524)
				(type default)
			)
			(layer "F.SilkS")
		)
		(fp_line
			(start 6.949948 -3.670046)
			(end 0 -3.670046)
			(stroke
				(width 0.1524)
				(type default)
			)
			(layer "F.SilkS")
		)
		(fp_line
			(start 0 -3.670046)
			(end -6.949948 -3.670046)
			(stroke
				(width 0.1524)
				(type default)
			)
			(layer "F.SilkS")
		)
		(fp_line
			(start -6.949948 8.32993)
			(end 6.949948 8.32993)
			(stroke
				(width 0.1524)
				(type default)
			)
			(layer "F.SilkS")
		)
		(fp_line
			(start -6.949948 5.7912)
			(end -6.949948 8.32993)
			(stroke
				(width 0.1524)
				(type default)
			)
			(layer "F.SilkS")
		)
		(fp_line
			(start -6.949948 0)
			(end -6.949948 4.5466)
			(stroke
				(width 0.1524)
				(type default)
			)
			(layer "F.SilkS")
		)
		(fp_line
			(start -6.949948 -3.670046)
			(end -6.949948 0)
			(stroke
				(width 0.1524)
				(type default)
			)
			(layer "F.SilkS")
		)
		(fp_poly
			(pts
				(xy -13.335 1.3208) (xy -15.113 2.3368) (xy -15.113 0.3048)
			)
			(stroke
				(width 0)
				(type default)
			)
			(fill yes)
			(layer "F.SilkS")
		)
		(fp_poly
			(pts
				(arc
					(start 4.933188 5.180076)
					(mid 7.066788 5.180076)
					(end 4.933188 5.180076)
				)
			)
			(stroke
				(width 0)
				(type default)
			)
			(fill no)
			(layer "B.CrtYd")
		)
		(fp_poly
			(pts
				(arc
					(start -7.06755 5.180076)
					(mid -4.932426 5.180076)
					(end -7.06755 5.180076)
				)
			)
			(stroke
				(width 0)
				(type default)
			)
			(fill no)
			(layer "B.CrtYd")
		)
		(fp_poly
			(pts
				(xy -6.949948 8.32993) (xy 6.949948 8.32993) (xy 6.949948 -3.670046) (xy -6.949948 -3.670046)
			)
			(stroke
				(width 0)
				(type default)
			)
			(fill no)
			(layer "F.CrtYd")
		)
		(fp_line
			(start 6.949948 8.32993)
			(end 6.949948 -3.670046)
			(stroke
				(width 0.1)
				(type default)
			)
			(layer "F.Fab")
		)
		(fp_line
			(start 6.949948 -3.670046)
			(end -6.949948 -3.670046)
			(stroke
				(width 0.1)
				(type default)
			)
			(layer "F.Fab")
		)
		(fp_line
			(start -6.700012 0)
			(end -6.949948 0)
			(stroke
				(width 0.1)
				(type default)
			)
			(layer "F.Fab")
		)
		(fp_line
			(start -6.949948 8.32993)
			(end 6.949948 8.32993)
			(stroke
				(width 0.1)
				(type default)
			)
			(layer "F.Fab")
		)
		(fp_line
			(start -6.949948 0)
			(end -6.949948 8.32993)
			(stroke
				(width 0.1)
				(type default)
			)
			(layer "F.Fab")
		)
		(fp_line
			(start -6.949948 -3.670046)
			(end -6.949948 0)
			(stroke
				(width 0.1)
				(type default)
			)
			(layer "F.Fab")
		)
		(fp_poly
			(pts
				(xy -6.9596 0) (xy -8.7376 1.016) (xy -8.7376 -1.016)
			)
			(stroke
				(width 0)
				(type default)
			)
			(fill yes)
			(layer "F.Fab")
		)
		(fp_text user "A13"
			(at 12.341098 0.57658 90)
			(unlocked yes)
			(layer "F.SilkS")
			(effects
				(font
					(size 0.7874 0.5842)
					(thickness 0.1524)
				)
				(justify left)
			)
		)
		(fp_text user "B13"
			(at 12.310872 -4.63042 90)
			(unlocked yes)
			(layer "F.SilkS")
			(effects
				(font
					(size 0.7874 0.5842)
					(thickness 0.1524)
				)
				(justify left)
			)
		)
		(fp_text user "A1"
			(at -9.41578 -9.128252 0)
			(unlocked yes)
			(layer "F.SilkS")
			(effects
				(font
					(size 0.7874 0.5842)
					(thickness 0.1524)
				)
				(justify left)
			)
		)
		(fp_text user "B1"
			(at -9.46658 -10.149078 0)
			(unlocked yes)
			(layer "F.SilkS")
			(effects
				(font
					(size 0.7874 0.5842)
					(thickness 0.1524)
				)
				(justify left)
			)
		)
		(fp_text user "A13"
			(at 7.360666 -0.091948 180)
			(unlocked yes)
			(layer "F.Fab")
			(effects
				(font
					(size 0.7874 0.5842)
					(thickness 0.000001)
				)
				(justify left)
			)
		)
		(fp_text user "B13"
			(at 7.360666 -2.601722 180)
			(unlocked yes)
			(layer "F.Fab")
			(effects
				(font
					(size 0.7874 0.5842)
					(thickness 0.000001)
				)
				(justify left)
			)
		)
		(fp_text user "A1"
			(at -8.609584 1.330452 180)
			(unlocked yes)
			(layer "F.Fab")
			(effects
				(font
					(size 0.7874 0.5842)
					(thickness 0.000001)
				)
				(justify left)
			)
		)
		(fp_text user "B1"
			(at -8.685784 -2.601722 180)
			(unlocked yes)
			(layer "F.Fab")
			(effects
				(font
					(size 0.7874 0.5842)
					(thickness 0.000001)
				)
				(justify left)
			)
		)
		(pad "" np_thru_hole circle
			(at -5.999988 5.180076 180)
			(size 1.6002 1.6002)
			(drill 1.6002)
			(layers "*.Cu" "*.Mask")
			(clearance 0.381)
			(thermal_gap 0.381)
		)
		(pad "" np_thru_hole circle
			(at 5.999988 5.180076 180)
			(size 1.6002 1.6002)
			(drill 1.6002)
			(layers "*.Cu" "*.Mask")
			(clearance 0.381)
			(thermal_gap 0.381)
		)
		(pad "A1" smd rect
			(at -4.59994 0 180)
			(size 0.381 1.8542)
			(layers "F.Cu" "F.Mask" "F.Paste")
			(net "GND")
		)
		(pad "A2" smd rect
			(at -3.800094 0 180)
			(size 0.381 1.8542)
			(layers "F.Cu" "F.Mask" "F.Paste")
			(net "SAS_BLAD1_RX5_P")
		)
		(pad "A3" smd rect
			(at -2.999994 0 180)
			(size 0.381 1.8542)
			(layers "F.Cu" "F.Mask" "F.Paste")
			(net "SAS_BLAD1_RX5_N")
		)
		(pad "A4" smd rect
			(at -2.199894 0 180)
			(size 0.381 1.8542)
			(layers "F.Cu" "F.Mask" "F.Paste")
			(net "GND")
		)
		(pad "A5" smd rect
			(at -1.400048 0 180)
			(size 0.381 1.8542)
			(layers "F.Cu" "F.Mask" "F.Paste")
			(net "SAS_BLAD1_RX6_P")
		)
		(pad "A6" smd rect
			(at -0.599948 0 180)
			(size 0.381 1.8542)
			(layers "F.Cu" "F.Mask" "F.Paste")
			(net "SAS_BLAD1_RX6_N")
		)
		(pad "A7" smd rect
			(at 0.199898 0 180)
			(size 0.381 1.8542)
			(layers "F.Cu" "F.Mask" "F.Paste")
			(net "GND")
		)
		(pad "A8" smd rect
			(at 0.999998 0 180)
			(size 0.381 1.8542)
			(layers "F.Cu" "F.Mask" "F.Paste")
			(net "SAS_BLAD1_RX7_P")
		)
		(pad "A9" smd rect
			(at 1.800098 0 180)
			(size 0.381 1.8542)
			(layers "F.Cu" "F.Mask" "F.Paste")
			(net "SAS_BLAD1_RX7_N")
		)
		(pad "A10" smd rect
			(at 2.599944 0 180)
			(size 0.381 1.8542)
			(layers "F.Cu" "F.Mask" "F.Paste")
			(net "GND")
		)
		(pad "A11" smd rect
			(at 3.400044 0 180)
			(size 0.381 1.8542)
			(layers "F.Cu" "F.Mask" "F.Paste")
			(net "SAS_BLAD1_RX8_P")
		)
		(pad "A12" smd rect
			(at 4.19989 0 180)
			(size 0.381 1.8542)
			(layers "F.Cu" "F.Mask" "F.Paste")
			(net "SAS_BLAD1_RX8_N")
		)
		(pad "A13" smd rect
			(at 4.99999 0 180)
			(size 0.381 1.8542)
			(layers "F.Cu" "F.Mask" "F.Paste")
			(net "GND")
		)
		(pad "B1" smd rect
			(at -4.99999 -2.510028 180)
			(size 0.381 1.8542)
			(layers "F.Cu" "F.Mask" "F.Paste")
			(net "GND")
		)
		(pad "B2" smd rect
			(at -4.19989 -2.510028 180)
			(size 0.381 1.8542)
			(layers "F.Cu" "F.Mask" "F.Paste")
			(net "SAS_BLAD1_TX5_P")
		)
		(pad "B3" smd rect
			(at -3.400044 -2.510028 180)
			(size 0.381 1.8542)
			(layers "F.Cu" "F.Mask" "F.Paste")
			(net "SAS_BLAD1_TX5_N")
		)
		(pad "B4" smd rect
			(at -2.599944 -2.510028 180)
			(size 0.381 1.8542)
			(layers "F.Cu" "F.Mask" "F.Paste")
			(net "GND")
		)
		(pad "B5" smd rect
			(at -1.800098 -2.510028 180)
			(size 0.381 1.8542)
			(layers "F.Cu" "F.Mask" "F.Paste")
			(net "SAS_BLAD1_TX6_P")
		)
		(pad "B6" smd rect
			(at -0.999998 -2.510028 180)
			(size 0.381 1.8542)
			(layers "F.Cu" "F.Mask" "F.Paste")
			(net "SAS_BLAD1_TX6_N")
		)
		(pad "B7" smd rect
			(at -0.199898 -2.510028 180)
			(size 0.381 1.8542)
			(layers "F.Cu" "F.Mask" "F.Paste")
			(net "GND")
		)
		(pad "B8" smd rect
			(at 0.599948 -2.510028 180)
			(size 0.381 1.8542)
			(layers "F.Cu" "F.Mask" "F.Paste")
			(net "SAS_BLAD1_TX7_P")
		)
		(pad "B9" smd rect
			(at 1.400048 -2.510028 180)
			(size 0.381 1.8542)
			(layers "F.Cu" "F.Mask" "F.Paste")
			(net "SAS_BLAD1_TX7_N")
		)
		(pad "B10" smd rect
			(at 2.199894 -2.510028 180)
			(size 0.381 1.8542)
			(layers "F.Cu" "F.Mask" "F.Paste")
			(net "GND")
		)
		(pad "B11" smd rect
			(at 2.999994 -2.510028 180)
			(size 0.381 1.8542)
			(layers "F.Cu" "F.Mask" "F.Paste")
			(net "SAS_BLAD1_TX8_P")
		)
		(pad "B12" smd rect
			(at 3.800094 -2.510028 180)
			(size 0.381 1.8542)
			(layers "F.Cu" "F.Mask" "F.Paste")
			(net "SAS_BLAD1_TX8_N")
		)
		(pad "B13" smd rect
			(at 4.59994 -2.510028 180)
			(size 0.381 1.8542)
			(layers "F.Cu" "F.Mask" "F.Paste")
			(net "GND")
		)
		(zone
			(layer "F.Cu")
			(hatch none 0.5)
			(connect_pads
				(clearance 0)
			)
			(min_thickness 0.25)
			(keepout
				(tracks not_allowed)
				(vias allowed)
				(pads allowed)
				(copperpour not_allowed)
				(footprints allowed)
			)
			(placement
				(enabled no)
				(sheetname "")
			)
			(fill
				(thermal_gap 0.5)
				(thermal_bridge_width 0.5)
				(island_removal_mode 0)
			)
			(polygon
				(pts
					(xy 167.40505 -36.73983) (xy 165.565074 -36.73983) (xy 165.565074 -35.279838) (xy 167.40505 -35.279838)
				)
			)
		)
		(zone
			(layer "F.Cu")
			(hatch none 0.5)
			(connect_pads
				(clearance 0)
			)
			(min_thickness 0.25)
			(keepout
				(tracks not_allowed)
				(vias allowed)
				(pads allowed)
				(copperpour not_allowed)
				(footprints allowed)
			)
			(placement
				(enabled no)
				(sheetname "")
			)
			(fill
				(thermal_gap 0.5)
				(thermal_bridge_width 0.5)
				(island_removal_mode 0)
			)
			(polygon
				(pts
					(xy 179.405026 -36.73983) (xy 177.56505 -36.73983) (xy 177.56505 -35.279838) (xy 179.405026 -35.279838)
				)
			)
		)
		(zone
			(layers "F.Cu" "B.Cu" "In1.Cu" "In2.Cu" "In3.Cu" "In4.Cu" "In5.Cu" "In6.Cu")
			(hatch none 0.5)
			(connect_pads
				(clearance 0)
			)
			(min_thickness 0.25)
			(keepout
				(tracks not_allowed)
				(vias allowed)
				(pads allowed)
				(copperpour not_allowed)
				(footprints allowed)
			)
			(placement
				(enabled no)
				(sheetname "")
			)
			(fill
				(thermal_gap 0.5)
				(thermal_bridge_width 0.5)
				(island_removal_mode 0)
			)
			(polygon
				(pts
					(arc
						(start 167.704008 -33.589976)
						(mid 165.266116 -33.589976)
						(end 167.704008 -33.589976)
					)
				)
			)
		)
		(zone
			(layers "F.Cu" "B.Cu" "In1.Cu" "In2.Cu" "In3.Cu" "In4.Cu" "In5.Cu" "In6.Cu")
			(hatch none 0.5)
			(connect_pads
				(clearance 0)
			)
			(min_thickness 0.25)
			(keepout
				(tracks not_allowed)
				(vias allowed)
				(pads allowed)
				(copperpour not_allowed)
				(footprints allowed)
			)
			(placement
				(enabled no)
				(sheetname "")
			)
			(fill
				(thermal_gap 0.5)
				(thermal_bridge_width 0.5)
				(island_removal_mode 0)
			)
			(polygon
				(pts
					(arc
						(start 179.704746 -33.589976)
						(mid 177.26533 -33.589976)
						(end 179.704746 -33.589976)
					)
				)
			)
		)
	)
	(footprint ""
		(layer "F.Cu")
		(at 378.431552 -23.636478)
		(property "Reference" "R50"
			(at 33.528 16.545052 0)
			(unlocked yes)
			(layer "F.SilkS")
			(effects
				(font
					(size 0.7874 0.5842)
					(thickness 0.1524)
				)
				(justify left)
			)
		)
		(property "Value" ""
			(at 0 0 0)
			(layer "F.Fab")
			(effects
				(font
					(size 1.27 1.27)
				)
			)
		)
		(duplicate_pad_numbers_are_jumpers no)
		(fp_line
			(start -0.7874 -0.4064)
			(end 0.7874 -0.4064)
			(stroke
				(width 0.1524)
				(type default)
			)
			(layer "F.SilkS")
		)
		(fp_line
			(start -0.7874 0.4064)
			(end -0.7874 -0.4064)
			(stroke
				(width 0.1524)
				(type default)
			)
			(layer "F.SilkS")
		)
		(fp_line
			(start 0.7874 -0.4064)
			(end 0.7874 0.4064)
			(stroke
				(width 0.1524)
				(type default)
			)
			(layer "F.SilkS")
		)
		(fp_line
			(start 0.7874 0.4064)
			(end -0.7874 0.4064)
			(stroke
				(width 0.1524)
				(type default)
			)
			(layer "F.SilkS")
		)
		(fp_poly
			(pts
				(xy -0.508 0.2794) (xy -0.508 0.2286) (xy -0.635 0.2286) (xy -0.635 -0.254) (xy -0.5334 -0.254)
				(xy -0.5334 -0.2794) (xy 0.5334 -0.2794) (xy 0.5334 -0.254) (xy 0.635 -0.254) (xy 0.635 0.254) (xy 0.5334 0.254)
				(xy 0.5334 0.2794)
			)
			(stroke
				(width 0)
				(type default)
			)
			(fill no)
			(layer "F.CrtYd")
		)
		(pad "1" smd rect
			(at 0.40005 0)
			(size 0.4572 0.508)
			(layers "F.Cu" "F.Mask" "F.Paste")
			(net "GND")
		)
		(pad "2" smd rect
			(at -0.40005 0)
			(size 0.4572 0.508)
			(layers "F.Cu" "F.Mask" "F.Paste")
			(net "ENET10G_3_TX_FAULT")
		)
	)
	(footprint ""
		(layer "F.Cu")
		(at 364.0836 -3.0988 90)
		(property "Reference" "C29"
			(at -2.286 -2.022348 90)
			(unlocked yes)
			(layer "F.SilkS")
			(effects
				(font
					(size 0.7874 0.5842)
					(thickness 0.1524)
				)
				(justify left)
			)
		)
		(property "Value" ""
			(at 0 0 90)
			(layer "F.Fab")
			(effects
				(font
					(size 1.27 1.27)
				)
			)
		)
		(duplicate_pad_numbers_are_jumpers no)
		(fp_line
			(start 0.7874 -0.4064)
			(end 0.7874 0.4064)
			(stroke
				(width 0.1524)
				(type default)
			)
			(layer "F.SilkS")
		)
		(fp_line
			(start -0.7874 -0.4064)
			(end 0.7874 -0.4064)
			(stroke
				(width 0.1524)
				(type default)
			)
			(layer "F.SilkS")
		)
		(fp_line
			(start 0 0.381)
			(end 0 -0.381)
			(stroke
				(width 0.1524)
				(type default)
			)
			(layer "F.SilkS")
		)
		(fp_line
			(start 0.7874 0.4064)
			(end -0.7874 0.4064)
			(stroke
				(width 0.1524)
				(type default)
			)
			(layer "F.SilkS")
		)
		(fp_line
			(start -0.7874 0.4064)
			(end -0.7874 -0.4064)
			(stroke
				(width 0.1524)
				(type default)
			)
			(layer "F.SilkS")
		)
		(fp_poly
			(pts
				(xy -0.5334 0.254) (xy -0.635 0.254) (xy -0.635 0.2286) (xy -0.635 -0.254) (xy -0.5334 -0.254) (xy -0.5334 -0.2794)
				(xy 0.5334 -0.2794) (xy 0.5334 -0.254) (xy 0.635 -0.254) (xy 0.635 0.254) (xy 0.5334 0.254) (xy 0.5334 0.2794)
				(xy -0.508 0.2794) (xy -0.5334 0.2794)
			)
			(stroke
				(width 0)
				(type default)
			)
			(fill no)
			(layer "F.CrtYd")
		)
		(pad "1" smd rect
			(at 0.40005 0 90)
			(size 0.4572 0.508)
			(layers "F.Cu" "F.Mask" "F.Paste")
			(net "P3V3_10G_3_VCCR")
		)
		(pad "2" smd rect
			(at -0.40005 0 90)
			(size 0.4572 0.508)
			(layers "F.Cu" "F.Mask" "F.Paste")
			(net "GND")
		)
	)
	(footprint ""
		(layer "F.Cu")
		(at 154.89936 -25.439878 180)
		(property "Reference" "R11"
			(at -33.71088 -17.844008 0)
			(unlocked yes)
			(layer "F.SilkS")
			(effects
				(font
					(size 0.7874 0.5842)
					(thickness 0.1524)
				)
				(justify left)
			)
		)
		(property "Value" ""
			(at 0 0 180)
			(layer "F.Fab")
			(effects
				(font
					(size 1.27 1.27)
				)
			)
		)
		(duplicate_pad_numbers_are_jumpers no)
		(fp_line
			(start 0.7874 0.4064)
			(end -0.7874 0.4064)
			(stroke
				(width 0.1524)
				(type default)
			)
			(layer "F.SilkS")
		)
		(fp_line
			(start 0.7874 -0.4064)
			(end 0.7874 0.4064)
			(stroke
				(width 0.1524)
				(type default)
			)
			(layer "F.SilkS")
		)
		(fp_line
			(start -0.7874 0.4064)
			(end -0.7874 -0.4064)
			(stroke
				(width 0.1524)
				(type default)
			)
			(layer "F.SilkS")
		)
		(fp_line
			(start -0.7874 -0.4064)
			(end 0.7874 -0.4064)
			(stroke
				(width 0.1524)
				(type default)
			)
			(layer "F.SilkS")
		)
		(fp_poly
			(pts
				(xy -0.508 0.2794) (xy -0.508 0.2286) (xy -0.635 0.2286) (xy -0.635 -0.254) (xy -0.5334 -0.254)
				(xy -0.5334 -0.2794) (xy 0.5334 -0.2794) (xy 0.5334 -0.254) (xy 0.635 -0.254) (xy 0.635 0.254) (xy 0.5334 0.254)
				(xy 0.5334 0.2794)
			)
			(stroke
				(width 0)
				(type default)
			)
			(fill no)
			(layer "F.CrtYd")
		)
		(pad "1" smd rect
			(at 0.40005 0 180)
			(size 0.4572 0.508)
			(layers "F.Cu" "F.Mask" "F.Paste")
			(net "P3V3_BLAD1")
		)
		(pad "2" smd rect
			(at -0.40005 0 180)
			(size 0.4572 0.508)
			(layers "F.Cu" "F.Mask" "F.Paste")
			(net "ENET10G_1_RS0")
		)
	)
	(footprint ""
		(layer "F.Cu")
		(at 332.695042 -49.795176)
		(property "Reference" "J18"
			(at -19.345148 3.078734 90)
			(unlocked yes)
			(layer "F.SilkS")
			(effects
				(font
					(size 0.7874 0.5842)
					(thickness 0.1524)
				)
				(justify left)
			)
		)
		(property "Value" ""
			(at 0 0 0)
			(layer "F.Fab")
			(effects
				(font
					(size 1.27 1.27)
				)
			)
		)
		(duplicate_pad_numbers_are_jumpers no)
		(fp_line
			(start -18.2499 -9.99998)
			(end 3.999992 -9.99998)
			(stroke
				(width 0.1524)
				(type default)
			)
			(layer "F.SilkS")
		)
		(fp_line
			(start -18.2499 45.299884)
			(end -18.2499 -9.99998)
			(stroke
				(width 0.1524)
				(type default)
			)
			(layer "F.SilkS")
		)
		(fp_line
			(start -15.249906 -6.999986)
			(end 0.999998 -6.999986)
			(stroke
				(width 0.1524)
				(type default)
			)
			(layer "F.SilkS")
		)
		(fp_line
			(start -15.249906 42.29989)
			(end -15.249906 -6.999986)
			(stroke
				(width 0.1524)
				(type default)
			)
			(layer "F.SilkS")
		)
		(fp_line
			(start -13.24991 26.800048)
			(end -13.24991 41.299892)
			(stroke
				(width 0.1524)
				(type default)
			)
			(layer "F.SilkS")
		)
		(fp_line
			(start -13.24991 41.299892)
			(end -12.6746 41.299892)
			(stroke
				(width 0.1524)
				(type default)
			)
			(layer "F.SilkS")
		)
		(fp_line
			(start -12.319 42.29989)
			(end -15.249906 42.29989)
			(stroke
				(width 0.1524)
				(type default)
			)
			(layer "F.SilkS")
		)
		(fp_line
			(start -11.176 41.299892)
			(end -10.919968 41.299892)
			(stroke
				(width 0.1524)
				(type default)
			)
			(layer "F.SilkS")
		)
		(fp_line
			(start -10.919968 41.299892)
			(end -10.919968 42.29989)
			(stroke
				(width 0.1524)
				(type default)
			)
			(layer "F.SilkS")
		)
		(fp_line
			(start -10.919968 42.29989)
			(end -11.5316 42.29989)
			(stroke
				(width 0.1524)
				(type default)
			)
			(layer "F.SilkS")
		)
		(fp_line
			(start -4.425442 45.299884)
			(end -18.2499 45.299884)
			(stroke
				(width 0.1524)
				(type default)
			)
			(layer "F.SilkS")
		)
		(fp_line
			(start -3.32994 41.299892)
			(end -3.0734 41.299892)
			(stroke
				(width 0.1524)
				(type default)
			)
			(layer "F.SilkS")
		)
		(fp_line
			(start -3.32994 42.29989)
			(end -3.32994 41.299892)
			(stroke
				(width 0.1524)
				(type default)
			)
			(layer "F.SilkS")
		)
		(fp_line
			(start -2.7178 42.29989)
			(end -3.32994 42.29989)
			(stroke
				(width 0.1524)
				(type default)
			)
			(layer "F.SilkS")
		)
		(fp_line
			(start -1.5748 41.299892)
			(end -0.999998 41.299892)
			(stroke
				(width 0.1524)
				(type default)
			)
			(layer "F.SilkS")
		)
		(fp_line
			(start -0.999998 26.800048)
			(end -13.24991 26.800048)
			(stroke
				(width 0.1524)
				(type default)
			)
			(layer "F.SilkS")
		)
		(fp_line
			(start -0.999998 41.299892)
			(end -0.999998 26.800048)
			(stroke
				(width 0.1524)
				(type default)
			)
			(layer "F.SilkS")
		)
		(fp_line
			(start 0.999998 -6.999986)
			(end 0.999998 42.29989)
			(stroke
				(width 0.1524)
				(type default)
			)
			(layer "F.SilkS")
		)
		(fp_line
			(start 0.999998 42.29989)
			(end -1.9558 42.29989)
			(stroke
				(width 0.1524)
				(type default)
			)
			(layer "F.SilkS")
		)
		(fp_line
			(start 3.999992 -9.99998)
			(end 3.999992 45.299884)
			(stroke
				(width 0.1524)
				(type default)
			)
			(layer "F.SilkS")
		)
		(fp_line
			(start 3.999992 45.299884)
			(end 2.838958 45.299884)
			(stroke
				(width 0.1524)
				(type default)
			)
			(layer "F.SilkS")
		)
		(fp_poly
			(pts
				(xy 0.6858 4.1021) (xy 4.1148 5.2451) (xy 4.1148 2.9591)
			)
			(stroke
				(width 0)
				(type default)
			)
			(fill yes)
			(layer "F.SilkS")
		)
		(fp_line
			(start -18.2499 -9.99998)
			(end 3.999992 -9.99998)
			(stroke
				(width 0.1524)
				(type default)
			)
			(layer "B.SilkS")
		)
		(fp_line
			(start -18.2499 16.775176)
			(end -18.2499 -9.99998)
			(stroke
				(width 0.1524)
				(type default)
			)
			(layer "B.SilkS")
		)
		(fp_line
			(start -18.2499 45.299884)
			(end -18.2499 17.816576)
			(stroke
				(width 0.1524)
				(type default)
			)
			(layer "B.SilkS")
		)
		(fp_line
			(start 3.999992 -9.99998)
			(end 3.999992 36.663376)
			(stroke
				(width 0.1524)
				(type default)
			)
			(layer "B.SilkS")
		)
		(fp_line
			(start 3.999992 39.660576)
			(end 3.999992 42.302176)
			(stroke
				(width 0.1524)
				(type default)
			)
			(layer "B.SilkS")
		)
		(fp_line
			(start 3.999992 43.902376)
			(end 3.999992 45.299884)
			(stroke
				(width 0.1524)
				(type default)
			)
			(layer "B.SilkS")
		)
		(fp_line
			(start 3.999992 45.299884)
			(end -18.2499 45.299884)
			(stroke
				(width 0.1524)
				(type default)
			)
			(layer "B.SilkS")
		)
		(fp_poly
			(pts
				(xy -15.0876 8.6614) (xy -13.4112 8.6614) (xy -13.4112 10.3378) (xy -15.0876 10.3378)
			)
			(stroke
				(width 0)
				(type default)
			)
			(fill no)
			(layer "B.CrtYd")
		)
		(fp_poly
			(pts
				(xy -15.0876 18.669) (xy -13.4112 18.669) (xy -13.4112 20.3454) (xy -15.0876 20.3454)
			)
			(stroke
				(width 0)
				(type default)
			)
			(fill no)
			(layer "B.CrtYd")
		)
		(fp_poly
			(pts
				(xy -15.0876 28.6512) (xy -13.4112 28.6512) (xy -13.4112 30.3276) (xy -15.0876 30.3276)
			)
			(stroke
				(width 0)
				(type default)
			)
			(fill no)
			(layer "B.CrtYd")
		)
		(fp_poly
			(pts
				(xy -15.0876 38.6588) (xy -13.4112 38.6588) (xy -13.4112 40.3352) (xy -15.0876 40.3352)
			)
			(stroke
				(width 0)
				(type default)
			)
			(fill no)
			(layer "B.CrtYd")
		)
		(fp_poly
			(pts
				(xy -14.986 26.5684) (xy -13.5128 26.5684) (xy -13.5128 28.0416) (xy -14.986 28.0416)
			)
			(stroke
				(width 0)
				(type default)
			)
			(fill no)
			(layer "B.CrtYd")
		)
		(fp_poly
			(pts
				(xy -14.986 31.2674) (xy -13.5128 31.2674) (xy -13.5128 32.7406) (xy -14.986 32.7406)
			)
			(stroke
				(width 0)
				(type default)
			)
			(fill no)
			(layer "B.CrtYd")
		)
		(fp_poly
			(pts
				(xy -14.986 36.2712) (xy -13.5128 36.2712) (xy -13.5128 37.7444) (xy -14.986 37.7444)
			)
			(stroke
				(width 0)
				(type default)
			)
			(fill no)
			(layer "B.CrtYd")
		)
		(fp_poly
			(pts
				(xy -12.6746 40.8686) (xy -11.2014 40.8686) (xy -11.2014 42.3418) (xy -12.6746 42.3418)
			)
			(stroke
				(width 0)
				(type default)
			)
			(fill no)
			(layer "B.CrtYd")
		)
		(fp_poly
			(pts
				(xy -11.9126 23.6728) (xy -10.2362 23.6728) (xy -10.2362 25.3492) (xy -11.9126 25.3492)
			)
			(stroke
				(width 0)
				(type default)
			)
			(fill no)
			(layer "B.CrtYd")
		)
		(fp_poly
			(pts
				(xy -9.4488 3.6576) (xy -7.7724 3.6576) (xy -7.7724 5.334) (xy -9.4488 5.334)
			)
			(stroke
				(width 0)
				(type default)
			)
			(fill no)
			(layer "B.CrtYd")
		)
		(fp_poly
			(pts
				(xy -7.874 40.8686) (xy -6.4008 40.8686) (xy -6.4008 42.3418) (xy -7.874 42.3418)
			)
			(stroke
				(width 0)
				(type default)
			)
			(fill no)
			(layer "B.CrtYd")
		)
		(fp_poly
			(pts
				(xy -6.5278 23.6728) (xy -4.8514 23.6728) (xy -4.8514 25.3492) (xy -6.5278 25.3492)
			)
			(stroke
				(width 0)
				(type default)
			)
			(fill no)
			(layer "B.CrtYd")
		)
		(fp_poly
			(pts
				(xy -3.0734 40.8686) (xy -1.6002 40.8686) (xy -1.6002 42.3418) (xy -3.0734 42.3418)
			)
			(stroke
				(width 0)
				(type default)
			)
			(fill no)
			(layer "B.CrtYd")
		)
		(fp_poly
			(pts
				(xy -0.8382 3.6576) (xy 0.8382 3.6576) (xy 0.8382 5.334) (xy -0.8382 5.334)
			)
			(stroke
				(width 0)
				(type default)
			)
			(fill no)
			(layer "B.CrtYd")
		)
		(fp_poly
			(pts
				(xy -0.8382 23.6728) (xy 0.8382 23.6728) (xy 0.8382 25.3492) (xy -0.8382 25.3492)
			)
			(stroke
				(width 0)
				(type default)
			)
			(fill no)
			(layer "B.CrtYd")
		)
		(fp_poly
			(pts
				(xy -0.7366 26.5684) (xy 0.7366 26.5684) (xy 0.7366 28.0416) (xy -0.7366 28.0416)
			)
			(stroke
				(width 0)
				(type default)
			)
			(fill no)
			(layer "B.CrtYd")
		)
		(fp_poly
			(pts
				(xy -0.7366 31.2674) (xy 0.7366 31.2674) (xy 0.7366 32.7406) (xy -0.7366 32.7406)
			)
			(stroke
				(width 0)
				(type default)
			)
			(fill no)
			(layer "B.CrtYd")
		)
		(fp_poly
			(pts
				(xy -0.7366 36.2712) (xy 0.7366 36.2712) (xy 0.7366 37.7444) (xy -0.7366 37.7444)
			)
			(stroke
				(width 0)
				(type default)
			)
			(fill no)
			(layer "B.CrtYd")
		)
		(fp_poly
			(pts
				(xy -0.6858 33.8074) (xy 0.6858 33.8074) (xy 0.6858 35.179) (xy -0.6858 35.179)
			)
			(stroke
				(width 0)
				(type default)
			)
			(fill no)
			(layer "B.CrtYd")
		)
		(fp_poly
			(pts
				(xy 0.8382 14.5542) (xy 0.8382 13.6652) (xy 0 13.6652) (xy -0.8382 13.6652) (xy -0.8382 15.3416)
				(xy 0.8382 15.3416)
			)
			(stroke
				(width 0)
				(type default)
			)
			(fill no)
			(layer "B.CrtYd")
		)
		(fp_rect
			(start -8.130032 42.29989)
			(end -6.130036 41.299892)
			(stroke
				(width 0)
				(type default)
			)
			(fill no)
			(layer "F.CrtYd")
		)
		(fp_poly
			(pts
				(xy 0.999998 -6.999986) (xy 0.999998 42.29989) (xy -3.32994 42.29989) (xy -3.32994 41.299892) (xy -0.999998 41.299892)
				(xy -0.999998 26.800048) (xy -13.24991 26.800048) (xy -13.24991 41.299892) (xy -10.919968 41.299892)
				(xy -10.919968 42.29989) (xy -15.249906 42.29989) (xy -15.249906 -6.999986)
			)
			(stroke
				(width 0)
				(type default)
			)
			(fill no)
			(layer "F.CrtYd")
		)
		(fp_line
			(start -15.249906 -6.999986)
			(end 0.999998 -6.999986)
			(stroke
				(width 0.1)
				(type default)
			)
			(layer "F.Fab")
		)
		(fp_line
			(start -15.249906 0)
			(end 0.999998 0)
			(stroke
				(width 0.1)
				(type default)
			)
			(layer "F.Fab")
		)
		(fp_line
			(start -15.249906 41.999916)
			(end -15.249906 -6.999986)
			(stroke
				(width 0.1)
				(type default)
			)
			(layer "F.Fab")
		)
		(fp_line
			(start -15.249906 42.29989)
			(end -15.249906 0)
			(stroke
				(width 0.1)
				(type default)
			)
			(layer "F.Fab")
		)
		(fp_line
			(start -13.24991 26.800048)
			(end -13.24991 41.299892)
			(stroke
				(width 0.1)
				(type default)
			)
			(layer "F.Fab")
		)
		(fp_line
			(start -13.24991 41.299892)
			(end -10.919968 41.299892)
			(stroke
				(width 0.1)
				(type default)
			)
			(layer "F.Fab")
		)
		(fp_line
			(start -10.919968 41.299892)
			(end -10.919968 42.29989)
			(stroke
				(width 0.1)
				(type default)
			)
			(layer "F.Fab")
		)
		(fp_line
			(start -10.919968 42.29989)
			(end -15.249906 42.29989)
			(stroke
				(width 0.1)
				(type default)
			)
			(layer "F.Fab")
		)
		(fp_line
			(start -3.32994 41.299892)
			(end -0.999998 41.299892)
			(stroke
				(width 0.1)
				(type default)
			)
			(layer "F.Fab")
		)
		(fp_line
			(start -3.32994 42.29989)
			(end -3.32994 41.299892)
			(stroke
				(width 0.1)
				(type default)
			)
			(layer "F.Fab")
		)
		(fp_line
			(start -0.999998 26.800048)
			(end -13.24991 26.800048)
			(stroke
				(width 0.1)
				(type default)
			)
			(layer "F.Fab")
		)
		(fp_line
			(start -0.999998 41.299892)
			(end -0.999998 26.800048)
			(stroke
				(width 0.1)
				(type default)
			)
			(layer "F.Fab")
		)
		(fp_line
			(start 0.999998 -6.999986)
			(end 0.999998 41.999916)
			(stroke
				(width 0.1)
				(type default)
			)
			(layer "F.Fab")
		)
		(fp_line
			(start 0.999998 0)
			(end 0.999998 42.29989)
			(stroke
				(width 0.1)
				(type default)
			)
			(layer "F.Fab")
		)
		(fp_line
			(start 0.999998 41.999916)
			(end -15.249906 41.999916)
			(stroke
				(width 0.1)
				(type default)
			)
			(layer "F.Fab")
		)
		(fp_line
			(start 0.999998 42.29989)
			(end -3.32994 42.29989)
			(stroke
				(width 0.1)
				(type default)
			)
			(layer "F.Fab")
		)
		(fp_text user "PRESS-FIT"
			(at -16.70939 23.449788 90)
			(unlocked yes)
			(layer "F.SilkS")
			(effects
				(font
					(size 1.6002 1.1938)
					(thickness 0.1524)
				)
				(justify left)
			)
		)
		(fp_text user "PRESS-FIT"
			(at -16.919194 22.450552 270)
			(unlocked yes)
			(layer "B.SilkS")
			(effects
				(font
					(size 1.6002 1.1938)
					(thickness 0.1524)
				)
				(justify left mirror)
			)
		)
		(pad "1" thru_hole circle
			(at 0 4.500118)
			(size 1.5494 1.5494)
			(drill 1.0414)
			(layers "*.Cu" "*.Mask")
			(remove_unused_layers no)
			(net "GND")
			(clearance 0)
		)
		(pad "2" thru_hole circle
			(at -8.58012 4.500118)
			(size 1.5494 1.5494)
			(drill 1.0414)
			(layers "*.Cu" "*.Mask")
			(remove_unused_layers no)
			(net "GND")
			(clearance 0)
		)
		(pad "3" thru_hole circle
			(at 0 14.500098)
			(size 1.5494 1.5494)
			(drill 1.0414)
			(layers "*.Cu" "*.Mask")
			(remove_unused_layers no)
			(net "GND")
			(clearance 0)
		)
		(pad "4" thru_hole circle
			(at -14.249908 9.500108)
			(size 1.5494 1.5494)
			(drill 1.0414)
			(layers "*.Cu" "*.Mask")
			(remove_unused_layers no)
			(net "GND")
			(clearance 0)
		)
		(pad "5" thru_hole circle
			(at -14.249908 19.500088)
			(size 1.5494 1.5494)
			(drill 1.0414)
			(layers "*.Cu" "*.Mask")
			(remove_unused_layers no)
			(net "GND")
			(clearance 0)
		)
		(pad "6" thru_hole circle
			(at 0 24.500078)
			(size 1.5494 1.5494)
			(drill 1.0414)
			(layers "*.Cu" "*.Mask")
			(remove_unused_layers no)
			(net "GND")
			(clearance 0)
		)
		(pad "7" thru_hole circle
			(at -5.679948 24.500078)
			(size 1.5494 1.5494)
			(drill 1.0414)
			(layers "*.Cu" "*.Mask")
			(remove_unused_layers no)
			(net "GND")
			(clearance 0)
		)
		(pad "8" thru_hole circle
			(at -11.079988 24.500078)
			(size 1.5494 1.5494)
			(drill 1.0414)
			(layers "*.Cu" "*.Mask")
			(remove_unused_layers no)
			(net "GND")
			(clearance 0)
		)
		(pad "9" thru_hole circle
			(at -14.249908 29.500068)
			(size 1.5494 1.5494)
			(drill 1.0414)
			(layers "*.Cu" "*.Mask")
			(remove_unused_layers no)
			(net "GND")
			(clearance 0)
		)
		(pad "10" thru_hole circle
			(at -14.249908 39.500048)
			(size 1.5494 1.5494)
			(drill 1.0414)
			(layers "*.Cu" "*.Mask")
			(remove_unused_layers no)
			(net "GND")
			(clearance 0)
		)
		(pad "11" thru_hole circle
			(at 0 27.29992)
			(size 1.3462 1.3462)
			(drill 0.9398)
			(layers "*.Cu" "*.Mask")
			(remove_unused_layers no)
			(net "GND")
			(clearance 0.0508)
			(thermal_gap 0.0508)
		)
		(pad "12" thru_hole circle
			(at 0 31.999936)
			(size 1.3462 1.3462)
			(drill 0.9398)
			(layers "*.Cu" "*.Mask")
			(remove_unused_layers no)
			(net "GND")
			(clearance 0.0508)
			(thermal_gap 0.0508)
		)
		(pad "13" thru_hole circle
			(at 0 36.999926)
			(size 1.3462 1.3462)
			(drill 0.9398)
			(layers "*.Cu" "*.Mask")
			(remove_unused_layers no)
			(net "GND")
			(clearance 0.0508)
			(thermal_gap 0.0508)
		)
		(pad "14" thru_hole circle
			(at -2.329942 41.60012)
			(size 1.3462 1.3462)
			(drill 0.9398)
			(layers "*.Cu" "*.Mask")
			(remove_unused_layers no)
			(net "GND")
			(clearance 0.0508)
			(thermal_gap 0.0508)
		)
		(pad "15" thru_hole circle
			(at -7.130034 41.60012)
			(size 1.3462 1.3462)
			(drill 0.9398)
			(layers "*.Cu" "*.Mask")
			(remove_unused_layers no)
			(net "GND")
			(clearance 0.0508)
			(thermal_gap 0.0508)
		)
		(pad "16" thru_hole circle
			(at -11.929872 41.60012)
			(size 1.3462 1.3462)
			(drill 0.9398)
			(layers "*.Cu" "*.Mask")
			(remove_unused_layers no)
			(net "GND")
			(clearance 0.0508)
			(thermal_gap 0.0508)
		)
		(pad "17" thru_hole circle
			(at -14.249908 27.29992)
			(size 1.3462 1.3462)
			(drill 0.9398)
			(layers "*.Cu" "*.Mask")
			(remove_unused_layers no)
			(net "GND")
			(clearance 0.0508)
			(thermal_gap 0.0508)
		)
		(pad "18" thru_hole circle
			(at -14.249908 31.999936)
			(size 1.3462 1.3462)
			(drill 0.9398)
			(layers "*.Cu" "*.Mask")
			(remove_unused_layers no)
			(net "GND")
			(clearance 0.0508)
			(thermal_gap 0.0508)
		)
		(pad "19" thru_hole circle
			(at -14.249908 36.999926)
			(size 1.3462 1.3462)
			(drill 0.9398)
			(layers "*.Cu" "*.Mask")
			(remove_unused_layers no)
			(net "GND")
			(clearance 0.0508)
			(thermal_gap 0.0508)
		)
		(pad "20" thru_hole circle
			(at 0 34.500058)
			(size 1.2446 1.2446)
			(drill 0.8382)
			(layers "*.Cu" "*.Mask")
			(remove_unused_layers no)
			(net "GND")
			(clearance 0.0508)
			(thermal_gap 0.0508)
		)
		(zone
			(layer "F.Cu")
			(hatch none 0.5)
			(connect_pads
				(clearance 0)
			)
			(min_thickness 0.25)
			(keepout
				(tracks not_allowed)
				(vias allowed)
				(pads allowed)
				(copperpour not_allowed)
				(footprints allowed)
			)
			(placement
				(enabled no)
				(sheetname "")
			)
			(fill
				(thermal_gap 0.5)
				(thermal_bridge_width 0.5)
				(island_removal_mode 0)
			)
			(polygon
				(pts
					(xy 324.56501 -7.495286) (xy 326.565006 -7.495286) (xy 326.565006 -8.495284) (xy 324.56501 -8.495284)
				)
			)
		)
		(zone
			(layer "F.Cu")
			(hatch none 0.5)
			(connect_pads
				(clearance 0)
			)
			(min_thickness 0.25)
			(keepout
				(tracks not_allowed)
				(vias allowed)
				(pads allowed)
				(copperpour not_allowed)
				(footprints allowed)
			)
			(placement
				(enabled no)
				(sheetname "")
			)
			(fill
				(thermal_gap 0.5)
				(thermal_bridge_width 0.5)
				(island_removal_mode 0)
			)
			(polygon
				(pts
					(xy 333.69504 -49.795176) (xy 333.69504 -7.495286) (xy 329.365102 -7.495286) (xy 329.365102 -8.495284)
					(xy 331.695044 -8.495284) (xy 331.695044 -22.995128) (xy 319.445132 -22.995128) (xy 319.445132 -8.495284)
					(xy 321.775074 -8.495284) (xy 321.775074 -7.495286) (xy 317.445136 -7.495286) (xy 317.451486 -49.795176)
				)
			)
		)
		(zone
			(layers "F.Cu" "B.Cu" "In1.Cu" "In2.Cu" "In3.Cu" "In4.Cu" "In5.Cu" "In6.Cu")
			(hatch none 0.5)
			(connect_pads
				(clearance 0)
			)
			(min_thickness 0.25)
			(keepout
				(tracks allowed)
				(vias not_allowed)
				(pads allowed)
				(copperpour not_allowed)
				(footprints allowed)
			)
			(placement
				(enabled no)
				(sheetname "")
			)
			(fill
				(thermal_gap 0.5)
				(thermal_bridge_width 0.5)
				(island_removal_mode 0)
			)
			(polygon
				(pts
					(xy 317.607442 -39.457376) (xy 319.283842 -39.457376) (xy 319.283842 -41.133776) (xy 317.607442 -41.133776)
				)
			)
		)
		(zone
			(layers "F.Cu" "B.Cu" "In1.Cu" "In2.Cu" "In3.Cu" "In4.Cu" "In5.Cu" "In6.Cu")
			(hatch none 0.5)
			(connect_pads
				(clearance 0)
			)
			(min_thickness 0.25)
			(keepout
				(tracks allowed)
				(vias not_allowed)
				(pads allowed)
				(copperpour not_allowed)
				(footprints allowed)
			)
			(placement
				(enabled no)
				(sheetname "")
			)
			(fill
				(thermal_gap 0.5)
				(thermal_bridge_width 0.5)
				(island_removal_mode 0)
			)
			(polygon
				(pts
					(xy 317.607442 -29.449776) (xy 319.283842 -29.449776) (xy 319.283842 -31.126176) (xy 317.607442 -31.126176)
				)
			)
		)
		(zone
			(layers "F.Cu" "B.Cu" "In1.Cu" "In2.Cu" "In3.Cu" "In4.Cu" "In5.Cu" "In6.Cu")
			(hatch none 0.5)
			(connect_pads
				(clearance 0)
			)
			(min_thickness 0.25)
			(keepout
				(tracks allowed)
				(vias not_allowed)
				(pads allowed)
				(copperpour not_allowed)
				(footprints allowed)
			)
			(placement
				(enabled no)
				(sheetname "")
			)
			(fill
				(thermal_gap 0.5)
				(thermal_bridge_width 0.5)
				(island_removal_mode 0)
			)
			(polygon
				(pts
					(xy 317.607442 -19.467576) (xy 319.283842 -19.467576) (xy 319.283842 -21.143976) (xy 317.607442 -21.143976)
				)
			)
		)
		(zone
			(layers "F.Cu" "B.Cu" "In1.Cu" "In2.Cu" "In3.Cu" "In4.Cu" "In5.Cu" "In6.Cu")
			(hatch none 0.5)
			(connect_pads
				(clearance 0)
			)
			(min_thickness 0.25)
			(keepout
				(tracks allowed)
				(vias not_allowed)
				(pads allowed)
				(copperpour not_allowed)
				(footprints allowed)
			)
			(placement
				(enabled no)
				(sheetname "")
			)
			(fill
				(thermal_gap 0.5)
				(thermal_bridge_width 0.5)
				(island_removal_mode 0)
			)
			(polygon
				(pts
					(xy 317.607442 -9.459976) (xy 319.283842 -9.459976) (xy 319.283842 -11.136376) (xy 317.607442 -11.136376)
				)
			)
		)
		(zone
			(layers "F.Cu" "B.Cu" "In1.Cu" "In2.Cu" "In3.Cu" "In4.Cu" "In5.Cu" "In6.Cu")
			(hatch none 0.5)
			(connect_pads
				(clearance 0)
			)
			(min_thickness 0.25)
			(keepout
				(tracks allowed)
				(vias not_allowed)
				(pads allowed)
				(copperpour not_allowed)
				(footprints allowed)
			)
			(placement
				(enabled no)
				(sheetname "")
			)
			(fill
				(thermal_gap 0.5)
				(thermal_bridge_width 0.5)
				(island_removal_mode 0)
			)
			(polygon
				(pts
					(xy 317.709042 -21.753576) (xy 319.182242 -21.753576) (xy 319.182242 -23.226776) (xy 317.709042 -23.226776)
				)
			)
		)
		(zone
			(layers "F.Cu" "B.Cu" "In1.Cu" "In2.Cu" "In3.Cu" "In4.Cu" "In5.Cu" "In6.Cu")
			(hatch none 0.5)
			(connect_pads
				(clearance 0)
			)
			(min_thickness 0.25)
			(keepout
				(tracks allowed)
				(vias not_allowed)
				(pads allowed)
				(copperpour not_allowed)
				(footprints allowed)
			)
			(placement
				(enabled no)
				(sheetname "")
			)
			(fill
				(thermal_gap 0.5)
				(thermal_bridge_width 0.5)
				(island_removal_mode 0)
			)
			(polygon
				(pts
					(xy 317.709042 -17.054576) (xy 319.182242 -17.054576) (xy 319.182242 -18.527776) (xy 317.709042 -18.527776)
				)
			)
		)
		(zone
			(layers "F.Cu" "B.Cu" "In1.Cu" "In2.Cu" "In3.Cu" "In4.Cu" "In5.Cu" "In6.Cu")
			(hatch none 0.5)
			(connect_pads
				(clearance 0)
			)
			(min_thickness 0.25)
			(keepout
				(tracks allowed)
				(vias not_allowed)
				(pads allowed)
				(copperpour not_allowed)
				(footprints allowed)
			)
			(placement
				(enabled no)
				(sheetname "")
			)
			(fill
				(thermal_gap 0.5)
				(thermal_bridge_width 0.5)
				(island_removal_mode 0)
			)
			(polygon
				(pts
					(xy 317.709042 -12.050776) (xy 319.182242 -12.050776) (xy 319.182242 -13.523976) (xy 317.709042 -13.523976)
				)
			)
		)
		(zone
			(layers "F.Cu" "B.Cu" "In1.Cu" "In2.Cu" "In3.Cu" "In4.Cu" "In5.Cu" "In6.Cu")
			(hatch none 0.5)
			(connect_pads
				(clearance 0)
			)
			(min_thickness 0.25)
			(keepout
				(tracks allowed)
				(vias not_allowed)
				(pads allowed)
				(copperpour not_allowed)
				(footprints allowed)
			)
			(placement
				(enabled no)
				(sheetname "")
			)
			(fill
				(thermal_gap 0.5)
				(thermal_bridge_width 0.5)
				(island_removal_mode 0)
			)
			(polygon
				(pts
					(xy 320.020442 -7.453376) (xy 321.493642 -7.453376) (xy 321.493642 -8.926576) (xy 320.020442 -8.926576)
				)
			)
		)
		(zone
			(layers "F.Cu" "B.Cu" "In1.Cu" "In2.Cu" "In3.Cu" "In4.Cu" "In5.Cu" "In6.Cu")
			(hatch none 0.5)
			(connect_pads
				(clearance 0)
			)
			(min_thickness 0.25)
			(keepout
				(tracks allowed)
				(vias not_allowed)
				(pads allowed)
				(copperpour not_allowed)
				(footprints allowed)
			)
			(placement
				(enabled no)
				(sheetname "")
			)
			(fill
				(thermal_gap 0.5)
				(thermal_bridge_width 0.5)
				(island_removal_mode 0)
			)
			(polygon
				(pts
					(xy 320.782442 -24.445976) (xy 322.458842 -24.445976) (xy 322.458842 -26.122376) (xy 320.782442 -26.122376)
				)
			)
		)
		(zone
			(layers "F.Cu" "B.Cu" "In1.Cu" "In2.Cu" "In3.Cu" "In4.Cu" "In5.Cu" "In6.Cu")
			(hatch none 0.5)
			(connect_pads
				(clearance 0)
			)
			(min_thickness 0.25)
			(keepout
				(tracks allowed)
				(vias not_allowed)
				(pads allowed)
				(copperpour not_allowed)
				(footprints allowed)
			)
			(placement
				(enabled no)
				(sheetname "")
			)
			(fill
				(thermal_gap 0.5)
				(thermal_bridge_width 0.5)
				(island_removal_mode 0)
			)
			(polygon
				(pts
					(xy 323.246242 -44.461176) (xy 324.922642 -44.461176) (xy 324.922642 -46.137576) (xy 323.246242 -46.137576)
				)
			)
		)
		(zone
			(layers "F.Cu" "B.Cu" "In1.Cu" "In2.Cu" "In3.Cu" "In4.Cu" "In5.Cu" "In6.Cu")
			(hatch none 0.5)
			(connect_pads
				(clearance 0)
			)
			(min_thickness 0.25)
			(keepout
				(tracks allowed)
				(vias not_allowed)
				(pads allowed)
				(copperpour not_allowed)
				(footprints allowed)
			)
			(placement
				(enabled no)
				(sheetname "")
			)
			(fill
				(thermal_gap 0.5)
				(thermal_bridge_width 0.5)
				(island_removal_mode 0)
			)
			(polygon
				(pts
					(xy 324.821042 -7.453376) (xy 326.294242 -7.453376) (xy 326.294242 -8.926576) (xy 324.821042 -8.926576)
				)
			)
		)
		(zone
			(layers "F.Cu" "B.Cu" "In1.Cu" "In2.Cu" "In3.Cu" "In4.Cu" "In5.Cu" "In6.Cu")
			(hatch none 0.5)
			(connect_pads
				(clearance 0)
			)
			(min_thickness 0.25)
			(keepout
				(tracks allowed)
				(vias not_allowed)
				(pads allowed)
				(copperpour not_allowed)
				(footprints allowed)
			)
			(placement
				(enabled no)
				(sheetname "")
			)
			(fill
				(thermal_gap 0.5)
				(thermal_bridge_width 0.5)
				(island_removal_mode 0)
			)
			(polygon
				(pts
					(xy 326.167242 -24.445976) (xy 327.843642 -24.445976) (xy 327.843642 -26.122376) (xy 326.167242 -26.122376)
				)
			)
		)
		(zone
			(layers "F.Cu" "B.Cu" "In1.Cu" "In2.Cu" "In3.Cu" "In4.Cu" "In5.Cu" "In6.Cu")
			(hatch none 0.5)
			(connect_pads
				(clearance 0)
			)
			(min_thickness 0.25)
			(keepout
				(tracks allowed)
				(vias not_allowed)
				(pads allowed)
				(copperpour not_allowed)
				(footprints allowed)
			)
			(placement
				(enabled no)
				(sheetname "")
			)
			(fill
				(thermal_gap 0.5)
				(thermal_bridge_width 0.5)
				(island_removal_mode 0)
			)
			(polygon
				(pts
					(xy 329.621642 -7.453376) (xy 331.094842 -7.453376) (xy 331.094842 -8.926576) (xy 329.621642 -8.926576)
				)
			)
		)
		(zone
			(layers "F.Cu" "B.Cu" "In1.Cu" "In2.Cu" "In3.Cu" "In4.Cu" "In5.Cu" "In6.Cu")
			(hatch none 0.5)
			(connect_pads
				(clearance 0)
			)
			(min_thickness 0.25)
			(keepout
				(tracks allowed)
				(vias not_allowed)
				(pads allowed)
				(copperpour not_allowed)
				(footprints allowed)
			)
			(placement
				(enabled no)
				(sheetname "")
			)
			(fill
				(thermal_gap 0.5)
				(thermal_bridge_width 0.5)
				(island_removal_mode 0)
			)
			(polygon
				(pts
					(xy 331.856842 -44.461176) (xy 333.533242 -44.461176) (xy 333.533242 -46.137576) (xy 331.856842 -46.137576)
				)
			)
		)
		(zone
			(layers "F.Cu" "B.Cu" "In1.Cu" "In2.Cu" "In3.Cu" "In4.Cu" "In5.Cu" "In6.Cu")
			(hatch none 0.5)
			(connect_pads
				(clearance 0)
			)
			(min_thickness 0.25)
			(keepout
				(tracks allowed)
				(vias not_allowed)
				(pads allowed)
				(copperpour not_allowed)
				(footprints allowed)
			)
			(placement
				(enabled no)
				(sheetname "")
			)
			(fill
				(thermal_gap 0.5)
				(thermal_bridge_width 0.5)
				(island_removal_mode 0)
			)
			(polygon
				(pts
					(xy 331.856842 -24.445976) (xy 333.533242 -24.445976) (xy 333.533242 -26.122376) (xy 331.856842 -26.122376)
				)
			)
		)
		(zone
			(layers "F.Cu" "B.Cu" "In1.Cu" "In2.Cu" "In3.Cu" "In4.Cu" "In5.Cu" "In6.Cu")
			(hatch none 0.5)
			(connect_pads
				(clearance 0)
			)
			(min_thickness 0.25)
			(keepout
				(tracks allowed)
				(vias not_allowed)
				(pads allowed)
				(copperpour not_allowed)
				(footprints allowed)
			)
			(placement
				(enabled no)
				(sheetname "")
			)
			(fill
				(thermal_gap 0.5)
				(thermal_bridge_width 0.5)
				(island_removal_mode 0)
			)
			(polygon
				(pts
					(xy 331.958442 -21.753576) (xy 333.431642 -21.753576) (xy 333.431642 -23.226776) (xy 331.958442 -23.226776)
				)
			)
		)
		(zone
			(layers "F.Cu" "B.Cu" "In1.Cu" "In2.Cu" "In3.Cu" "In4.Cu" "In5.Cu" "In6.Cu")
			(hatch none 0.5)
			(connect_pads
				(clearance 0)
			)
			(min_thickness 0.25)
			(keepout
				(tracks allowed)
				(vias not_allowed)
				(pads allowed)
				(copperpour not_allowed)
				(footprints allowed)
			)
			(placement
				(enabled no)
				(sheetname "")
			)
			(fill
				(thermal_gap 0.5)
				(thermal_bridge_width 0.5)
				(island_removal_mode 0)
			)
			(polygon
				(pts
					(xy 331.958442 -17.054576) (xy 333.431642 -17.054576) (xy 333.431642 -18.527776) (xy 331.958442 -18.527776)
				)
			)
		)
		(zone
			(layers "F.Cu" "B.Cu" "In1.Cu" "In2.Cu" "In3.Cu" "In4.Cu" "In5.Cu" "In6.Cu")
			(hatch none 0.5)
			(connect_pads
				(clearance 0)
			)
			(min_thickness 0.25)
			(keepout
				(tracks allowed)
				(vias not_allowed)
				(pads allowed)
				(copperpour not_allowed)
				(footprints allowed)
			)
			(placement
				(enabled no)
				(sheetname "")
			)
			(fill
				(thermal_gap 0.5)
				(thermal_bridge_width 0.5)
				(island_removal_mode 0)
			)
			(polygon
				(pts
					(xy 331.958442 -12.050776) (xy 333.431642 -12.050776) (xy 333.431642 -13.523976) (xy 331.958442 -13.523976)
				)
			)
		)
		(zone
			(layers "F.Cu" "B.Cu" "In1.Cu" "In2.Cu" "In3.Cu" "In4.Cu" "In5.Cu" "In6.Cu")
			(hatch none 0.5)
			(connect_pads
				(clearance 0)
			)
			(min_thickness 0.25)
			(keepout
				(tracks allowed)
				(vias not_allowed)
				(pads allowed)
				(copperpour not_allowed)
				(footprints allowed)
			)
			(placement
				(enabled no)
				(sheetname "")
			)
			(fill
				(thermal_gap 0.5)
				(thermal_bridge_width 0.5)
				(island_removal_mode 0)
			)
			(polygon
				(pts
					(xy 332.009242 -14.616176) (xy 333.380842 -14.616176) (xy 333.380842 -15.987776) (xy 332.009242 -15.987776)
				)
			)
		)
		(zone
			(layers "F.Cu" "B.Cu" "In1.Cu" "In2.Cu" "In3.Cu" "In4.Cu" "In5.Cu" "In6.Cu")
			(hatch none 0.5)
			(connect_pads
				(clearance 0)
			)
			(min_thickness 0.25)
			(keepout
				(tracks allowed)
				(vias not_allowed)
				(pads allowed)
				(copperpour not_allowed)
				(footprints allowed)
			)
			(placement
				(enabled no)
				(sheetname "")
			)
			(fill
				(thermal_gap 0.5)
				(thermal_bridge_width 0.5)
				(island_removal_mode 0)
			)
			(polygon
				(pts
					(xy 333.533242 -35.240976) (xy 333.533242 -36.129976) (xy 331.856842 -36.129976) (xy 331.856842 -34.453576)
					(xy 333.533242 -34.453576)
				)
			)
		)
	)
	(footprint ""
		(layer "F.Cu")
		(at 104.8512 -2.9464 90)
		(property "Reference" "C19"
			(at -2.3876 -4.841748 90)
			(unlocked yes)
			(layer "F.SilkS")
			(effects
				(font
					(size 0.7874 0.5842)
					(thickness 0.1524)
				)
				(justify left)
			)
		)
		(property "Value" ""
			(at 0 0 90)
			(layer "F.Fab")
			(effects
				(font
					(size 1.27 1.27)
				)
			)
		)
		(duplicate_pad_numbers_are_jumpers no)
		(fp_line
			(start 0.7874 -0.4064)
			(end 0.7874 0.4064)
			(stroke
				(width 0.1524)
				(type default)
			)
			(layer "F.SilkS")
		)
		(fp_line
			(start -0.7874 -0.4064)
			(end 0.7874 -0.4064)
			(stroke
				(width 0.1524)
				(type default)
			)
			(layer "F.SilkS")
		)
		(fp_line
			(start 0 0.381)
			(end 0 -0.381)
			(stroke
				(width 0.1524)
				(type default)
			)
			(layer "F.SilkS")
		)
		(fp_line
			(start 0.7874 0.4064)
			(end -0.7874 0.4064)
			(stroke
				(width 0.1524)
				(type default)
			)
			(layer "F.SilkS")
		)
		(fp_line
			(start -0.7874 0.4064)
			(end -0.7874 -0.4064)
			(stroke
				(width 0.1524)
				(type default)
			)
			(layer "F.SilkS")
		)
		(fp_poly
			(pts
				(xy -0.5334 0.254) (xy -0.635 0.254) (xy -0.635 0.2286) (xy -0.635 -0.254) (xy -0.5334 -0.254) (xy -0.5334 -0.2794)
				(xy 0.5334 -0.2794) (xy 0.5334 -0.254) (xy 0.635 -0.254) (xy 0.635 0.254) (xy 0.5334 0.254) (xy 0.5334 0.2794)
				(xy -0.508 0.2794) (xy -0.5334 0.2794)
			)
			(stroke
				(width 0)
				(type default)
			)
			(fill no)
			(layer "F.CrtYd")
		)
		(pad "1" smd rect
			(at 0.40005 0 90)
			(size 0.4572 0.508)
			(layers "F.Cu" "F.Mask" "F.Paste")
			(net "P3V3_10G_2_VCCT")
		)
		(pad "2" smd rect
			(at -0.40005 0 90)
			(size 0.4572 0.508)
			(layers "F.Cu" "F.Mask" "F.Paste")
			(net "GND")
		)
	)
	(footprint ""
		(layer "F.Cu")
		(at 111.694976 -49.795176)
		(property "Reference" "J15"
			(at -19.198082 3.683 90)
			(unlocked yes)
			(layer "F.SilkS")
			(effects
				(font
					(size 0.7874 0.5842)
					(thickness 0.1524)
				)
				(justify left)
			)
		)
		(property "Value" ""
			(at 0 0 0)
			(layer "F.Fab")
			(effects
				(font
					(size 1.27 1.27)
				)
			)
		)
		(duplicate_pad_numbers_are_jumpers no)
		(fp_line
			(start -18.2499 -9.99998)
			(end 3.999992 -9.99998)
			(stroke
				(width 0.1524)
				(type default)
			)
			(layer "F.SilkS")
		)
		(fp_line
			(start -18.2499 45.299884)
			(end -18.2499 -9.99998)
			(stroke
				(width 0.1524)
				(type default)
			)
			(layer "F.SilkS")
		)
		(fp_line
			(start -15.249906 -6.999986)
			(end 0.999998 -6.999986)
			(stroke
				(width 0.1524)
				(type default)
			)
			(layer "F.SilkS")
		)
		(fp_line
			(start -15.249906 42.29989)
			(end -15.249906 -6.999986)
			(stroke
				(width 0.1524)
				(type default)
			)
			(layer "F.SilkS")
		)
		(fp_line
			(start -13.24991 26.800048)
			(end -13.24991 41.299892)
			(stroke
				(width 0.1524)
				(type default)
			)
			(layer "F.SilkS")
		)
		(fp_line
			(start -13.24991 41.299892)
			(end -12.6746 41.299892)
			(stroke
				(width 0.1524)
				(type default)
			)
			(layer "F.SilkS")
		)
		(fp_line
			(start -12.319 42.29989)
			(end -15.249906 42.29989)
			(stroke
				(width 0.1524)
				(type default)
			)
			(layer "F.SilkS")
		)
		(fp_line
			(start -11.176 41.299892)
			(end -10.919968 41.299892)
			(stroke
				(width 0.1524)
				(type default)
			)
			(layer "F.SilkS")
		)
		(fp_line
			(start -10.919968 41.299892)
			(end -10.919968 42.29989)
			(stroke
				(width 0.1524)
				(type default)
			)
			(layer "F.SilkS")
		)
		(fp_line
			(start -10.919968 42.29989)
			(end -11.5316 42.29989)
			(stroke
				(width 0.1524)
				(type default)
			)
			(layer "F.SilkS")
		)
		(fp_line
			(start -4.430776 45.299884)
			(end -18.2499 45.299884)
			(stroke
				(width 0.1524)
				(type default)
			)
			(layer "F.SilkS")
		)
		(fp_line
			(start -3.32994 41.299892)
			(end -3.0734 41.299892)
			(stroke
				(width 0.1524)
				(type default)
			)
			(layer "F.SilkS")
		)
		(fp_line
			(start -3.32994 42.29989)
			(end -3.32994 41.299892)
			(stroke
				(width 0.1524)
				(type default)
			)
			(layer "F.SilkS")
		)
		(fp_line
			(start -2.7178 42.29989)
			(end -3.32994 42.29989)
			(stroke
				(width 0.1524)
				(type default)
			)
			(layer "F.SilkS")
		)
		(fp_line
			(start -1.5748 41.299892)
			(end -0.999998 41.299892)
			(stroke
				(width 0.1524)
				(type default)
			)
			(layer "F.SilkS")
		)
		(fp_line
			(start -0.999998 26.800048)
			(end -13.24991 26.800048)
			(stroke
				(width 0.1524)
				(type default)
			)
			(layer "F.SilkS")
		)
		(fp_line
			(start -0.999998 41.299892)
			(end -0.999998 26.800048)
			(stroke
				(width 0.1524)
				(type default)
			)
			(layer "F.SilkS")
		)
		(fp_line
			(start 0.999998 -6.999986)
			(end 0.999998 42.29989)
			(stroke
				(width 0.1524)
				(type default)
			)
			(layer "F.SilkS")
		)
		(fp_line
			(start 0.999998 42.29989)
			(end -1.9558 42.29989)
			(stroke
				(width 0.1524)
				(type default)
			)
			(layer "F.SilkS")
		)
		(fp_line
			(start 3.999992 -9.99998)
			(end 3.999992 45.299884)
			(stroke
				(width 0.1524)
				(type default)
			)
			(layer "F.SilkS")
		)
		(fp_line
			(start 3.999992 45.299884)
			(end 2.935224 45.299884)
			(stroke
				(width 0.1524)
				(type default)
			)
			(layer "F.SilkS")
		)
		(fp_poly
			(pts
				(xy 1.9812 4.5593) (xy 5.4102 5.7023) (xy 5.4102 3.4163)
			)
			(stroke
				(width 0)
				(type default)
			)
			(fill yes)
			(layer "F.SilkS")
		)
		(fp_line
			(start -18.2499 -9.99998)
			(end 3.999992 -9.99998)
			(stroke
				(width 0.1524)
				(type default)
			)
			(layer "B.SilkS")
		)
		(fp_line
			(start -18.2499 45.299884)
			(end -18.2499 -9.99998)
			(stroke
				(width 0.1524)
				(type default)
			)
			(layer "B.SilkS")
		)
		(fp_line
			(start 3.999992 -9.99998)
			(end 3.999992 36.714176)
			(stroke
				(width 0.1524)
				(type default)
			)
			(layer "B.SilkS")
		)
		(fp_line
			(start 3.999992 39.609776)
			(end 3.999992 42.200576)
			(stroke
				(width 0.1524)
				(type default)
			)
			(layer "B.SilkS")
		)
		(fp_line
			(start 3.999992 43.597576)
			(end 3.999992 45.299884)
			(stroke
				(width 0.1524)
				(type default)
			)
			(layer "B.SilkS")
		)
		(fp_line
			(start 3.999992 45.299884)
			(end -18.2499 45.299884)
			(stroke
				(width 0.1524)
				(type default)
			)
			(layer "B.SilkS")
		)
		(fp_poly
			(pts
				(xy -15.0876 8.6614) (xy -13.4112 8.6614) (xy -13.4112 10.3378) (xy -15.0876 10.3378)
			)
			(stroke
				(width 0)
				(type default)
			)
			(fill no)
			(layer "B.CrtYd")
		)
		(fp_poly
			(pts
				(xy -15.0876 18.669) (xy -13.4112 18.669) (xy -13.4112 20.3454) (xy -15.0876 20.3454)
			)
			(stroke
				(width 0)
				(type default)
			)
			(fill no)
			(layer "B.CrtYd")
		)
		(fp_poly
			(pts
				(xy -15.0876 28.6512) (xy -13.4112 28.6512) (xy -13.4112 30.3276) (xy -15.0876 30.3276)
			)
			(stroke
				(width 0)
				(type default)
			)
			(fill no)
			(layer "B.CrtYd")
		)
		(fp_poly
			(pts
				(xy -15.0876 38.6588) (xy -13.4112 38.6588) (xy -13.4112 40.3352) (xy -15.0876 40.3352)
			)
			(stroke
				(width 0)
				(type default)
			)
			(fill no)
			(layer "B.CrtYd")
		)
		(fp_poly
			(pts
				(xy -14.986 26.5684) (xy -13.5128 26.5684) (xy -13.5128 28.0416) (xy -14.986 28.0416)
			)
			(stroke
				(width 0)
				(type default)
			)
			(fill no)
			(layer "B.CrtYd")
		)
		(fp_poly
			(pts
				(xy -14.986 31.2674) (xy -13.5128 31.2674) (xy -13.5128 32.7406) (xy -14.986 32.7406)
			)
			(stroke
				(width 0)
				(type default)
			)
			(fill no)
			(layer "B.CrtYd")
		)
		(fp_poly
			(pts
				(xy -14.986 36.2712) (xy -13.5128 36.2712) (xy -13.5128 37.7444) (xy -14.986 37.7444)
			)
			(stroke
				(width 0)
				(type default)
			)
			(fill no)
			(layer "B.CrtYd")
		)
		(fp_poly
			(pts
				(xy -12.6746 40.8686) (xy -11.2014 40.8686) (xy -11.2014 42.3418) (xy -12.6746 42.3418)
			)
			(stroke
				(width 0)
				(type default)
			)
			(fill no)
			(layer "B.CrtYd")
		)
		(fp_poly
			(pts
				(xy -11.9126 23.6728) (xy -10.2362 23.6728) (xy -10.2362 25.3492) (xy -11.9126 25.3492)
			)
			(stroke
				(width 0)
				(type default)
			)
			(fill no)
			(layer "B.CrtYd")
		)
		(fp_poly
			(pts
				(xy -9.4488 3.6576) (xy -7.7724 3.6576) (xy -7.7724 5.334) (xy -9.4488 5.334)
			)
			(stroke
				(width 0)
				(type default)
			)
			(fill no)
			(layer "B.CrtYd")
		)
		(fp_poly
			(pts
				(xy -7.874 40.8686) (xy -6.4008 40.8686) (xy -6.4008 42.3418) (xy -7.874 42.3418)
			)
			(stroke
				(width 0)
				(type default)
			)
			(fill no)
			(layer "B.CrtYd")
		)
		(fp_poly
			(pts
				(xy -6.5278 23.6728) (xy -4.8514 23.6728) (xy -4.8514 25.3492) (xy -6.5278 25.3492)
			)
			(stroke
				(width 0)
				(type default)
			)
			(fill no)
			(layer "B.CrtYd")
		)
		(fp_poly
			(pts
				(xy -3.0734 40.8686) (xy -1.6002 40.8686) (xy -1.6002 42.3418) (xy -3.0734 42.3418)
			)
			(stroke
				(width 0)
				(type default)
			)
			(fill no)
			(layer "B.CrtYd")
		)
		(fp_poly
			(pts
				(xy -0.8382 3.6576) (xy 0.8382 3.6576) (xy 0.8382 5.334) (xy -0.8382 5.334)
			)
			(stroke
				(width 0)
				(type default)
			)
			(fill no)
			(layer "B.CrtYd")
		)
		(fp_poly
			(pts
				(xy -0.8382 23.6728) (xy 0.8382 23.6728) (xy 0.8382 25.3492) (xy -0.8382 25.3492)
			)
			(stroke
				(width 0)
				(type default)
			)
			(fill no)
			(layer "B.CrtYd")
		)
		(fp_poly
			(pts
				(xy -0.7366 26.5684) (xy 0.7366 26.5684) (xy 0.7366 28.0416) (xy -0.7366 28.0416)
			)
			(stroke
				(width 0)
				(type default)
			)
			(fill no)
			(layer "B.CrtYd")
		)
		(fp_poly
			(pts
				(xy -0.7366 31.2674) (xy 0.7366 31.2674) (xy 0.7366 32.7406) (xy -0.7366 32.7406)
			)
			(stroke
				(width 0)
				(type default)
			)
			(fill no)
			(layer "B.CrtYd")
		)
		(fp_poly
			(pts
				(xy -0.7366 36.2712) (xy 0.7366 36.2712) (xy 0.7366 37.7444) (xy -0.7366 37.7444)
			)
			(stroke
				(width 0)
				(type default)
			)
			(fill no)
			(layer "B.CrtYd")
		)
		(fp_poly
			(pts
				(xy -0.6858 33.8074) (xy 0.6858 33.8074) (xy 0.6858 35.179) (xy -0.6858 35.179)
			)
			(stroke
				(width 0)
				(type default)
			)
			(fill no)
			(layer "B.CrtYd")
		)
		(fp_poly
			(pts
				(xy 0.8382 14.5542) (xy 0.8382 13.6652) (xy 0 13.6652) (xy -0.8382 13.6652) (xy -0.8382 15.3416)
				(xy 0.8382 15.3416)
			)
			(stroke
				(width 0)
				(type default)
			)
			(fill no)
			(layer "B.CrtYd")
		)
		(fp_rect
			(start -8.130032 42.29989)
			(end -6.130036 41.299892)
			(stroke
				(width 0)
				(type default)
			)
			(fill no)
			(layer "F.CrtYd")
		)
		(fp_poly
			(pts
				(xy 0.999998 -6.999986) (xy 0.999998 42.29989) (xy -3.32994 42.29989) (xy -3.32994 41.299892) (xy -0.999998 41.299892)
				(xy -0.999998 26.800048) (xy -13.24991 26.800048) (xy -13.24991 41.299892) (xy -10.919968 41.299892)
				(xy -10.919968 42.29989) (xy -15.249906 42.29989) (xy -15.249906 -6.999986)
			)
			(stroke
				(width 0)
				(type default)
			)
			(fill no)
			(layer "F.CrtYd")
		)
		(fp_line
			(start -15.249906 -6.999986)
			(end 0.999998 -6.999986)
			(stroke
				(width 0.1)
				(type default)
			)
			(layer "F.Fab")
		)
		(fp_line
			(start -15.249906 0)
			(end 0.999998 0)
			(stroke
				(width 0.1)
				(type default)
			)
			(layer "F.Fab")
		)
		(fp_line
			(start -15.249906 41.999916)
			(end -15.249906 -6.999986)
			(stroke
				(width 0.1)
				(type default)
			)
			(layer "F.Fab")
		)
		(fp_line
			(start -15.249906 42.29989)
			(end -15.249906 0)
			(stroke
				(width 0.1)
				(type default)
			)
			(layer "F.Fab")
		)
		(fp_line
			(start -13.24991 26.800048)
			(end -13.24991 41.299892)
			(stroke
				(width 0.1)
				(type default)
			)
			(layer "F.Fab")
		)
		(fp_line
			(start -13.24991 41.299892)
			(end -10.919968 41.299892)
			(stroke
				(width 0.1)
				(type default)
			)
			(layer "F.Fab")
		)
		(fp_line
			(start -10.919968 41.299892)
			(end -10.919968 42.29989)
			(stroke
				(width 0.1)
				(type default)
			)
			(layer "F.Fab")
		)
		(fp_line
			(start -10.919968 42.29989)
			(end -15.249906 42.29989)
			(stroke
				(width 0.1)
				(type default)
			)
			(layer "F.Fab")
		)
		(fp_line
			(start -3.32994 41.299892)
			(end -0.999998 41.299892)
			(stroke
				(width 0.1)
				(type default)
			)
			(layer "F.Fab")
		)
		(fp_line
			(start -3.32994 42.29989)
			(end -3.32994 41.299892)
			(stroke
				(width 0.1)
				(type default)
			)
			(layer "F.Fab")
		)
		(fp_line
			(start -0.999998 26.800048)
			(end -13.24991 26.800048)
			(stroke
				(width 0.1)
				(type default)
			)
			(layer "F.Fab")
		)
		(fp_line
			(start -0.999998 41.299892)
			(end -0.999998 26.800048)
			(stroke
				(width 0.1)
				(type default)
			)
			(layer "F.Fab")
		)
		(fp_line
			(start 0.999998 -6.999986)
			(end 0.999998 41.999916)
			(stroke
				(width 0.1)
				(type default)
			)
			(layer "F.Fab")
		)
		(fp_line
			(start 0.999998 0)
			(end 0.999998 42.29989)
			(stroke
				(width 0.1)
				(type default)
			)
			(layer "F.Fab")
		)
		(fp_line
			(start 0.999998 41.999916)
			(end -15.249906 41.999916)
			(stroke
				(width 0.1)
				(type default)
			)
			(layer "F.Fab")
		)
		(fp_line
			(start 0.999998 42.29989)
			(end -3.32994 42.29989)
			(stroke
				(width 0.1)
				(type default)
			)
			(layer "F.Fab")
		)
		(fp_text user "PRESS-FIT"
			(at -16.70939 23.449788 90)
			(unlocked yes)
			(layer "F.SilkS")
			(effects
				(font
					(size 1.6002 1.1938)
					(thickness 0.1524)
				)
				(justify left)
			)
		)
		(fp_text user "PRESS-FIT"
			(at -17.133062 22.704552 270)
			(unlocked yes)
			(layer "B.SilkS")
			(effects
				(font
					(size 1.6002 1.1938)
					(thickness 0.1524)
				)
				(justify left mirror)
			)
		)
		(pad "1" thru_hole circle
			(at 0 4.500118)
			(size 1.5494 1.5494)
			(drill 1.0414)
			(layers "*.Cu" "*.Mask")
			(remove_unused_layers no)
			(net "GND")
			(clearance 0)
		)
		(pad "2" thru_hole circle
			(at -8.58012 4.500118)
			(size 1.5494 1.5494)
			(drill 1.0414)
			(layers "*.Cu" "*.Mask")
			(remove_unused_layers no)
			(net "GND")
			(clearance 0)
		)
		(pad "3" thru_hole circle
			(at 0 14.500098)
			(size 1.5494 1.5494)
			(drill 1.0414)
			(layers "*.Cu" "*.Mask")
			(remove_unused_layers no)
			(net "GND")
			(clearance 0)
		)
		(pad "4" thru_hole circle
			(at -14.249908 9.500108)
			(size 1.5494 1.5494)
			(drill 1.0414)
			(layers "*.Cu" "*.Mask")
			(remove_unused_layers no)
			(net "GND")
			(clearance 0)
		)
		(pad "5" thru_hole circle
			(at -14.249908 19.500088)
			(size 1.5494 1.5494)
			(drill 1.0414)
			(layers "*.Cu" "*.Mask")
			(remove_unused_layers no)
			(net "GND")
			(clearance 0)
		)
		(pad "6" thru_hole circle
			(at 0 24.500078)
			(size 1.5494 1.5494)
			(drill 1.0414)
			(layers "*.Cu" "*.Mask")
			(remove_unused_layers no)
			(net "GND")
			(clearance 0)
		)
		(pad "7" thru_hole circle
			(at -5.679948 24.500078)
			(size 1.5494 1.5494)
			(drill 1.0414)
			(layers "*.Cu" "*.Mask")
			(remove_unused_layers no)
			(net "GND")
			(clearance 0)
		)
		(pad "8" thru_hole circle
			(at -11.079988 24.500078)
			(size 1.5494 1.5494)
			(drill 1.0414)
			(layers "*.Cu" "*.Mask")
			(remove_unused_layers no)
			(net "GND")
			(clearance 0)
		)
		(pad "9" thru_hole circle
			(at -14.249908 29.500068)
			(size 1.5494 1.5494)
			(drill 1.0414)
			(layers "*.Cu" "*.Mask")
			(remove_unused_layers no)
			(net "GND")
			(clearance 0)
		)
		(pad "10" thru_hole circle
			(at -14.249908 39.500048)
			(size 1.5494 1.5494)
			(drill 1.0414)
			(layers "*.Cu" "*.Mask")
			(remove_unused_layers no)
			(net "GND")
			(clearance 0)
		)
		(pad "11" thru_hole circle
			(at 0 27.29992)
			(size 1.3462 1.3462)
			(drill 0.9398)
			(layers "*.Cu" "*.Mask")
			(remove_unused_layers no)
			(net "GND")
			(clearance 0.0508)
			(thermal_gap 0.0508)
		)
		(pad "12" thru_hole circle
			(at 0 31.999936)
			(size 1.3462 1.3462)
			(drill 0.9398)
			(layers "*.Cu" "*.Mask")
			(remove_unused_layers no)
			(net "GND")
			(clearance 0.0508)
			(thermal_gap 0.0508)
		)
		(pad "13" thru_hole circle
			(at 0 36.999926)
			(size 1.3462 1.3462)
			(drill 0.9398)
			(layers "*.Cu" "*.Mask")
			(remove_unused_layers no)
			(net "GND")
			(clearance 0.0508)
			(thermal_gap 0.0508)
		)
		(pad "14" thru_hole circle
			(at -2.329942 41.60012)
			(size 1.3462 1.3462)
			(drill 0.9398)
			(layers "*.Cu" "*.Mask")
			(remove_unused_layers no)
			(net "GND")
			(clearance 0.0508)
			(thermal_gap 0.0508)
		)
		(pad "15" thru_hole circle
			(at -7.130034 41.60012)
			(size 1.3462 1.3462)
			(drill 0.9398)
			(layers "*.Cu" "*.Mask")
			(remove_unused_layers no)
			(net "GND")
			(clearance 0.0508)
			(thermal_gap 0.0508)
		)
		(pad "16" thru_hole circle
			(at -11.929872 41.60012)
			(size 1.3462 1.3462)
			(drill 0.9398)
			(layers "*.Cu" "*.Mask")
			(remove_unused_layers no)
			(net "GND")
			(clearance 0.0508)
			(thermal_gap 0.0508)
		)
		(pad "17" thru_hole circle
			(at -14.249908 27.29992)
			(size 1.3462 1.3462)
			(drill 0.9398)
			(layers "*.Cu" "*.Mask")
			(remove_unused_layers no)
			(net "GND")
			(clearance 0.0508)
			(thermal_gap 0.0508)
		)
		(pad "18" thru_hole circle
			(at -14.249908 31.999936)
			(size 1.3462 1.3462)
			(drill 0.9398)
			(layers "*.Cu" "*.Mask")
			(remove_unused_layers no)
			(net "GND")
			(clearance 0.0508)
			(thermal_gap 0.0508)
		)
		(pad "19" thru_hole circle
			(at -14.249908 36.999926)
			(size 1.3462 1.3462)
			(drill 0.9398)
			(layers "*.Cu" "*.Mask")
			(remove_unused_layers no)
			(net "GND")
			(clearance 0.0508)
			(thermal_gap 0.0508)
		)
		(pad "20" thru_hole circle
			(at 0 34.500058)
			(size 1.2446 1.2446)
			(drill 0.8382)
			(layers "*.Cu" "*.Mask")
			(remove_unused_layers no)
			(net "GND")
			(clearance 0.0508)
			(thermal_gap 0.0508)
		)
		(zone
			(layer "F.Cu")
			(hatch none 0.5)
			(connect_pads
				(clearance 0)
			)
			(min_thickness 0.25)
			(keepout
				(tracks not_allowed)
				(vias allowed)
				(pads allowed)
				(copperpour not_allowed)
				(footprints allowed)
			)
			(placement
				(enabled no)
				(sheetname "")
			)
			(fill
				(thermal_gap 0.5)
				(thermal_bridge_width 0.5)
				(island_removal_mode 0)
			)
			(polygon
				(pts
					(xy 103.564944 -7.495286) (xy 105.56494 -7.495286) (xy 105.56494 -8.495284) (xy 103.564944 -8.495284)
				)
			)
		)
		(zone
			(layer "F.Cu")
			(hatch none 0.5)
			(connect_pads
				(clearance 0)
			)
			(min_thickness 0.25)
			(keepout
				(tracks not_allowed)
				(vias allowed)
				(pads allowed)
				(copperpour not_allowed)
				(footprints allowed)
			)
			(placement
				(enabled no)
				(sheetname "")
			)
			(fill
				(thermal_gap 0.5)
				(thermal_bridge_width 0.5)
				(island_removal_mode 0)
			)
			(polygon
				(pts
					(xy 112.694974 -49.795176) (xy 112.694974 -7.495286) (xy 108.365036 -7.495286) (xy 108.365036 -8.495284)
					(xy 110.694978 -8.495284) (xy 110.694978 -22.995128) (xy 98.445066 -22.995128) (xy 98.445066 -8.495284)
					(xy 100.775008 -8.495284) (xy 100.775008 -7.495286) (xy 96.44507 -7.495286) (xy 96.45142 -49.795176)
				)
			)
		)
		(zone
			(layers "F.Cu" "B.Cu" "In1.Cu" "In2.Cu" "In3.Cu" "In4.Cu" "In5.Cu" "In6.Cu")
			(hatch none 0.5)
			(connect_pads
				(clearance 0)
			)
			(min_thickness 0.25)
			(keepout
				(tracks allowed)
				(vias not_allowed)
				(pads allowed)
				(copperpour not_allowed)
				(footprints allowed)
			)
			(placement
				(enabled no)
				(sheetname "")
			)
			(fill
				(thermal_gap 0.5)
				(thermal_bridge_width 0.5)
				(island_removal_mode 0)
			)
			(polygon
				(pts
					(xy 96.607376 -39.457376) (xy 98.283776 -39.457376) (xy 98.283776 -41.133776) (xy 96.607376 -41.133776)
				)
			)
		)
		(zone
			(layers "F.Cu" "B.Cu" "In1.Cu" "In2.Cu" "In3.Cu" "In4.Cu" "In5.Cu" "In6.Cu")
			(hatch none 0.5)
			(connect_pads
				(clearance 0)
			)
			(min_thickness 0.25)
			(keepout
				(tracks allowed)
				(vias not_allowed)
				(pads allowed)
				(copperpour not_allowed)
				(footprints allowed)
			)
			(placement
				(enabled no)
				(sheetname "")
			)
			(fill
				(thermal_gap 0.5)
				(thermal_bridge_width 0.5)
				(island_removal_mode 0)
			)
			(polygon
				(pts
					(xy 96.607376 -29.449776) (xy 98.283776 -29.449776) (xy 98.283776 -31.126176) (xy 96.607376 -31.126176)
				)
			)
		)
		(zone
			(layers "F.Cu" "B.Cu" "In1.Cu" "In2.Cu" "In3.Cu" "In4.Cu" "In5.Cu" "In6.Cu")
			(hatch none 0.5)
			(connect_pads
				(clearance 0)
			)
			(min_thickness 0.25)
			(keepout
				(tracks allowed)
				(vias not_allowed)
				(pads allowed)
				(copperpour not_allowed)
				(footprints allowed)
			)
			(placement
				(enabled no)
				(sheetname "")
			)
			(fill
				(thermal_gap 0.5)
				(thermal_bridge_width 0.5)
				(island_removal_mode 0)
			)
			(polygon
				(pts
					(xy 96.607376 -19.467576) (xy 98.283776 -19.467576) (xy 98.283776 -21.143976) (xy 96.607376 -21.143976)
				)
			)
		)
		(zone
			(layers "F.Cu" "B.Cu" "In1.Cu" "In2.Cu" "In3.Cu" "In4.Cu" "In5.Cu" "In6.Cu")
			(hatch none 0.5)
			(connect_pads
				(clearance 0)
			)
			(min_thickness 0.25)
			(keepout
				(tracks allowed)
				(vias not_allowed)
				(pads allowed)
				(copperpour not_allowed)
				(footprints allowed)
			)
			(placement
				(enabled no)
				(sheetname "")
			)
			(fill
				(thermal_gap 0.5)
				(thermal_bridge_width 0.5)
				(island_removal_mode 0)
			)
			(polygon
				(pts
					(xy 96.607376 -9.459976) (xy 98.283776 -9.459976) (xy 98.283776 -11.136376) (xy 96.607376 -11.136376)
				)
			)
		)
		(zone
			(layers "F.Cu" "B.Cu" "In1.Cu" "In2.Cu" "In3.Cu" "In4.Cu" "In5.Cu" "In6.Cu")
			(hatch none 0.5)
			(connect_pads
				(clearance 0)
			)
			(min_thickness 0.25)
			(keepout
				(tracks allowed)
				(vias not_allowed)
				(pads allowed)
				(copperpour not_allowed)
				(footprints allowed)
			)
			(placement
				(enabled no)
				(sheetname "")
			)
			(fill
				(thermal_gap 0.5)
				(thermal_bridge_width 0.5)
				(island_removal_mode 0)
			)
			(polygon
				(pts
					(xy 96.708976 -21.753576) (xy 98.182176 -21.753576) (xy 98.182176 -23.226776) (xy 96.708976 -23.226776)
				)
			)
		)
		(zone
			(layers "F.Cu" "B.Cu" "In1.Cu" "In2.Cu" "In3.Cu" "In4.Cu" "In5.Cu" "In6.Cu")
			(hatch none 0.5)
			(connect_pads
				(clearance 0)
			)
			(min_thickness 0.25)
			(keepout
				(tracks allowed)
				(vias not_allowed)
				(pads allowed)
				(copperpour not_allowed)
				(footprints allowed)
			)
			(placement
				(enabled no)
				(sheetname "")
			)
			(fill
				(thermal_gap 0.5)
				(thermal_bridge_width 0.5)
				(island_removal_mode 0)
			)
			(polygon
				(pts
					(xy 96.708976 -17.054576) (xy 98.182176 -17.054576) (xy 98.182176 -18.527776) (xy 96.708976 -18.527776)
				)
			)
		)
		(zone
			(layers "F.Cu" "B.Cu" "In1.Cu" "In2.Cu" "In3.Cu" "In4.Cu" "In5.Cu" "In6.Cu")
			(hatch none 0.5)
			(connect_pads
				(clearance 0)
			)
			(min_thickness 0.25)
			(keepout
				(tracks allowed)
				(vias not_allowed)
				(pads allowed)
				(copperpour not_allowed)
				(footprints allowed)
			)
			(placement
				(enabled no)
				(sheetname "")
			)
			(fill
				(thermal_gap 0.5)
				(thermal_bridge_width 0.5)
				(island_removal_mode 0)
			)
			(polygon
				(pts
					(xy 96.708976 -12.050776) (xy 98.182176 -12.050776) (xy 98.182176 -13.523976) (xy 96.708976 -13.523976)
				)
			)
		)
		(zone
			(layers "F.Cu" "B.Cu" "In1.Cu" "In2.Cu" "In3.Cu" "In4.Cu" "In5.Cu" "In6.Cu")
			(hatch none 0.5)
			(connect_pads
				(clearance 0)
			)
			(min_thickness 0.25)
			(keepout
				(tracks allowed)
				(vias not_allowed)
				(pads allowed)
				(copperpour not_allowed)
				(footprints allowed)
			)
			(placement
				(enabled no)
				(sheetname "")
			)
			(fill
				(thermal_gap 0.5)
				(thermal_bridge_width 0.5)
				(island_removal_mode 0)
			)
			(polygon
				(pts
					(xy 99.020376 -7.453376) (xy 100.493576 -7.453376) (xy 100.493576 -8.926576) (xy 99.020376 -8.926576)
				)
			)
		)
		(zone
			(layers "F.Cu" "B.Cu" "In1.Cu" "In2.Cu" "In3.Cu" "In4.Cu" "In5.Cu" "In6.Cu")
			(hatch none 0.5)
			(connect_pads
				(clearance 0)
			)
			(min_thickness 0.25)
			(keepout
				(tracks allowed)
				(vias not_allowed)
				(pads allowed)
				(copperpour not_allowed)
				(footprints allowed)
			)
			(placement
				(enabled no)
				(sheetname "")
			)
			(fill
				(thermal_gap 0.5)
				(thermal_bridge_width 0.5)
				(island_removal_mode 0)
			)
			(polygon
				(pts
					(xy 99.782376 -24.445976) (xy 101.458776 -24.445976) (xy 101.458776 -26.122376) (xy 99.782376 -26.122376)
				)
			)
		)
		(zone
			(layers "F.Cu" "B.Cu" "In1.Cu" "In2.Cu" "In3.Cu" "In4.Cu" "In5.Cu" "In6.Cu")
			(hatch none 0.5)
			(connect_pads
				(clearance 0)
			)
			(min_thickness 0.25)
			(keepout
				(tracks allowed)
				(vias not_allowed)
				(pads allowed)
				(copperpour not_allowed)
				(footprints allowed)
			)
			(placement
				(enabled no)
				(sheetname "")
			)
			(fill
				(thermal_gap 0.5)
				(thermal_bridge_width 0.5)
				(island_removal_mode 0)
			)
			(polygon
				(pts
					(xy 102.246176 -44.461176) (xy 103.922576 -44.461176) (xy 103.922576 -46.137576) (xy 102.246176 -46.137576)
				)
			)
		)
		(zone
			(layers "F.Cu" "B.Cu" "In1.Cu" "In2.Cu" "In3.Cu" "In4.Cu" "In5.Cu" "In6.Cu")
			(hatch none 0.5)
			(connect_pads
				(clearance 0)
			)
			(min_thickness 0.25)
			(keepout
				(tracks allowed)
				(vias not_allowed)
				(pads allowed)
				(copperpour not_allowed)
				(footprints allowed)
			)
			(placement
				(enabled no)
				(sheetname "")
			)
			(fill
				(thermal_gap 0.5)
				(thermal_bridge_width 0.5)
				(island_removal_mode 0)
			)
			(polygon
				(pts
					(xy 103.820976 -7.453376) (xy 105.294176 -7.453376) (xy 105.294176 -8.926576) (xy 103.820976 -8.926576)
				)
			)
		)
		(zone
			(layers "F.Cu" "B.Cu" "In1.Cu" "In2.Cu" "In3.Cu" "In4.Cu" "In5.Cu" "In6.Cu")
			(hatch none 0.5)
			(connect_pads
				(clearance 0)
			)
			(min_thickness 0.25)
			(keepout
				(tracks allowed)
				(vias not_allowed)
				(pads allowed)
				(copperpour not_allowed)
				(footprints allowed)
			)
			(placement
				(enabled no)
				(sheetname "")
			)
			(fill
				(thermal_gap 0.5)
				(thermal_bridge_width 0.5)
				(island_removal_mode 0)
			)
			(polygon
				(pts
					(xy 105.167176 -24.445976) (xy 106.843576 -24.445976) (xy 106.843576 -26.122376) (xy 105.167176 -26.122376)
				)
			)
		)
		(zone
			(layers "F.Cu" "B.Cu" "In1.Cu" "In2.Cu" "In3.Cu" "In4.Cu" "In5.Cu" "In6.Cu")
			(hatch none 0.5)
			(connect_pads
				(clearance 0)
			)
			(min_thickness 0.25)
			(keepout
				(tracks allowed)
				(vias not_allowed)
				(pads allowed)
				(copperpour not_allowed)
				(footprints allowed)
			)
			(placement
				(enabled no)
				(sheetname "")
			)
			(fill
				(thermal_gap 0.5)
				(thermal_bridge_width 0.5)
				(island_removal_mode 0)
			)
			(polygon
				(pts
					(xy 108.621576 -7.453376) (xy 110.094776 -7.453376) (xy 110.094776 -8.926576) (xy 108.621576 -8.926576)
				)
			)
		)
		(zone
			(layers "F.Cu" "B.Cu" "In1.Cu" "In2.Cu" "In3.Cu" "In4.Cu" "In5.Cu" "In6.Cu")
			(hatch none 0.5)
			(connect_pads
				(clearance 0)
			)
			(min_thickness 0.25)
			(keepout
				(tracks allowed)
				(vias not_allowed)
				(pads allowed)
				(copperpour not_allowed)
				(footprints allowed)
			)
			(placement
				(enabled no)
				(sheetname "")
			)
			(fill
				(thermal_gap 0.5)
				(thermal_bridge_width 0.5)
				(island_removal_mode 0)
			)
			(polygon
				(pts
					(xy 110.856776 -44.461176) (xy 112.533176 -44.461176) (xy 112.533176 -46.137576) (xy 110.856776 -46.137576)
				)
			)
		)
		(zone
			(layers "F.Cu" "B.Cu" "In1.Cu" "In2.Cu" "In3.Cu" "In4.Cu" "In5.Cu" "In6.Cu")
			(hatch none 0.5)
			(connect_pads
				(clearance 0)
			)
			(min_thickness 0.25)
			(keepout
				(tracks allowed)
				(vias not_allowed)
				(pads allowed)
				(copperpour not_allowed)
				(footprints allowed)
			)
			(placement
				(enabled no)
				(sheetname "")
			)
			(fill
				(thermal_gap 0.5)
				(thermal_bridge_width 0.5)
				(island_removal_mode 0)
			)
			(polygon
				(pts
					(xy 110.856776 -24.445976) (xy 112.533176 -24.445976) (xy 112.533176 -26.122376) (xy 110.856776 -26.122376)
				)
			)
		)
		(zone
			(layers "F.Cu" "B.Cu" "In1.Cu" "In2.Cu" "In3.Cu" "In4.Cu" "In5.Cu" "In6.Cu")
			(hatch none 0.5)
			(connect_pads
				(clearance 0)
			)
			(min_thickness 0.25)
			(keepout
				(tracks allowed)
				(vias not_allowed)
				(pads allowed)
				(copperpour not_allowed)
				(footprints allowed)
			)
			(placement
				(enabled no)
				(sheetname "")
			)
			(fill
				(thermal_gap 0.5)
				(thermal_bridge_width 0.5)
				(island_removal_mode 0)
			)
			(polygon
				(pts
					(xy 110.958376 -21.753576) (xy 112.431576 -21.753576) (xy 112.431576 -23.226776) (xy 110.958376 -23.226776)
				)
			)
		)
		(zone
			(layers "F.Cu" "B.Cu" "In1.Cu" "In2.Cu" "In3.Cu" "In4.Cu" "In5.Cu" "In6.Cu")
			(hatch none 0.5)
			(connect_pads
				(clearance 0)
			)
			(min_thickness 0.25)
			(keepout
				(tracks allowed)
				(vias not_allowed)
				(pads allowed)
				(copperpour not_allowed)
				(footprints allowed)
			)
			(placement
				(enabled no)
				(sheetname "")
			)
			(fill
				(thermal_gap 0.5)
				(thermal_bridge_width 0.5)
				(island_removal_mode 0)
			)
			(polygon
				(pts
					(xy 110.958376 -17.054576) (xy 112.431576 -17.054576) (xy 112.431576 -18.527776) (xy 110.958376 -18.527776)
				)
			)
		)
		(zone
			(layers "F.Cu" "B.Cu" "In1.Cu" "In2.Cu" "In3.Cu" "In4.Cu" "In5.Cu" "In6.Cu")
			(hatch none 0.5)
			(connect_pads
				(clearance 0)
			)
			(min_thickness 0.25)
			(keepout
				(tracks allowed)
				(vias not_allowed)
				(pads allowed)
				(copperpour not_allowed)
				(footprints allowed)
			)
			(placement
				(enabled no)
				(sheetname "")
			)
			(fill
				(thermal_gap 0.5)
				(thermal_bridge_width 0.5)
				(island_removal_mode 0)
			)
			(polygon
				(pts
					(xy 110.958376 -12.050776) (xy 112.431576 -12.050776) (xy 112.431576 -13.523976) (xy 110.958376 -13.523976)
				)
			)
		)
		(zone
			(layers "F.Cu" "B.Cu" "In1.Cu" "In2.Cu" "In3.Cu" "In4.Cu" "In5.Cu" "In6.Cu")
			(hatch none 0.5)
			(connect_pads
				(clearance 0)
			)
			(min_thickness 0.25)
			(keepout
				(tracks allowed)
				(vias not_allowed)
				(pads allowed)
				(copperpour not_allowed)
				(footprints allowed)
			)
			(placement
				(enabled no)
				(sheetname "")
			)
			(fill
				(thermal_gap 0.5)
				(thermal_bridge_width 0.5)
				(island_removal_mode 0)
			)
			(polygon
				(pts
					(xy 111.009176 -14.616176) (xy 112.380776 -14.616176) (xy 112.380776 -15.987776) (xy 111.009176 -15.987776)
				)
			)
		)
		(zone
			(layers "F.Cu" "B.Cu" "In1.Cu" "In2.Cu" "In3.Cu" "In4.Cu" "In5.Cu" "In6.Cu")
			(hatch none 0.5)
			(connect_pads
				(clearance 0)
			)
			(min_thickness 0.25)
			(keepout
				(tracks allowed)
				(vias not_allowed)
				(pads allowed)
				(copperpour not_allowed)
				(footprints allowed)
			)
			(placement
				(enabled no)
				(sheetname "")
			)
			(fill
				(thermal_gap 0.5)
				(thermal_bridge_width 0.5)
				(island_removal_mode 0)
			)
			(polygon
				(pts
					(xy 112.533176 -35.240976) (xy 112.533176 -36.129976) (xy 110.856776 -36.129976) (xy 110.856776 -34.453576)
					(xy 112.533176 -34.453576)
				)
			)
		)
	)
	(footprint ""
		(layer "F.Cu")
		(at 149.615144 -49.795176)
		(property "Reference" "J16"
			(at 4.98475 2.618232 90)
			(unlocked yes)
			(layer "F.SilkS")
			(effects
				(font
					(size 0.7874 0.5842)
					(thickness 0.1524)
				)
				(justify left)
			)
		)
		(property "Value" ""
			(at 0 0 0)
			(layer "F.Fab")
			(effects
				(font
					(size 1.27 1.27)
				)
			)
		)
		(duplicate_pad_numbers_are_jumpers no)
		(fp_line
			(start -18.2499 -9.99998)
			(end 3.999992 -9.99998)
			(stroke
				(width 0.1524)
				(type default)
			)
			(layer "F.SilkS")
		)
		(fp_line
			(start -18.2499 45.299884)
			(end -18.2499 -9.99998)
			(stroke
				(width 0.1524)
				(type default)
			)
			(layer "F.SilkS")
		)
		(fp_line
			(start -16.646144 45.299884)
			(end -18.2499 45.299884)
			(stroke
				(width 0.1524)
				(type default)
			)
			(layer "F.SilkS")
		)
		(fp_line
			(start -15.249906 -6.999986)
			(end 0.999998 -6.999986)
			(stroke
				(width 0.1524)
				(type default)
			)
			(layer "F.SilkS")
		)
		(fp_line
			(start -15.249906 42.29989)
			(end -15.249906 -6.999986)
			(stroke
				(width 0.1524)
				(type default)
			)
			(layer "F.SilkS")
		)
		(fp_line
			(start -13.24991 26.800048)
			(end -13.24991 41.299892)
			(stroke
				(width 0.1524)
				(type default)
			)
			(layer "F.SilkS")
		)
		(fp_line
			(start -13.24991 41.299892)
			(end -12.6746 41.299892)
			(stroke
				(width 0.1524)
				(type default)
			)
			(layer "F.SilkS")
		)
		(fp_line
			(start -12.319 42.29989)
			(end -15.249906 42.29989)
			(stroke
				(width 0.1524)
				(type default)
			)
			(layer "F.SilkS")
		)
		(fp_line
			(start -11.176 41.299892)
			(end -10.919968 41.299892)
			(stroke
				(width 0.1524)
				(type default)
			)
			(layer "F.SilkS")
		)
		(fp_line
			(start -10.919968 41.299892)
			(end -10.919968 42.29989)
			(stroke
				(width 0.1524)
				(type default)
			)
			(layer "F.SilkS")
		)
		(fp_line
			(start -10.919968 42.29989)
			(end -11.5316 42.29989)
			(stroke
				(width 0.1524)
				(type default)
			)
			(layer "F.SilkS")
		)
		(fp_line
			(start -3.32994 41.299892)
			(end -3.0734 41.299892)
			(stroke
				(width 0.1524)
				(type default)
			)
			(layer "F.SilkS")
		)
		(fp_line
			(start -3.32994 42.29989)
			(end -3.32994 41.299892)
			(stroke
				(width 0.1524)
				(type default)
			)
			(layer "F.SilkS")
		)
		(fp_line
			(start -2.7178 42.29989)
			(end -3.32994 42.29989)
			(stroke
				(width 0.1524)
				(type default)
			)
			(layer "F.SilkS")
		)
		(fp_line
			(start -1.5748 41.299892)
			(end -0.999998 41.299892)
			(stroke
				(width 0.1524)
				(type default)
			)
			(layer "F.SilkS")
		)
		(fp_line
			(start -0.999998 26.800048)
			(end -13.24991 26.800048)
			(stroke
				(width 0.1524)
				(type default)
			)
			(layer "F.SilkS")
		)
		(fp_line
			(start -0.999998 41.299892)
			(end -0.999998 26.800048)
			(stroke
				(width 0.1524)
				(type default)
			)
			(layer "F.SilkS")
		)
		(fp_line
			(start 0.999998 -6.999986)
			(end 0.999998 42.29989)
			(stroke
				(width 0.1524)
				(type default)
			)
			(layer "F.SilkS")
		)
		(fp_line
			(start 0.999998 42.29989)
			(end -1.9558 42.29989)
			(stroke
				(width 0.1524)
				(type default)
			)
			(layer "F.SilkS")
		)
		(fp_line
			(start 3.999992 -9.99998)
			(end 3.999992 45.299884)
			(stroke
				(width 0.1524)
				(type default)
			)
			(layer "F.SilkS")
		)
		(fp_line
			(start 3.999992 45.299884)
			(end -9.102344 45.299884)
			(stroke
				(width 0.1524)
				(type default)
			)
			(layer "F.SilkS")
		)
		(fp_poly
			(pts
				(xy 4.318 4.6101) (xy 7.747 5.7531) (xy 7.747 3.4671)
			)
			(stroke
				(width 0)
				(type default)
			)
			(fill yes)
			(layer "F.SilkS")
		)
		(fp_line
			(start -18.2499 -9.99998)
			(end 3.999992 -9.99998)
			(stroke
				(width 0.1524)
				(type default)
			)
			(layer "B.SilkS")
		)
		(fp_line
			(start -18.2499 27.112976)
			(end -18.2499 -9.99998)
			(stroke
				(width 0.1524)
				(type default)
			)
			(layer "B.SilkS")
		)
		(fp_line
			(start -18.2499 37.984176)
			(end -18.2499 28.052776)
			(stroke
				(width 0.1524)
				(type default)
			)
			(layer "B.SilkS")
		)
		(fp_line
			(start -18.2499 44.054776)
			(end -18.2499 43.394376)
			(stroke
				(width 0.1524)
				(type default)
			)
			(layer "B.SilkS")
		)
		(fp_line
			(start 3.999992 -9.99998)
			(end 3.999992 22.007576)
			(stroke
				(width 0.1524)
				(type default)
			)
			(layer "B.SilkS")
		)
		(fp_line
			(start 3.999992 23.048976)
			(end 3.999992 45.299884)
			(stroke
				(width 0.1524)
				(type default)
			)
			(layer "B.SilkS")
		)
		(fp_line
			(start 3.999992 45.299884)
			(end -16.544544 45.299884)
			(stroke
				(width 0.1524)
				(type default)
			)
			(layer "B.SilkS")
		)
		(fp_poly
			(pts
				(xy -15.0876 8.6614) (xy -13.4112 8.6614) (xy -13.4112 10.3378) (xy -15.0876 10.3378)
			)
			(stroke
				(width 0)
				(type default)
			)
			(fill no)
			(layer "B.CrtYd")
		)
		(fp_poly
			(pts
				(xy -15.0876 18.669) (xy -13.4112 18.669) (xy -13.4112 20.3454) (xy -15.0876 20.3454)
			)
			(stroke
				(width 0)
				(type default)
			)
			(fill no)
			(layer "B.CrtYd")
		)
		(fp_poly
			(pts
				(xy -15.0876 28.6512) (xy -13.4112 28.6512) (xy -13.4112 30.3276) (xy -15.0876 30.3276)
			)
			(stroke
				(width 0)
				(type default)
			)
			(fill no)
			(layer "B.CrtYd")
		)
		(fp_poly
			(pts
				(xy -15.0876 38.6588) (xy -13.4112 38.6588) (xy -13.4112 40.3352) (xy -15.0876 40.3352)
			)
			(stroke
				(width 0)
				(type default)
			)
			(fill no)
			(layer "B.CrtYd")
		)
		(fp_poly
			(pts
				(xy -14.986 26.5684) (xy -13.5128 26.5684) (xy -13.5128 28.0416) (xy -14.986 28.0416)
			)
			(stroke
				(width 0)
				(type default)
			)
			(fill no)
			(layer "B.CrtYd")
		)
		(fp_poly
			(pts
				(xy -14.986 31.2674) (xy -13.5128 31.2674) (xy -13.5128 32.7406) (xy -14.986 32.7406)
			)
			(stroke
				(width 0)
				(type default)
			)
			(fill no)
			(layer "B.CrtYd")
		)
		(fp_poly
			(pts
				(xy -14.986 36.2712) (xy -13.5128 36.2712) (xy -13.5128 37.7444) (xy -14.986 37.7444)
			)
			(stroke
				(width 0)
				(type default)
			)
			(fill no)
			(layer "B.CrtYd")
		)
		(fp_poly
			(pts
				(xy -12.6746 40.8686) (xy -11.2014 40.8686) (xy -11.2014 42.3418) (xy -12.6746 42.3418)
			)
			(stroke
				(width 0)
				(type default)
			)
			(fill no)
			(layer "B.CrtYd")
		)
		(fp_poly
			(pts
				(xy -11.9126 23.6728) (xy -10.2362 23.6728) (xy -10.2362 25.3492) (xy -11.9126 25.3492)
			)
			(stroke
				(width 0)
				(type default)
			)
			(fill no)
			(layer "B.CrtYd")
		)
		(fp_poly
			(pts
				(xy -9.4488 3.6576) (xy -7.7724 3.6576) (xy -7.7724 5.334) (xy -9.4488 5.334)
			)
			(stroke
				(width 0)
				(type default)
			)
			(fill no)
			(layer "B.CrtYd")
		)
		(fp_poly
			(pts
				(xy -7.874 40.8686) (xy -6.4008 40.8686) (xy -6.4008 42.3418) (xy -7.874 42.3418)
			)
			(stroke
				(width 0)
				(type default)
			)
			(fill no)
			(layer "B.CrtYd")
		)
		(fp_poly
			(pts
				(xy -6.5278 23.6728) (xy -4.8514 23.6728) (xy -4.8514 25.3492) (xy -6.5278 25.3492)
			)
			(stroke
				(width 0)
				(type default)
			)
			(fill no)
			(layer "B.CrtYd")
		)
		(fp_poly
			(pts
				(xy -3.0734 40.8686) (xy -1.6002 40.8686) (xy -1.6002 42.3418) (xy -3.0734 42.3418)
			)
			(stroke
				(width 0)
				(type default)
			)
			(fill no)
			(layer "B.CrtYd")
		)
		(fp_poly
			(pts
				(xy -0.8382 3.6576) (xy 0.8382 3.6576) (xy 0.8382 5.334) (xy -0.8382 5.334)
			)
			(stroke
				(width 0)
				(type default)
			)
			(fill no)
			(layer "B.CrtYd")
		)
		(fp_poly
			(pts
				(xy -0.8382 23.6728) (xy 0.8382 23.6728) (xy 0.8382 25.3492) (xy -0.8382 25.3492)
			)
			(stroke
				(width 0)
				(type default)
			)
			(fill no)
			(layer "B.CrtYd")
		)
		(fp_poly
			(pts
				(xy -0.7366 26.5684) (xy 0.7366 26.5684) (xy 0.7366 28.0416) (xy -0.7366 28.0416)
			)
			(stroke
				(width 0)
				(type default)
			)
			(fill no)
			(layer "B.CrtYd")
		)
		(fp_poly
			(pts
				(xy -0.7366 31.2674) (xy 0.7366 31.2674) (xy 0.7366 32.7406) (xy -0.7366 32.7406)
			)
			(stroke
				(width 0)
				(type default)
			)
			(fill no)
			(layer "B.CrtYd")
		)
		(fp_poly
			(pts
				(xy -0.7366 36.2712) (xy 0.7366 36.2712) (xy 0.7366 37.7444) (xy -0.7366 37.7444)
			)
			(stroke
				(width 0)
				(type default)
			)
			(fill no)
			(layer "B.CrtYd")
		)
		(fp_poly
			(pts
				(xy -0.6858 33.8074) (xy 0.6858 33.8074) (xy 0.6858 35.179) (xy -0.6858 35.179)
			)
			(stroke
				(width 0)
				(type default)
			)
			(fill no)
			(layer "B.CrtYd")
		)
		(fp_poly
			(pts
				(xy 0.8382 14.5542) (xy 0.8382 13.6652) (xy 0 13.6652) (xy -0.8382 13.6652) (xy -0.8382 15.3416)
				(xy 0.8382 15.3416)
			)
			(stroke
				(width 0)
				(type default)
			)
			(fill no)
			(layer "B.CrtYd")
		)
		(fp_rect
			(start -8.130032 42.29989)
			(end -6.130036 41.299892)
			(stroke
				(width 0)
				(type default)
			)
			(fill no)
			(layer "F.CrtYd")
		)
		(fp_poly
			(pts
				(xy 0.999998 -6.999986) (xy 0.999998 42.29989) (xy -3.32994 42.29989) (xy -3.32994 41.299892) (xy -0.999998 41.299892)
				(xy -0.999998 26.800048) (xy -13.24991 26.800048) (xy -13.24991 41.299892) (xy -10.919968 41.299892)
				(xy -10.919968 42.29989) (xy -15.249906 42.29989) (xy -15.249906 -6.999986)
			)
			(stroke
				(width 0)
				(type default)
			)
			(fill no)
			(layer "F.CrtYd")
		)
		(fp_line
			(start -15.249906 -6.999986)
			(end 0.999998 -6.999986)
			(stroke
				(width 0.1)
				(type default)
			)
			(layer "F.Fab")
		)
		(fp_line
			(start -15.249906 0)
			(end 0.999998 0)
			(stroke
				(width 0.1)
				(type default)
			)
			(layer "F.Fab")
		)
		(fp_line
			(start -15.249906 41.999916)
			(end -15.249906 -6.999986)
			(stroke
				(width 0.1)
				(type default)
			)
			(layer "F.Fab")
		)
		(fp_line
			(start -15.249906 42.29989)
			(end -15.249906 0)
			(stroke
				(width 0.1)
				(type default)
			)
			(layer "F.Fab")
		)
		(fp_line
			(start -13.24991 26.800048)
			(end -13.24991 41.299892)
			(stroke
				(width 0.1)
				(type default)
			)
			(layer "F.Fab")
		)
		(fp_line
			(start -13.24991 41.299892)
			(end -10.919968 41.299892)
			(stroke
				(width 0.1)
				(type default)
			)
			(layer "F.Fab")
		)
		(fp_line
			(start -10.919968 41.299892)
			(end -10.919968 42.29989)
			(stroke
				(width 0.1)
				(type default)
			)
			(layer "F.Fab")
		)
		(fp_line
			(start -10.919968 42.29989)
			(end -15.249906 42.29989)
			(stroke
				(width 0.1)
				(type default)
			)
			(layer "F.Fab")
		)
		(fp_line
			(start -3.32994 41.299892)
			(end -0.999998 41.299892)
			(stroke
				(width 0.1)
				(type default)
			)
			(layer "F.Fab")
		)
		(fp_line
			(start -3.32994 42.29989)
			(end -3.32994 41.299892)
			(stroke
				(width 0.1)
				(type default)
			)
			(layer "F.Fab")
		)
		(fp_line
			(start -0.999998 26.800048)
			(end -13.24991 26.800048)
			(stroke
				(width 0.1)
				(type default)
			)
			(layer "F.Fab")
		)
		(fp_line
			(start -0.999998 41.299892)
			(end -0.999998 26.800048)
			(stroke
				(width 0.1)
				(type default)
			)
			(layer "F.Fab")
		)
		(fp_line
			(start 0.999998 -6.999986)
			(end 0.999998 41.999916)
			(stroke
				(width 0.1)
				(type default)
			)
			(layer "F.Fab")
		)
		(fp_line
			(start 0.999998 0)
			(end 0.999998 42.29989)
			(stroke
				(width 0.1)
				(type default)
			)
			(layer "F.Fab")
		)
		(fp_line
			(start 0.999998 41.999916)
			(end -15.249906 41.999916)
			(stroke
				(width 0.1)
				(type default)
			)
			(layer "F.Fab")
		)
		(fp_line
			(start 0.999998 42.29989)
			(end -3.32994 42.29989)
			(stroke
				(width 0.1)
				(type default)
			)
			(layer "F.Fab")
		)
		(fp_text user "PRESS-FIT"
			(at 2.59461 23.398988 90)
			(unlocked yes)
			(layer "F.SilkS")
			(effects
				(font
					(size 1.6002 1.1938)
					(thickness 0.1524)
				)
				(justify left)
			)
		)
		(fp_text user "PRESS-FIT"
			(at 2.556002 21.815552 270)
			(unlocked yes)
			(layer "B.SilkS")
			(effects
				(font
					(size 1.6002 1.1938)
					(thickness 0.1524)
				)
				(justify left mirror)
			)
		)
		(pad "1" thru_hole circle
			(at 0 4.500118)
			(size 1.5494 1.5494)
			(drill 1.0414)
			(layers "*.Cu" "*.Mask")
			(remove_unused_layers no)
			(net "GND")
			(clearance 0)
		)
		(pad "2" thru_hole circle
			(at -8.58012 4.500118)
			(size 1.5494 1.5494)
			(drill 1.0414)
			(layers "*.Cu" "*.Mask")
			(remove_unused_layers no)
			(net "GND")
			(clearance 0)
		)
		(pad "3" thru_hole circle
			(at 0 14.500098)
			(size 1.5494 1.5494)
			(drill 1.0414)
			(layers "*.Cu" "*.Mask")
			(remove_unused_layers no)
			(net "GND")
			(clearance 0)
		)
		(pad "4" thru_hole circle
			(at -14.249908 9.500108)
			(size 1.5494 1.5494)
			(drill 1.0414)
			(layers "*.Cu" "*.Mask")
			(remove_unused_layers no)
			(net "GND")
			(clearance 0)
		)
		(pad "5" thru_hole circle
			(at -14.249908 19.500088)
			(size 1.5494 1.5494)
			(drill 1.0414)
			(layers "*.Cu" "*.Mask")
			(remove_unused_layers no)
			(net "GND")
			(clearance 0)
		)
		(pad "6" thru_hole circle
			(at 0 24.500078)
			(size 1.5494 1.5494)
			(drill 1.0414)
			(layers "*.Cu" "*.Mask")
			(remove_unused_layers no)
			(net "GND")
			(clearance 0)
		)
		(pad "7" thru_hole circle
			(at -5.679948 24.500078)
			(size 1.5494 1.5494)
			(drill 1.0414)
			(layers "*.Cu" "*.Mask")
			(remove_unused_layers no)
			(net "GND")
			(clearance 0)
		)
		(pad "8" thru_hole circle
			(at -11.079988 24.500078)
			(size 1.5494 1.5494)
			(drill 1.0414)
			(layers "*.Cu" "*.Mask")
			(remove_unused_layers no)
			(net "GND")
			(clearance 0)
		)
		(pad "9" thru_hole circle
			(at -14.249908 29.500068)
			(size 1.5494 1.5494)
			(drill 1.0414)
			(layers "*.Cu" "*.Mask")
			(remove_unused_layers no)
			(net "GND")
			(clearance 0)
		)
		(pad "10" thru_hole circle
			(at -14.249908 39.500048)
			(size 1.5494 1.5494)
			(drill 1.0414)
			(layers "*.Cu" "*.Mask")
			(remove_unused_layers no)
			(net "GND")
			(clearance 0)
		)
		(pad "11" thru_hole circle
			(at 0 27.29992)
			(size 1.3462 1.3462)
			(drill 0.9398)
			(layers "*.Cu" "*.Mask")
			(remove_unused_layers no)
			(net "GND")
			(clearance 0.0508)
			(thermal_gap 0.0508)
		)
		(pad "12" thru_hole circle
			(at 0 31.999936)
			(size 1.3462 1.3462)
			(drill 0.9398)
			(layers "*.Cu" "*.Mask")
			(remove_unused_layers no)
			(net "GND")
			(clearance 0.0508)
			(thermal_gap 0.0508)
		)
		(pad "13" thru_hole circle
			(at 0 36.999926)
			(size 1.3462 1.3462)
			(drill 0.9398)
			(layers "*.Cu" "*.Mask")
			(remove_unused_layers no)
			(net "GND")
			(clearance 0.0508)
			(thermal_gap 0.0508)
		)
		(pad "14" thru_hole circle
			(at -2.329942 41.60012)
			(size 1.3462 1.3462)
			(drill 0.9398)
			(layers "*.Cu" "*.Mask")
			(remove_unused_layers no)
			(net "GND")
			(clearance 0.0508)
			(thermal_gap 0.0508)
		)
		(pad "15" thru_hole circle
			(at -7.130034 41.60012)
			(size 1.3462 1.3462)
			(drill 0.9398)
			(layers "*.Cu" "*.Mask")
			(remove_unused_layers no)
			(net "GND")
			(clearance 0.0508)
			(thermal_gap 0.0508)
		)
		(pad "16" thru_hole circle
			(at -11.929872 41.60012)
			(size 1.3462 1.3462)
			(drill 0.9398)
			(layers "*.Cu" "*.Mask")
			(remove_unused_layers no)
			(net "GND")
			(clearance 0.0508)
			(thermal_gap 0.0508)
		)
		(pad "17" thru_hole circle
			(at -14.249908 27.29992)
			(size 1.3462 1.3462)
			(drill 0.9398)
			(layers "*.Cu" "*.Mask")
			(remove_unused_layers no)
			(net "GND")
			(clearance 0.0508)
			(thermal_gap 0.0508)
		)
		(pad "18" thru_hole circle
			(at -14.249908 31.999936)
			(size 1.3462 1.3462)
			(drill 0.9398)
			(layers "*.Cu" "*.Mask")
			(remove_unused_layers no)
			(net "GND")
			(clearance 0.0508)
			(thermal_gap 0.0508)
		)
		(pad "19" thru_hole circle
			(at -14.249908 36.999926)
			(size 1.3462 1.3462)
			(drill 0.9398)
			(layers "*.Cu" "*.Mask")
			(remove_unused_layers no)
			(net "GND")
			(clearance 0.0508)
			(thermal_gap 0.0508)
		)
		(pad "20" thru_hole circle
			(at 0 34.500058)
			(size 1.2446 1.2446)
			(drill 0.8382)
			(layers "*.Cu" "*.Mask")
			(remove_unused_layers no)
			(net "GND")
			(clearance 0.0508)
			(thermal_gap 0.0508)
		)
		(zone
			(layer "F.Cu")
			(hatch none 0.5)
			(connect_pads
				(clearance 0)
			)
			(min_thickness 0.25)
			(keepout
				(tracks not_allowed)
				(vias allowed)
				(pads allowed)
				(copperpour not_allowed)
				(footprints allowed)
			)
			(placement
				(enabled no)
				(sheetname "")
			)
			(fill
				(thermal_gap 0.5)
				(thermal_bridge_width 0.5)
				(island_removal_mode 0)
			)
			(polygon
				(pts
					(xy 141.485112 -7.495286) (xy 143.485108 -7.495286) (xy 143.485108 -8.495284) (xy 141.485112 -8.495284)
				)
			)
		)
		(zone
			(layer "F.Cu")
			(hatch none 0.5)
			(connect_pads
				(clearance 0)
			)
			(min_thickness 0.25)
			(keepout
				(tracks not_allowed)
				(vias allowed)
				(pads allowed)
				(copperpour not_allowed)
				(footprints allowed)
			)
			(placement
				(enabled no)
				(sheetname "")
			)
			(fill
				(thermal_gap 0.5)
				(thermal_bridge_width 0.5)
				(island_removal_mode 0)
			)
			(polygon
				(pts
					(xy 150.615142 -49.795176) (xy 150.615142 -7.495286) (xy 146.285204 -7.495286) (xy 146.285204 -8.495284)
					(xy 148.615146 -8.495284) (xy 148.615146 -22.995128) (xy 136.365234 -22.995128) (xy 136.365234 -8.495284)
					(xy 138.695176 -8.495284) (xy 138.695176 -7.495286) (xy 134.365238 -7.495286) (xy 134.371588 -49.795176)
				)
			)
		)
		(zone
			(layers "F.Cu" "B.Cu" "In1.Cu" "In2.Cu" "In3.Cu" "In4.Cu" "In5.Cu" "In6.Cu")
			(hatch none 0.5)
			(connect_pads
				(clearance 0)
			)
			(min_thickness 0.25)
			(keepout
				(tracks allowed)
				(vias not_allowed)
				(pads allowed)
				(copperpour not_allowed)
				(footprints allowed)
			)
			(placement
				(enabled no)
				(sheetname "")
			)
			(fill
				(thermal_gap 0.5)
				(thermal_bridge_width 0.5)
				(island_removal_mode 0)
			)
			(polygon
				(pts
					(xy 134.527544 -39.457376) (xy 136.203944 -39.457376) (xy 136.203944 -41.133776) (xy 134.527544 -41.133776)
				)
			)
		)
		(zone
			(layers "F.Cu" "B.Cu" "In1.Cu" "In2.Cu" "In3.Cu" "In4.Cu" "In5.Cu" "In6.Cu")
			(hatch none 0.5)
			(connect_pads
				(clearance 0)
			)
			(min_thickness 0.25)
			(keepout
				(tracks allowed)
				(vias not_allowed)
				(pads allowed)
				(copperpour not_allowed)
				(footprints allowed)
			)
			(placement
				(enabled no)
				(sheetname "")
			)
			(fill
				(thermal_gap 0.5)
				(thermal_bridge_width 0.5)
				(island_removal_mode 0)
			)
			(polygon
				(pts
					(xy 134.527544 -29.449776) (xy 136.203944 -29.449776) (xy 136.203944 -31.126176) (xy 134.527544 -31.126176)
				)
			)
		)
		(zone
			(layers "F.Cu" "B.Cu" "In1.Cu" "In2.Cu" "In3.Cu" "In4.Cu" "In5.Cu" "In6.Cu")
			(hatch none 0.5)
			(connect_pads
				(clearance 0)
			)
			(min_thickness 0.25)
			(keepout
				(tracks allowed)
				(vias not_allowed)
				(pads allowed)
				(copperpour not_allowed)
				(footprints allowed)
			)
			(placement
				(enabled no)
				(sheetname "")
			)
			(fill
				(thermal_gap 0.5)
				(thermal_bridge_width 0.5)
				(island_removal_mode 0)
			)
			(polygon
				(pts
					(xy 134.527544 -19.467576) (xy 136.203944 -19.467576) (xy 136.203944 -21.143976) (xy 134.527544 -21.143976)
				)
			)
		)
		(zone
			(layers "F.Cu" "B.Cu" "In1.Cu" "In2.Cu" "In3.Cu" "In4.Cu" "In5.Cu" "In6.Cu")
			(hatch none 0.5)
			(connect_pads
				(clearance 0)
			)
			(min_thickness 0.25)
			(keepout
				(tracks allowed)
				(vias not_allowed)
				(pads allowed)
				(copperpour not_allowed)
				(footprints allowed)
			)
			(placement
				(enabled no)
				(sheetname "")
			)
			(fill
				(thermal_gap 0.5)
				(thermal_bridge_width 0.5)
				(island_removal_mode 0)
			)
			(polygon
				(pts
					(xy 134.527544 -9.459976) (xy 136.203944 -9.459976) (xy 136.203944 -11.136376) (xy 134.527544 -11.136376)
				)
			)
		)
		(zone
			(layers "F.Cu" "B.Cu" "In1.Cu" "In2.Cu" "In3.Cu" "In4.Cu" "In5.Cu" "In6.Cu")
			(hatch none 0.5)
			(connect_pads
				(clearance 0)
			)
			(min_thickness 0.25)
			(keepout
				(tracks allowed)
				(vias not_allowed)
				(pads allowed)
				(copperpour not_allowed)
				(footprints allowed)
			)
			(placement
				(enabled no)
				(sheetname "")
			)
			(fill
				(thermal_gap 0.5)
				(thermal_bridge_width 0.5)
				(island_removal_mode 0)
			)
			(polygon
				(pts
					(xy 134.629144 -21.753576) (xy 136.102344 -21.753576) (xy 136.102344 -23.226776) (xy 134.629144 -23.226776)
				)
			)
		)
		(zone
			(layers "F.Cu" "B.Cu" "In1.Cu" "In2.Cu" "In3.Cu" "In4.Cu" "In5.Cu" "In6.Cu")
			(hatch none 0.5)
			(connect_pads
				(clearance 0)
			)
			(min_thickness 0.25)
			(keepout
				(tracks allowed)
				(vias not_allowed)
				(pads allowed)
				(copperpour not_allowed)
				(footprints allowed)
			)
			(placement
				(enabled no)
				(sheetname "")
			)
			(fill
				(thermal_gap 0.5)
				(thermal_bridge_width 0.5)
				(island_removal_mode 0)
			)
			(polygon
				(pts
					(xy 134.629144 -17.054576) (xy 136.102344 -17.054576) (xy 136.102344 -18.527776) (xy 134.629144 -18.527776)
				)
			)
		)
		(zone
			(layers "F.Cu" "B.Cu" "In1.Cu" "In2.Cu" "In3.Cu" "In4.Cu" "In5.Cu" "In6.Cu")
			(hatch none 0.5)
			(connect_pads
				(clearance 0)
			)
			(min_thickness 0.25)
			(keepout
				(tracks allowed)
				(vias not_allowed)
				(pads allowed)
				(copperpour not_allowed)
				(footprints allowed)
			)
			(placement
				(enabled no)
				(sheetname "")
			)
			(fill
				(thermal_gap 0.5)
				(thermal_bridge_width 0.5)
				(island_removal_mode 0)
			)
			(polygon
				(pts
					(xy 134.629144 -12.050776) (xy 136.102344 -12.050776) (xy 136.102344 -13.523976) (xy 134.629144 -13.523976)
				)
			)
		)
		(zone
			(layers "F.Cu" "B.Cu" "In1.Cu" "In2.Cu" "In3.Cu" "In4.Cu" "In5.Cu" "In6.Cu")
			(hatch none 0.5)
			(connect_pads
				(clearance 0)
			)
			(min_thickness 0.25)
			(keepout
				(tracks allowed)
				(vias not_allowed)
				(pads allowed)
				(copperpour not_allowed)
				(footprints allowed)
			)
			(placement
				(enabled no)
				(sheetname "")
			)
			(fill
				(thermal_gap 0.5)
				(thermal_bridge_width 0.5)
				(island_removal_mode 0)
			)
			(polygon
				(pts
					(xy 136.940544 -7.453376) (xy 138.413744 -7.453376) (xy 138.413744 -8.926576) (xy 136.940544 -8.926576)
				)
			)
		)
		(zone
			(layers "F.Cu" "B.Cu" "In1.Cu" "In2.Cu" "In3.Cu" "In4.Cu" "In5.Cu" "In6.Cu")
			(hatch none 0.5)
			(connect_pads
				(clearance 0)
			)
			(min_thickness 0.25)
			(keepout
				(tracks allowed)
				(vias not_allowed)
				(pads allowed)
				(copperpour not_allowed)
				(footprints allowed)
			)
			(placement
				(enabled no)
				(sheetname "")
			)
			(fill
				(thermal_gap 0.5)
				(thermal_bridge_width 0.5)
				(island_removal_mode 0)
			)
			(polygon
				(pts
					(xy 137.702544 -24.445976) (xy 139.378944 -24.445976) (xy 139.378944 -26.122376) (xy 137.702544 -26.122376)
				)
			)
		)
		(zone
			(layers "F.Cu" "B.Cu" "In1.Cu" "In2.Cu" "In3.Cu" "In4.Cu" "In5.Cu" "In6.Cu")
			(hatch none 0.5)
			(connect_pads
				(clearance 0)
			)
			(min_thickness 0.25)
			(keepout
				(tracks allowed)
				(vias not_allowed)
				(pads allowed)
				(copperpour not_allowed)
				(footprints allowed)
			)
			(placement
				(enabled no)
				(sheetname "")
			)
			(fill
				(thermal_gap 0.5)
				(thermal_bridge_width 0.5)
				(island_removal_mode 0)
			)
			(polygon
				(pts
					(xy 140.166344 -44.461176) (xy 141.842744 -44.461176) (xy 141.842744 -46.137576) (xy 140.166344 -46.137576)
				)
			)
		)
		(zone
			(layers "F.Cu" "B.Cu" "In1.Cu" "In2.Cu" "In3.Cu" "In4.Cu" "In5.Cu" "In6.Cu")
			(hatch none 0.5)
			(connect_pads
				(clearance 0)
			)
			(min_thickness 0.25)
			(keepout
				(tracks allowed)
				(vias not_allowed)
				(pads allowed)
				(copperpour not_allowed)
				(footprints allowed)
			)
			(placement
				(enabled no)
				(sheetname "")
			)
			(fill
				(thermal_gap 0.5)
				(thermal_bridge_width 0.5)
				(island_removal_mode 0)
			)
			(polygon
				(pts
					(xy 141.741144 -7.453376) (xy 143.214344 -7.453376) (xy 143.214344 -8.926576) (xy 141.741144 -8.926576)
				)
			)
		)
		(zone
			(layers "F.Cu" "B.Cu" "In1.Cu" "In2.Cu" "In3.Cu" "In4.Cu" "In5.Cu" "In6.Cu")
			(hatch none 0.5)
			(connect_pads
				(clearance 0)
			)
			(min_thickness 0.25)
			(keepout
				(tracks allowed)
				(vias not_allowed)
				(pads allowed)
				(copperpour not_allowed)
				(footprints allowed)
			)
			(placement
				(enabled no)
				(sheetname "")
			)
			(fill
				(thermal_gap 0.5)
				(thermal_bridge_width 0.5)
				(island_removal_mode 0)
			)
			(polygon
				(pts
					(xy 143.087344 -24.445976) (xy 144.763744 -24.445976) (xy 144.763744 -26.122376) (xy 143.087344 -26.122376)
				)
			)
		)
		(zone
			(layers "F.Cu" "B.Cu" "In1.Cu" "In2.Cu" "In3.Cu" "In4.Cu" "In5.Cu" "In6.Cu")
			(hatch none 0.5)
			(connect_pads
				(clearance 0)
			)
			(min_thickness 0.25)
			(keepout
				(tracks allowed)
				(vias not_allowed)
				(pads allowed)
				(copperpour not_allowed)
				(footprints allowed)
			)
			(placement
				(enabled no)
				(sheetname "")
			)
			(fill
				(thermal_gap 0.5)
				(thermal_bridge_width 0.5)
				(island_removal_mode 0)
			)
			(polygon
				(pts
					(xy 146.541744 -7.453376) (xy 148.014944 -7.453376) (xy 148.014944 -8.926576) (xy 146.541744 -8.926576)
				)
			)
		)
		(zone
			(layers "F.Cu" "B.Cu" "In1.Cu" "In2.Cu" "In3.Cu" "In4.Cu" "In5.Cu" "In6.Cu")
			(hatch none 0.5)
			(connect_pads
				(clearance 0)
			)
			(min_thickness 0.25)
			(keepout
				(tracks allowed)
				(vias not_allowed)
				(pads allowed)
				(copperpour not_allowed)
				(footprints allowed)
			)
			(placement
				(enabled no)
				(sheetname "")
			)
			(fill
				(thermal_gap 0.5)
				(thermal_bridge_width 0.5)
				(island_removal_mode 0)
			)
			(polygon
				(pts
					(xy 148.776944 -44.461176) (xy 150.453344 -44.461176) (xy 150.453344 -46.137576) (xy 148.776944 -46.137576)
				)
			)
		)
		(zone
			(layers "F.Cu" "B.Cu" "In1.Cu" "In2.Cu" "In3.Cu" "In4.Cu" "In5.Cu" "In6.Cu")
			(hatch none 0.5)
			(connect_pads
				(clearance 0)
			)
			(min_thickness 0.25)
			(keepout
				(tracks allowed)
				(vias not_allowed)
				(pads allowed)
				(copperpour not_allowed)
				(footprints allowed)
			)
			(placement
				(enabled no)
				(sheetname "")
			)
			(fill
				(thermal_gap 0.5)
				(thermal_bridge_width 0.5)
				(island_removal_mode 0)
			)
			(polygon
				(pts
					(xy 148.776944 -24.445976) (xy 150.453344 -24.445976) (xy 150.453344 -26.122376) (xy 148.776944 -26.122376)
				)
			)
		)
		(zone
			(layers "F.Cu" "B.Cu" "In1.Cu" "In2.Cu" "In3.Cu" "In4.Cu" "In5.Cu" "In6.Cu")
			(hatch none 0.5)
			(connect_pads
				(clearance 0)
			)
			(min_thickness 0.25)
			(keepout
				(tracks allowed)
				(vias not_allowed)
				(pads allowed)
				(copperpour not_allowed)
				(footprints allowed)
			)
			(placement
				(enabled no)
				(sheetname "")
			)
			(fill
				(thermal_gap 0.5)
				(thermal_bridge_width 0.5)
				(island_removal_mode 0)
			)
			(polygon
				(pts
					(xy 148.878544 -21.753576) (xy 150.351744 -21.753576) (xy 150.351744 -23.226776) (xy 148.878544 -23.226776)
				)
			)
		)
		(zone
			(layers "F.Cu" "B.Cu" "In1.Cu" "In2.Cu" "In3.Cu" "In4.Cu" "In5.Cu" "In6.Cu")
			(hatch none 0.5)
			(connect_pads
				(clearance 0)
			)
			(min_thickness 0.25)
			(keepout
				(tracks allowed)
				(vias not_allowed)
				(pads allowed)
				(copperpour not_allowed)
				(footprints allowed)
			)
			(placement
				(enabled no)
				(sheetname "")
			)
			(fill
				(thermal_gap 0.5)
				(thermal_bridge_width 0.5)
				(island_removal_mode 0)
			)
			(polygon
				(pts
					(xy 148.878544 -17.054576) (xy 150.351744 -17.054576) (xy 150.351744 -18.527776) (xy 148.878544 -18.527776)
				)
			)
		)
		(zone
			(layers "F.Cu" "B.Cu" "In1.Cu" "In2.Cu" "In3.Cu" "In4.Cu" "In5.Cu" "In6.Cu")
			(hatch none 0.5)
			(connect_pads
				(clearance 0)
			)
			(min_thickness 0.25)
			(keepout
				(tracks allowed)
				(vias not_allowed)
				(pads allowed)
				(copperpour not_allowed)
				(footprints allowed)
			)
			(placement
				(enabled no)
				(sheetname "")
			)
			(fill
				(thermal_gap 0.5)
				(thermal_bridge_width 0.5)
				(island_removal_mode 0)
			)
			(polygon
				(pts
					(xy 148.878544 -12.050776) (xy 150.351744 -12.050776) (xy 150.351744 -13.523976) (xy 148.878544 -13.523976)
				)
			)
		)
		(zone
			(layers "F.Cu" "B.Cu" "In1.Cu" "In2.Cu" "In3.Cu" "In4.Cu" "In5.Cu" "In6.Cu")
			(hatch none 0.5)
			(connect_pads
				(clearance 0)
			)
			(min_thickness 0.25)
			(keepout
				(tracks allowed)
				(vias not_allowed)
				(pads allowed)
				(copperpour not_allowed)
				(footprints allowed)
			)
			(placement
				(enabled no)
				(sheetname "")
			)
			(fill
				(thermal_gap 0.5)
				(thermal_bridge_width 0.5)
				(island_removal_mode 0)
			)
			(polygon
				(pts
					(xy 148.929344 -14.616176) (xy 150.300944 -14.616176) (xy 150.300944 -15.987776) (xy 148.929344 -15.987776)
				)
			)
		)
		(zone
			(layers "F.Cu" "B.Cu" "In1.Cu" "In2.Cu" "In3.Cu" "In4.Cu" "In5.Cu" "In6.Cu")
			(hatch none 0.5)
			(connect_pads
				(clearance 0)
			)
			(min_thickness 0.25)
			(keepout
				(tracks allowed)
				(vias not_allowed)
				(pads allowed)
				(copperpour not_allowed)
				(footprints allowed)
			)
			(placement
				(enabled no)
				(sheetname "")
			)
			(fill
				(thermal_gap 0.5)
				(thermal_bridge_width 0.5)
				(island_removal_mode 0)
			)
			(polygon
				(pts
					(xy 150.453344 -35.240976) (xy 150.453344 -36.129976) (xy 148.776944 -36.129976) (xy 148.776944 -34.453576)
					(xy 150.453344 -34.453576)
				)
			)
		)
	)
	(footprint ""
		(layer "F.Cu")
		(at 351.208848 -24.348694 180)
		(property "Reference" "R25"
			(at 58.940192 4.27736 0)
			(unlocked yes)
			(layer "F.SilkS")
			(effects
				(font
					(size 0.7874 0.5842)
					(thickness 0.1524)
				)
				(justify left)
			)
		)
		(property "Value" ""
			(at 0 0 180)
			(layer "F.Fab")
			(effects
				(font
					(size 1.27 1.27)
				)
			)
		)
		(duplicate_pad_numbers_are_jumpers no)
		(fp_line
			(start 0.7874 0.4064)
			(end -0.7874 0.4064)
			(stroke
				(width 0.1524)
				(type default)
			)
			(layer "F.SilkS")
		)
		(fp_line
			(start 0.7874 -0.4064)
			(end 0.7874 0.4064)
			(stroke
				(width 0.1524)
				(type default)
			)
			(layer "F.SilkS")
		)
		(fp_line
			(start -0.7874 0.4064)
			(end -0.7874 -0.4064)
			(stroke
				(width 0.1524)
				(type default)
			)
			(layer "F.SilkS")
		)
		(fp_line
			(start -0.7874 -0.4064)
			(end 0.7874 -0.4064)
			(stroke
				(width 0.1524)
				(type default)
			)
			(layer "F.SilkS")
		)
		(fp_poly
			(pts
				(xy -0.508 0.2794) (xy -0.508 0.2286) (xy -0.635 0.2286) (xy -0.635 -0.254) (xy -0.5334 -0.254)
				(xy -0.5334 -0.2794) (xy 0.5334 -0.2794) (xy 0.5334 -0.254) (xy 0.635 -0.254) (xy 0.635 0.254) (xy 0.5334 0.254)
				(xy 0.5334 0.2794)
			)
			(stroke
				(width 0)
				(type default)
			)
			(fill no)
			(layer "F.CrtYd")
		)
		(pad "1" smd rect
			(at 0.40005 0 180)
			(size 0.4572 0.508)
			(layers "F.Cu" "F.Mask" "F.Paste")
			(net "P3V3_BLAD2")
		)
		(pad "2" smd rect
			(at -0.40005 0 180)
			(size 0.4572 0.508)
			(layers "F.Cu" "F.Mask" "F.Paste")
			(net "ENET10G_3_MOD_DEF0")
		)
	)
	(footprint ""
		(layer "F.Cu")
		(at 325.570088 -14.390116 180)
		(property "Reference" "U8"
			(at 5.929376 -10.501884 0)
			(unlocked yes)
			(layer "F.SilkS")
			(effects
				(font
					(size 0.7874 0.5842)
					(thickness 0.1524)
				)
				(justify left)
			)
		)
		(property "Value" ""
			(at 0 0 180)
			(layer "F.Fab")
			(effects
				(font
					(size 1.27 1.27)
				)
			)
		)
		(duplicate_pad_numbers_are_jumpers no)
		(fp_line
			(start 5.500116 3.700018)
			(end 4.191 3.700018)
			(stroke
				(width 0.1524)
				(type default)
			)
			(layer "F.SilkS")
		)
		(fp_line
			(start 5.500116 0.889)
			(end 5.500116 3.700018)
			(stroke
				(width 0.1524)
				(type default)
			)
			(layer "F.SilkS")
		)
		(fp_line
			(start 5.500116 -3.700018)
			(end 5.500116 -0.889)
			(stroke
				(width 0.1524)
				(type default)
			)
			(layer "F.SilkS")
		)
		(fp_line
			(start 3.7846 -3.700018)
			(end 5.500116 -3.700018)
			(stroke
				(width 0.1524)
				(type default)
			)
			(layer "F.SilkS")
		)
		(fp_line
			(start -3.7846 3.700018)
			(end -5.500116 3.700018)
			(stroke
				(width 0.1524)
				(type default)
			)
			(layer "F.SilkS")
		)
		(fp_line
			(start -5.500116 0.635)
			(end -5.500116 3.700018)
			(stroke
				(width 0.1524)
				(type default)
			)
			(layer "F.SilkS")
		)
		(fp_line
			(start -5.500116 -3.700018)
			(end -4.191 -3.700018)
			(stroke
				(width 0.1524)
				(type default)
			)
			(layer "F.SilkS")
		)
		(fp_line
			(start -5.500116 -3.700018)
			(end -5.500116 -0.635)
			(stroke
				(width 0.1524)
				(type default)
			)
			(layer "F.SilkS")
		)
		(fp_poly
			(pts
				(xy -3.387344 5.3848) (xy -3.946144 6.8072) (xy -2.853944 6.8072)
			)
			(stroke
				(width 0)
				(type default)
			)
			(fill yes)
			(layer "F.SilkS")
		)
		(fp_poly
			(pts
				(arc
					(start -4.064 -0.3302)
					(mid -4.8006 -1.0668)
					(end -5.5372 -0.3302)
				)
				(arc
					(start -5.5372 0.3048)
					(mid -5.314015 0.843615)
					(end -4.7752 1.0668)
				)
				(arc
					(start -4.7752 1.0668)
					(mid -4.272306 0.858494)
					(end -4.064 0.3556)
				)
			)
			(stroke
				(width 0)
				(type default)
			)
			(fill no)
			(layer "B.CrtYd")
		)
		(fp_poly
			(pts
				(arc
					(start 3.7338 0)
					(mid 5.8674 0)
					(end 3.7338 0)
				)
			)
			(stroke
				(width 0)
				(type default)
			)
			(fill no)
			(layer "B.CrtYd")
		)
		(fp_rect
			(start -5.5118 5.1308)
			(end 5.5118 -5.1308)
			(stroke
				(width 0)
				(type default)
			)
			(fill no)
			(layer "F.CrtYd")
		)
		(fp_text user "10"
			(at 5.105146 6.460998 0)
			(unlocked yes)
			(layer "F.SilkS")
			(effects
				(font
					(size 0.7874 0.5842)
					(thickness 0.1524)
				)
				(justify left)
			)
		)
		(fp_text user "11"
			(at 3.292602 -6.421374 90)
			(unlocked yes)
			(layer "F.SilkS")
			(effects
				(font
					(size 0.7874 0.5842)
					(thickness 0.1524)
				)
				(justify left)
			)
		)
		(fp_text user "1"
			(at -3.90525 5.927598 0)
			(unlocked yes)
			(layer "F.SilkS")
			(effects
				(font
					(size 0.7874 0.5842)
					(thickness 0.1524)
				)
				(justify left)
			)
		)
		(fp_text user "20"
			(at -4.073398 -8.377174 90)
			(unlocked yes)
			(layer "F.SilkS")
			(effects
				(font
					(size 0.7874 0.5842)
					(thickness 0.1524)
				)
				(justify left)
			)
		)
		(pad "" np_thru_hole oval
			(at -4.800092 0 180)
			(size 0.9652 1.6002)
			(drill oval 0.9652 1.6002)
			(layers "*.Cu" "*.Mask")
			(clearance 0.381)
			(thermal_gap 0.381)
		)
		(pad "" np_thru_hole circle
			(at 4.800092 0 180)
			(size 1.6002 1.6002)
			(drill 1.6002)
			(layers "*.Cu" "*.Mask")
			(clearance 0.381)
			(thermal_gap 0.381)
		)
		(pad "1" smd oval
			(at -3.400044 4.100068 180)
			(size 0.508 2.032)
			(layers "F.Cu" "F.Mask" "F.Paste")
			(net "GND")
		)
		(pad "2" smd oval
			(at -2.599944 4.100068 180)
			(size 0.508 2.032)
			(layers "F.Cu" "F.Mask" "F.Paste")
			(net "ENET10G_4_TX_FAULT")
		)
		(pad "3" smd oval
			(at -1.800098 4.100068 180)
			(size 0.508 2.032)
			(layers "F.Cu" "F.Mask" "F.Paste")
			(net "ENET10G_4_TX_DIS")
		)
		(pad "4" smd oval
			(at -0.999998 4.100068 180)
			(size 0.508 2.032)
			(layers "F.Cu" "F.Mask" "F.Paste")
			(net "ENET10G_4_SDA")
		)
		(pad "5" smd oval
			(at -0.199898 4.100068 180)
			(size 0.508 2.032)
			(layers "F.Cu" "F.Mask" "F.Paste")
			(net "ENET10G_4_SCL")
		)
		(pad "6" smd oval
			(at 0.599948 4.100068 180)
			(size 0.508 2.032)
			(layers "F.Cu" "F.Mask" "F.Paste")
			(net "ENET10G_4_MOD_DEF0")
		)
		(pad "7" smd oval
			(at 1.400048 4.100068 180)
			(size 0.508 2.032)
			(layers "F.Cu" "F.Mask" "F.Paste")
			(net "ENET10G_4_RS0")
		)
		(pad "8" smd oval
			(at 2.199894 4.100068 180)
			(size 0.508 2.032)
			(layers "F.Cu" "F.Mask" "F.Paste")
			(net "ENET10G_4_LOS")
		)
		(pad "9" smd oval
			(at 2.999994 4.100068 180)
			(size 0.508 2.032)
			(layers "F.Cu" "F.Mask" "F.Paste")
			(net "ENET10G_4_RS1")
		)
		(pad "10" smd oval
			(at 3.800094 4.100068 180)
			(size 0.508 2.032)
			(layers "F.Cu" "F.Mask" "F.Paste")
			(net "GND")
		)
		(pad "11" smd oval
			(at 3.400044 -4.100068 180)
			(size 0.508 2.032)
			(layers "F.Cu" "F.Mask" "F.Paste")
			(net "GND")
		)
		(pad "12" smd oval
			(at 2.599944 -4.100068 180)
			(size 0.508 2.032)
			(layers "F.Cu" "F.Mask" "F.Paste")
			(net "ENET10G_4_RDN")
		)
		(pad "13" smd oval
			(at 1.800098 -4.100068 180)
			(size 0.508 2.032)
			(layers "F.Cu" "F.Mask" "F.Paste")
			(net "ENET10G_4_RDP")
		)
		(pad "14" smd oval
			(at 0.999998 -4.100068 180)
			(size 0.508 2.032)
			(layers "F.Cu" "F.Mask" "F.Paste")
			(net "GND")
		)
		(pad "15" smd oval
			(at 0.199898 -4.100068 180)
			(size 0.508 2.032)
			(layers "F.Cu" "F.Mask" "F.Paste")
			(net "P3V3_10G_4_VCCR")
		)
		(pad "16" smd oval
			(at -0.599948 -4.100068 180)
			(size 0.508 2.032)
			(layers "F.Cu" "F.Mask" "F.Paste")
			(net "P3V3_10G_4_VCCT")
		)
		(pad "17" smd oval
			(at -1.400048 -4.100068 180)
			(size 0.508 2.032)
			(layers "F.Cu" "F.Mask" "F.Paste")
			(net "GND")
		)
		(pad "18" smd oval
			(at -2.199894 -4.100068 180)
			(size 0.508 2.032)
			(layers "F.Cu" "F.Mask" "F.Paste")
			(net "ENET10G_4_TDP")
		)
		(pad "19" smd oval
			(at -2.999994 -4.100068 180)
			(size 0.508 2.032)
			(layers "F.Cu" "F.Mask" "F.Paste")
			(net "ENET10G_4_TDN")
		)
		(pad "20" smd oval
			(at -3.800094 -4.100068 180)
			(size 0.508 2.032)
			(layers "F.Cu" "F.Mask" "F.Paste")
			(net "GND")
		)
		(zone
			(layers "F.Cu" "B.Cu" "In1.Cu" "In2.Cu" "In3.Cu" "In4.Cu" "In5.Cu" "In6.Cu")
			(hatch none 0.5)
			(connect_pads
				(clearance 0)
			)
			(min_thickness 0.25)
			(keepout
				(tracks not_allowed)
				(vias allowed)
				(pads allowed)
				(copperpour not_allowed)
				(footprints allowed)
			)
			(placement
				(enabled no)
				(sheetname "")
			)
			(fill
				(thermal_gap 0.5)
				(thermal_bridge_width 0.5)
				(island_removal_mode 0)
			)
			(polygon
				(pts
					(arc
						(start 330.345288 -15.609316)
						(mid 330.991866 -15.341494)
						(end 331.259688 -14.694916)
					)
					(arc
						(start 331.259688 -14.059916)
						(mid 330.370688 -13.170916)
						(end 329.481688 -14.059916)
					)
					(arc
						(start 329.481688 -14.745716)
						(mid 329.734631 -15.356373)
						(end 330.345288 -15.609316)
					)
				)
			)
		)
		(zone
			(layers "F.Cu" "B.Cu" "In1.Cu" "In2.Cu" "In3.Cu" "In4.Cu" "In5.Cu" "In6.Cu")
			(hatch none 0.5)
			(connect_pads
				(clearance 0)
			)
			(min_thickness 0.25)
			(keepout
				(tracks not_allowed)
				(vias allowed)
				(pads allowed)
				(copperpour not_allowed)
				(footprints allowed)
			)
			(placement
				(enabled no)
				(sheetname "")
			)
			(fill
				(thermal_gap 0.5)
				(thermal_bridge_width 0.5)
				(island_removal_mode 0)
			)
			(polygon
				(pts
					(arc
						(start 321.988688 -14.390116)
						(mid 319.550288 -14.390116)
						(end 321.988688 -14.390116)
					)
				)
			)
		)
	)
	(footprint ""
		(layer "F.Cu")
		(at 28.437332 -16.383 90)
		(property "Reference" "R85"
			(at -3.7846 -0.371348 90)
			(unlocked yes)
			(layer "F.SilkS")
			(effects
				(font
					(size 0.7874 0.5842)
					(thickness 0.1524)
				)
				(justify left)
			)
		)
		(property "Value" ""
			(at 0 0 90)
			(layer "F.Fab")
			(effects
				(font
					(size 1.27 1.27)
				)
			)
		)
		(duplicate_pad_numbers_are_jumpers no)
		(fp_line
			(start 0.7874 -0.4064)
			(end 0.7874 0.4064)
			(stroke
				(width 0.1524)
				(type default)
			)
			(layer "F.SilkS")
		)
		(fp_line
			(start -0.7874 -0.4064)
			(end 0.7874 -0.4064)
			(stroke
				(width 0.1524)
				(type default)
			)
			(layer "F.SilkS")
		)
		(fp_line
			(start 0.7874 0.4064)
			(end -0.7874 0.4064)
			(stroke
				(width 0.1524)
				(type default)
			)
			(layer "F.SilkS")
		)
		(fp_line
			(start -0.7874 0.4064)
			(end -0.7874 -0.4064)
			(stroke
				(width 0.1524)
				(type default)
			)
			(layer "F.SilkS")
		)
		(fp_poly
			(pts
				(xy -0.508 0.2794) (xy -0.508 0.2286) (xy -0.635 0.2286) (xy -0.635 -0.254) (xy -0.5334 -0.254)
				(xy -0.5334 -0.2794) (xy 0.5334 -0.2794) (xy 0.5334 -0.254) (xy 0.635 -0.254) (xy 0.635 0.254) (xy 0.5334 0.254)
				(xy 0.5334 0.2794)
			)
			(stroke
				(width 0)
				(type default)
			)
			(fill no)
			(layer "F.CrtYd")
		)
		(pad "1" smd rect
			(at 0.40005 0 90)
			(size 0.4572 0.508)
			(layers "F.Cu" "F.Mask" "F.Paste")
			(net "N39386877")
		)
		(pad "2" smd rect
			(at -0.40005 0 90)
			(size 0.4572 0.508)
			(layers "F.Cu" "F.Mask" "F.Paste")
			(net "GND")
		)
	)
	(footprint ""
		(layer "F.Cu")
		(at 4.500118 -4.700016 180)
		(property "Reference" "H7"
			(at -8.474964 -0.926084 0)
			(unlocked yes)
			(layer "F.SilkS")
			(effects
				(font
					(size 0.7874 0.5842)
					(thickness 0.1524)
				)
				(justify left)
			)
		)
		(property "Value" ""
			(at 0 0 180)
			(layer "F.Fab")
			(effects
				(font
					(size 1.27 1.27)
				)
			)
		)
		(duplicate_pad_numbers_are_jumpers no)
		(fp_circle
			(center 0 0)
			(end -7.999984 0)
			(stroke
				(width 0.1524)
				(type default)
			)
			(fill no)
			(layer "F.SilkS")
		)
		(fp_arc
			(start 14.5034 0)
			(mid -13.07281 6.291111)
			(end 9.04875 -11.334496)
			(stroke
				(width 0.1524)
				(type default)
			)
			(layer "B.SilkS")
		)
		(fp_arc
			(start 9.463786 -10.990072)
			(mid 13.183363 -6.045203)
			(end 14.5034 0)
			(stroke
				(width 0.1524)
				(type default)
			)
			(layer "B.SilkS")
		)
		(fp_arc
			(start 7.999984 0)
			(mid 7.105874 3.675179)
			(end 4.623308 6.528816)
			(stroke
				(width 0.1524)
				(type default)
			)
			(layer "B.SilkS")
		)
		(fp_arc
			(start -4.623308 6.528816)
			(mid -3.675184 -7.105826)
			(end 7.999984 0)
			(stroke
				(width 0.1524)
				(type default)
			)
			(layer "B.SilkS")
		)
		(fp_poly
			(pts
				(arc
					(start -4.5085 0)
					(mid 4.5085 0)
					(end -4.5085 0)
				)
			)
			(stroke
				(width 0)
				(type default)
			)
			(fill no)
			(layer "F.CrtYd")
		)
		(pad "" np_thru_hole circle
			(at 0 0 180)
			(size 3.6068 3.6068)
			(drill 3.6068)
			(layers "*.Cu" "*.Mask")
			(clearance 0.381)
			(thermal_gap 0.381)
		)
		(pad "2" thru_hole circle
			(at 3.41122 0 180)
			(size 0.762 0.762)
			(drill 0.5588)
			(layers "*.Cu" "*.Mask")
			(remove_unused_layers no)
			(net "GND")
			(clearance 0.1524)
			(thermal_gap 0.1524)
		)
		(pad "3" thru_hole circle
			(at 2.411984 -2.411984 180)
			(size 0.762 0.762)
			(drill 0.5588)
			(layers "*.Cu" "*.Mask")
			(remove_unused_layers no)
			(net "GND")
			(clearance 0.1524)
			(thermal_gap 0.1524)
		)
		(pad "4" thru_hole circle
			(at 0 -3.41122 180)
			(size 0.762 0.762)
			(drill 0.5588)
			(layers "*.Cu" "*.Mask")
			(remove_unused_layers no)
			(net "GND")
			(clearance 0.1524)
			(thermal_gap 0.1524)
		)
		(pad "5" thru_hole circle
			(at -2.411984 -2.411984 180)
			(size 0.762 0.762)
			(drill 0.5588)
			(layers "*.Cu" "*.Mask")
			(remove_unused_layers no)
			(net "GND")
			(clearance 0.1524)
			(thermal_gap 0.1524)
		)
		(pad "6" thru_hole circle
			(at -3.41122 0 180)
			(size 0.762 0.762)
			(drill 0.5588)
			(layers "*.Cu" "*.Mask")
			(remove_unused_layers no)
			(net "GND")
			(clearance 0.1524)
			(thermal_gap 0.1524)
		)
		(pad "7" thru_hole circle
			(at -2.411984 2.411984 180)
			(size 0.762 0.762)
			(drill 0.5588)
			(layers "*.Cu" "*.Mask")
			(remove_unused_layers no)
			(net "GND")
			(clearance 0.1524)
			(thermal_gap 0.1524)
		)
		(pad "8" thru_hole circle
			(at 0 3.41122 180)
			(size 0.762 0.762)
			(drill 0.5588)
			(layers "*.Cu" "*.Mask")
			(remove_unused_layers no)
			(net "GND")
			(clearance 0.1524)
			(thermal_gap 0.1524)
		)
		(pad "9" thru_hole circle
			(at 2.411984 2.411984 180)
			(size 0.762 0.762)
			(drill 0.5588)
			(layers "*.Cu" "*.Mask")
			(remove_unused_layers no)
			(net "GND")
			(clearance 0.1524)
			(thermal_gap 0.1524)
		)
		(zone
			(layer "F.Cu")
			(hatch none 0.5)
			(connect_pads
				(clearance 0)
			)
			(min_thickness 0.25)
			(keepout
				(tracks not_allowed)
				(vias allowed)
				(pads allowed)
				(copperpour not_allowed)
				(footprints allowed)
			)
			(placement
				(enabled no)
				(sheetname "")
			)
			(fill
				(thermal_gap 0.5)
				(thermal_bridge_width 0.5)
				(island_removal_mode 0)
			)
			(polygon
				(pts
					(arc
						(start 4.500118 3.299968)
						(mid -1.156725 0.956827)
						(end -3.499866 -4.700016)
					)
					(arc
						(start -3.499866 -4.700016)
						(mid -1.156725 -10.356859)
						(end 4.500118 -12.7)
					)
					(arc
						(start 4.500118 -9.462516)
						(mid -0.262382 -4.700016)
						(end 4.500118 0.062484)
					)
				)
			)
		)
		(zone
			(layers "F.Cu" "B.Cu" "In1.Cu" "In2.Cu" "In3.Cu" "In4.Cu" "In5.Cu" "In6.Cu")
			(hatch none 0.5)
			(connect_pads
				(clearance 0)
			)
			(min_thickness 0.25)
			(keepout
				(tracks not_allowed)
				(vias allowed)
				(pads allowed)
				(copperpour not_allowed)
				(footprints allowed)
			)
			(placement
				(enabled no)
				(sheetname "")
			)
			(fill
				(thermal_gap 0.5)
				(thermal_bridge_width 0.5)
				(island_removal_mode 0)
			)
			(polygon
				(pts
					(arc
						(start 6.811518 -4.700016)
						(mid 2.188718 -4.700016)
						(end 6.811518 -4.700016)
					)
				)
			)
		)
		(zone
			(layer "B.Cu")
			(hatch none 0.5)
			(connect_pads
				(clearance 0)
			)
			(min_thickness 0.25)
			(keepout
				(tracks not_allowed)
				(vias allowed)
				(pads allowed)
				(copperpour not_allowed)
				(footprints allowed)
			)
			(placement
				(enabled no)
				(sheetname "")
			)
			(fill
				(thermal_gap 0.5)
				(thermal_bridge_width 0.5)
				(island_removal_mode 0)
			)
			(polygon
				(pts
					(arc
						(start 4.500118 -15.225522)
						(mid 1.300094 -13.900028)
						(end -0.0254 -10.700004)
					)
					(arc
						(start -0.0254 -4.700016)
						(mid 1.300094 -1.499992)
						(end 4.500118 -0.174498)
					)
					(arc
						(start 4.500118 0.308102)
						(mid 0.958844 -1.158742)
						(end -0.508 -4.700016)
					)
					(arc
						(start -0.508 -10.700004)
						(mid 0.958934 -14.241114)
						(end 4.500118 -15.707868)
					)
				)
			)
		)
		(zone
			(layer "B.Cu")
			(hatch none 0.5)
			(connect_pads
				(clearance 0)
			)
			(min_thickness 0.25)
			(keepout
				(tracks not_allowed)
				(vias allowed)
				(pads allowed)
				(copperpour not_allowed)
				(footprints allowed)
			)
			(placement
				(enabled no)
				(sheetname "")
			)
			(fill
				(thermal_gap 0.5)
				(thermal_bridge_width 0.5)
				(island_removal_mode 0)
			)
			(polygon
				(pts
					(arc
						(start 4.500118 -15.225522)
						(mid 7.700142 -13.900028)
						(end 9.025636 -10.700004)
					)
					(arc
						(start 9.025636 -4.700016)
						(mid 7.700142 -1.499992)
						(end 4.500118 -0.174498)
					)
					(arc
						(start 4.500118 0.308102)
						(mid 8.041392 -1.158742)
						(end 9.508236 -4.700016)
					)
					(arc
						(start 9.508236 -10.700004)
						(mid 8.041302 -14.241114)
						(end 4.500118 -15.707868)
					)
				)
			)
		)
	)
	(footprint ""
		(layer "F.Cu")
		(at 92.140786 -23.442676 -90)
		(property "Reference" "C4"
			(at -0.561848 5.50672 90)
			(unlocked yes)
			(layer "F.SilkS")
			(effects
				(font
					(size 0.7874 0.5842)
					(thickness 0.1524)
				)
				(justify left)
			)
		)
		(property "Value" ""
			(at 0 0 270)
			(layer "F.Fab")
			(effects
				(font
					(size 1.27 1.27)
				)
			)
		)
		(duplicate_pad_numbers_are_jumpers no)
		(fp_line
			(start -0.7874 0.4064)
			(end -0.7874 -0.4064)
			(stroke
				(width 0.1524)
				(type default)
			)
			(layer "F.SilkS")
		)
		(fp_line
			(start 0.7874 0.4064)
			(end -0.7874 0.4064)
			(stroke
				(width 0.1524)
				(type default)
			)
			(layer "F.SilkS")
		)
		(fp_line
			(start 0 0.381)
			(end 0 -0.381)
			(stroke
				(width 0.1524)
				(type default)
			)
			(layer "F.SilkS")
		)
		(fp_line
			(start -0.7874 -0.4064)
			(end 0.7874 -0.4064)
			(stroke
				(width 0.1524)
				(type default)
			)
			(layer "F.SilkS")
		)
		(fp_line
			(start 0.7874 -0.4064)
			(end 0.7874 0.4064)
			(stroke
				(width 0.1524)
				(type default)
			)
			(layer "F.SilkS")
		)
		(fp_poly
			(pts
				(xy -0.5334 0.254) (xy -0.635 0.254) (xy -0.635 0.2286) (xy -0.635 -0.254) (xy -0.5334 -0.254) (xy -0.5334 -0.2794)
				(xy 0.5334 -0.2794) (xy 0.5334 -0.254) (xy 0.635 -0.254) (xy 0.635 0.254) (xy 0.5334 0.254) (xy 0.5334 0.2794)
				(xy -0.508 0.2794) (xy -0.5334 0.2794)
			)
			(stroke
				(width 0)
				(type default)
			)
			(fill no)
			(layer "F.CrtYd")
		)
		(pad "1" smd rect
			(at 0.40005 0 270)
			(size 0.4572 0.508)
			(layers "F.Cu" "F.Mask" "F.Paste")
			(net "P12V")
		)
		(pad "2" smd rect
			(at -0.40005 0 270)
			(size 0.4572 0.508)
			(layers "F.Cu" "F.Mask" "F.Paste")
			(net "GND")
		)
	)
	(footprint ""
		(layer "F.Cu")
		(at 156.0576 -30.545532 180)
		(property "Reference" "R77"
			(at -33.9598 -19.690334 0)
			(unlocked yes)
			(layer "F.SilkS")
			(effects
				(font
					(size 0.7874 0.5842)
					(thickness 0.1524)
				)
				(justify left)
			)
		)
		(property "Value" ""
			(at 0 0 180)
			(layer "F.Fab")
			(effects
				(font
					(size 1.27 1.27)
				)
			)
		)
		(duplicate_pad_numbers_are_jumpers no)
		(fp_line
			(start 1.905 0.8636)
			(end -1.905 0.8636)
			(stroke
				(width 0.1524)
				(type default)
			)
			(layer "F.SilkS")
		)
		(fp_line
			(start 1.905 -0.8636)
			(end 1.905 0.8636)
			(stroke
				(width 0.1524)
				(type default)
			)
			(layer "F.SilkS")
		)
		(fp_line
			(start -1.905 0.8636)
			(end -1.905 -0.8636)
			(stroke
				(width 0.1524)
				(type default)
			)
			(layer "F.SilkS")
		)
		(fp_line
			(start -1.905 -0.8636)
			(end 1.905 -0.8636)
			(stroke
				(width 0.1524)
				(type default)
			)
			(layer "F.SilkS")
		)
		(fp_poly
			(pts
				(xy 1.524 0.6858) (xy 1.524 -0.6858) (xy 1.524 -0.7366) (xy -1.524 -0.7366) (xy -1.524 -0.6858)
				(xy -1.524 0.6858) (xy -1.524 0.7366) (xy 1.524 0.7366)
			)
			(stroke
				(width 0)
				(type default)
			)
			(fill no)
			(layer "F.CrtYd")
		)
		(pad "1" smd rect
			(at 0.94996 0 180)
			(size 1.1176 1.3716)
			(layers "F.Cu" "F.Mask" "F.Paste")
			(net "P3V3_BLAD1")
		)
		(pad "2" smd rect
			(at -0.94996 0 180)
			(size 1.1176 1.3716)
			(layers "F.Cu" "F.Mask" "F.Paste")
			(net "P3V3_10G_1_VCCR")
		)
	)
	(footprint ""
		(layer "F.Cu")
		(at 338.153248 -25.206706)
		(property "Reference" "R30"
			(at -58.3692 -4.435348 0)
			(unlocked yes)
			(layer "F.SilkS")
			(effects
				(font
					(size 0.7874 0.5842)
					(thickness 0.1524)
				)
				(justify left)
			)
		)
		(property "Value" ""
			(at 0 0 0)
			(layer "F.Fab")
			(effects
				(font
					(size 1.27 1.27)
				)
			)
		)
		(duplicate_pad_numbers_are_jumpers no)
		(fp_line
			(start -0.7874 -0.4064)
			(end 0.7874 -0.4064)
			(stroke
				(width 0.1524)
				(type default)
			)
			(layer "F.SilkS")
		)
		(fp_line
			(start -0.7874 0.4064)
			(end -0.7874 -0.4064)
			(stroke
				(width 0.1524)
				(type default)
			)
			(layer "F.SilkS")
		)
		(fp_line
			(start 0.7874 -0.4064)
			(end 0.7874 0.4064)
			(stroke
				(width 0.1524)
				(type default)
			)
			(layer "F.SilkS")
		)
		(fp_line
			(start 0.7874 0.4064)
			(end -0.7874 0.4064)
			(stroke
				(width 0.1524)
				(type default)
			)
			(layer "F.SilkS")
		)
		(fp_poly
			(pts
				(xy -0.508 0.2794) (xy -0.508 0.2286) (xy -0.635 0.2286) (xy -0.635 -0.254) (xy -0.5334 -0.254)
				(xy -0.5334 -0.2794) (xy 0.5334 -0.2794) (xy 0.5334 -0.254) (xy 0.635 -0.254) (xy 0.635 0.254) (xy 0.5334 0.254)
				(xy 0.5334 0.2794)
			)
			(stroke
				(width 0)
				(type default)
			)
			(fill no)
			(layer "F.CrtYd")
		)
		(pad "1" smd rect
			(at 0.40005 0)
			(size 0.4572 0.508)
			(layers "F.Cu" "F.Mask" "F.Paste")
			(net "P3V3_BLAD2")
		)
		(pad "2" smd rect
			(at -0.40005 0)
			(size 0.4572 0.508)
			(layers "F.Cu" "F.Mask" "F.Paste")
			(net "ENET10G_4_LOS")
		)
	)
	(footprint ""
		(layer "F.Cu")
		(at 181.987952 -33.589976)
		(property "Reference" "U10"
			(at -21.817076 -12.088876 90)
			(unlocked yes)
			(layer "F.SilkS")
			(effects
				(font
					(size 0.7874 0.5842)
					(thickness 0.1524)
				)
				(justify left)
			)
		)
		(property "Value" ""
			(at 0 0 0)
			(layer "F.Fab")
			(effects
				(font
					(size 1.27 1.27)
				)
			)
		)
		(duplicate_pad_numbers_are_jumpers no)
		(fp_line
			(start -20.984972 -16.800068)
			(end 20.984972 -16.800068)
			(stroke
				(width 0.1524)
				(type default)
			)
			(layer "F.SilkS")
		)
		(fp_line
			(start -20.984972 -10.3886)
			(end -20.984972 -10.3124)
			(stroke
				(width 0.1524)
				(type default)
			)
			(layer "F.SilkS")
		)
		(fp_line
			(start -20.984972 -10.3124)
			(end -20.984972 -16.800068)
			(stroke
				(width 0.1524)
				(type default)
			)
			(layer "F.SilkS")
		)
		(fp_line
			(start -20.984972 0)
			(end -20.984972 -7.6962)
			(stroke
				(width 0.1524)
				(type default)
			)
			(layer "F.SilkS")
		)
		(fp_line
			(start -20.984972 4.699)
			(end -20.984972 0)
			(stroke
				(width 0.1524)
				(type default)
			)
			(layer "F.SilkS")
		)
		(fp_line
			(start -20.984972 13.679932)
			(end -20.984972 7.3152)
			(stroke
				(width 0.1524)
				(type default)
			)
			(layer "F.SilkS")
		)
		(fp_line
			(start -18.379948 -12.599924)
			(end -0.635 -12.599924)
			(stroke
				(width 0.1524)
				(type default)
			)
			(layer "F.SilkS")
		)
		(fp_line
			(start -18.379948 -10.4394)
			(end -18.379948 -12.599924)
			(stroke
				(width 0.1524)
				(type default)
			)
			(layer "F.SilkS")
		)
		(fp_line
			(start -18.379948 -1.0668)
			(end -18.379948 -7.5692)
			(stroke
				(width 0.1524)
				(type default)
			)
			(layer "F.SilkS")
		)
		(fp_line
			(start -18.379948 4.5466)
			(end -18.379948 1.0668)
			(stroke
				(width 0.1524)
				(type default)
			)
			(layer "F.SilkS")
		)
		(fp_line
			(start -18.379948 11.569954)
			(end -18.379948 7.4422)
			(stroke
				(width 0.1524)
				(type default)
			)
			(layer "F.SilkS")
		)
		(fp_line
			(start -13.64996 11.569954)
			(end -18.379948 11.569954)
			(stroke
				(width 0.1524)
				(type default)
			)
			(layer "F.SilkS")
		)
		(fp_line
			(start -13.64996 13.679932)
			(end -20.984972 13.679932)
			(stroke
				(width 0.1524)
				(type default)
			)
			(layer "F.SilkS")
		)
		(fp_line
			(start -13.64996 13.679932)
			(end -13.64996 11.569954)
			(stroke
				(width 0.1524)
				(type default)
			)
			(layer "F.SilkS")
		)
		(fp_line
			(start -4.949952 11.569954)
			(end -4.949952 13.679932)
			(stroke
				(width 0.1524)
				(type default)
			)
			(layer "F.SilkS")
		)
		(fp_line
			(start -0.635 -12.599924)
			(end -0.635 11.569954)
			(stroke
				(width 0.1524)
				(type default)
			)
			(layer "F.SilkS")
		)
		(fp_line
			(start -0.635 11.569954)
			(end -4.949952 11.569954)
			(stroke
				(width 0.1524)
				(type default)
			)
			(layer "F.SilkS")
		)
		(fp_line
			(start 0.635 -12.599924)
			(end 18.379948 -12.599924)
			(stroke
				(width 0.1524)
				(type default)
			)
			(layer "F.SilkS")
		)
		(fp_line
			(start 0.635 11.569954)
			(end 0.635 -12.599924)
			(stroke
				(width 0.1524)
				(type default)
			)
			(layer "F.SilkS")
		)
		(fp_line
			(start 5.359908 11.569954)
			(end 0.635 11.569954)
			(stroke
				(width 0.1524)
				(type default)
			)
			(layer "F.SilkS")
		)
		(fp_line
			(start 5.359908 13.679932)
			(end -4.949952 13.679932)
			(stroke
				(width 0.1524)
				(type default)
			)
			(layer "F.SilkS")
		)
		(fp_line
			(start 5.359908 13.679932)
			(end 5.359908 11.569954)
			(stroke
				(width 0.1524)
				(type default)
			)
			(layer "F.SilkS")
		)
		(fp_line
			(start 14.059916 11.569954)
			(end 14.059916 13.679932)
			(stroke
				(width 0.1524)
				(type default)
			)
			(layer "F.SilkS")
		)
		(fp_line
			(start 18.379948 -12.599924)
			(end 18.379948 -10.4394)
			(stroke
				(width 0.1524)
				(type default)
			)
			(layer "F.SilkS")
		)
		(fp_line
			(start 18.379948 -7.5438)
			(end 18.379948 -1.0922)
			(stroke
				(width 0.1524)
				(type default)
			)
			(layer "F.SilkS")
		)
		(fp_line
			(start 18.379948 1.0668)
			(end 18.379948 4.5466)
			(stroke
				(width 0.1524)
				(type default)
			)
			(layer "F.SilkS")
		)
		(fp_line
			(start 18.379948 7.4422)
			(end 18.379948 11.569954)
			(stroke
				(width 0.1524)
				(type default)
			)
			(layer "F.SilkS")
		)
		(fp_line
			(start 18.379948 11.569954)
			(end 14.059916 11.569954)
			(stroke
				(width 0.1524)
				(type default)
			)
			(layer "F.SilkS")
		)
		(fp_line
			(start 20.984972 -16.800068)
			(end 20.984972 -10.3124)
			(stroke
				(width 0.1524)
				(type default)
			)
			(layer "F.SilkS")
		)
		(fp_line
			(start 20.984972 -7.6962)
			(end 20.984972 4.699)
			(stroke
				(width 0.1524)
				(type default)
			)
			(layer "F.SilkS")
		)
		(fp_line
			(start 20.984972 7.3152)
			(end 20.984972 13.679932)
			(stroke
				(width 0.1524)
				(type default)
			)
			(layer "F.SilkS")
		)
		(fp_line
			(start 20.984972 13.679932)
			(end 14.059916 13.679932)
			(stroke
				(width 0.1524)
				(type default)
			)
			(layer "F.SilkS")
		)
		(fp_poly
			(pts
				(xy 11.90498 14.2367) (xy 10.76198 17.6657) (xy 13.04798 17.6657)
			)
			(stroke
				(width 0)
				(type default)
			)
			(fill yes)
			(layer "F.SilkS")
		)
		(fp_poly
			(pts
				(arc
					(start -17.89938 0)
					(mid -20.340828 0)
					(end -17.89938 0)
				)
			)
			(stroke
				(width 0)
				(type default)
			)
			(fill no)
			(layer "B.CrtYd")
		)
		(fp_poly
			(pts
				(arc
					(start 20.334986 0)
					(mid 17.895062 0)
					(end 20.334986 0)
				)
			)
			(stroke
				(width 0)
				(type default)
			)
			(fill no)
			(layer "B.CrtYd")
		)
		(fp_poly
			(pts
				(arc
					(start -17.775682 -8.999982)
					(mid -21.444458 -8.999982)
					(end -17.775682 -8.999982)
				)
			)
			(stroke
				(width 0)
				(type default)
			)
			(fill no)
			(layer "B.CrtYd")
		)
		(fp_poly
			(pts
				(arc
					(start -17.775682 5.999988)
					(mid -21.444458 5.999988)
					(end -17.775682 5.999988)
				)
			)
			(stroke
				(width 0)
				(type default)
			)
			(fill no)
			(layer "B.CrtYd")
		)
		(fp_poly
			(pts
				(arc
					(start 21.444458 -8.999982)
					(mid 17.775682 -8.999982)
					(end 21.444458 -8.999982)
				)
			)
			(stroke
				(width 0)
				(type default)
			)
			(fill no)
			(layer "B.CrtYd")
		)
		(fp_poly
			(pts
				(arc
					(start 21.444458 5.999988)
					(mid 17.775682 5.999988)
					(end 21.444458 5.999988)
				)
			)
			(stroke
				(width 0)
				(type default)
			)
			(fill no)
			(layer "B.CrtYd")
		)
		(fp_poly
			(pts
				(xy -18.3388 -12.573) (xy -18.3388 -10.3886) (xy -17.7292 -10.3886) (xy -17.7292 -7.6708) (xy -18.3388 -7.6708)
				(xy -18.3388 -1.016) (xy -17.8308 -1.016) (xy -17.8308 0.9652) (xy -18.3388 0.9652) (xy -18.3388 4.6228)
				(xy -17.7292 4.6228) (xy -17.7292 7.3406) (xy -18.3388 7.3406) (xy -18.3388 11.5316) (xy -0.6604 11.5316)
				(xy -0.6604 7.3406) (xy -0.6604 4.6228) (xy -0.6604 0.9652) (xy -0.6604 -1.016) (xy -0.6604 -7.6708)
				(xy -0.6604 -10.3886) (xy -0.6604 -12.573)
			)
			(stroke
				(width 0)
				(type default)
			)
			(fill no)
			(layer "F.CrtYd")
		)
		(fp_poly
			(pts
				(xy 0.7112 -12.5984) (xy 0.7112 -10.3632) (xy 0.7112 -7.6454) (xy 0.7112 -0.9906) (xy 0.7112 0.9906)
				(xy 0.7112 4.6482) (xy 0.7112 7.366) (xy 0.7112 11.557) (xy 18.3896 11.557) (xy 18.3896 7.366) (xy 18.3896 7.3406)
				(xy 17.8054 7.3406) (xy 17.8054 4.6482) (xy 17.8308 4.6482) (xy 18.3896 4.6482) (xy 18.3896 0.9906)
				(xy 18.3896 0.9652) (xy 17.9324 0.9652) (xy 17.8816 0.9652) (xy 17.8816 -0.9906) (xy 17.9324 -0.9906)
				(xy 18.3642 -0.9906) (xy 18.3642 -7.6454) (xy 17.8308 -7.6454) (xy 17.8054 -7.6454) (xy 17.8054 -10.3632)
				(xy 17.8308 -10.3632) (xy 18.3642 -10.3632) (xy 18.3642 -12.5984)
			)
			(stroke
				(width 0)
				(type default)
			)
			(fill no)
			(layer "F.CrtYd")
		)
		(fp_poly
			(pts
				(xy -20.984972 0) (xy -20.984972 -7.874) (xy -21.392134 -7.874) (xy -21.392134 -10.1092) (xy -20.984972 -10.1092)
				(xy -20.984972 -16.800068) (xy 20.984972 -16.800068) (xy 20.984972 -10.1092) (xy 21.3868 -10.1092)
				(xy 21.3868 -7.874) (xy 20.984972 -7.874) (xy 20.984972 0) (xy 20.984972 4.9022) (xy 21.3868 4.9022)
				(xy 21.3868 7.112) (xy 20.984972 7.112) (xy 20.984972 13.679932) (xy 9.50468 13.679932) (xy 9.50468 11.569954)
				(xy 18.415 11.569954) (xy 18.408904 7.2898) (xy 17.8308 7.2898) (xy 17.8308 4.699) (xy 17.8562 4.699)
				(xy 18.405094 4.699) (xy 18.399506 0.9144) (xy 17.9324 0.9144) (xy 17.9324 -0.9398) (xy 18.396966 -0.9398)
				(xy 18.38706 -7.7216) (xy 17.8308 -7.7216) (xy 17.8308 -10.2362) (xy 18.383504 -10.2362) (xy 18.383504 -10.2616)
				(xy 18.379948 -12.599924) (xy 0.635 -12.599924) (xy 0.635 11.569954) (xy 9.50214 11.569954) (xy 9.50214 13.679932)
				(xy -9.50214 13.679932) (xy -9.50214 11.569954) (xy -0.635 11.569954) (xy -0.635 -12.599924) (xy -18.379948 -12.599924)
				(xy -18.377662 -10.2616) (xy -17.8308 -10.2616) (xy -17.8308 -7.747) (xy -18.375122 -7.747) (xy -18.375122 -7.7216)
				(xy -18.375122 -0.9144) (xy -17.9324 -0.9144) (xy -17.9324 0.9144) (xy -18.375122 0.9144) (xy -18.375122 4.7498)
				(xy -17.8308 4.7498) (xy -17.8308 7.2644) (xy -18.375122 7.2644) (xy -18.375122 11.569954) (xy -9.50468 11.569954)
				(xy -9.50468 13.679932) (xy -20.984972 13.679932) (xy -20.984972 7.112) (xy -21.392134 7.112) (xy -21.392134 4.8768)
				(xy -20.984972 4.8768)
			)
			(stroke
				(width 0)
				(type default)
			)
			(fill no)
			(layer "F.CrtYd")
		)
		(fp_line
			(start -20.984972 -16.800068)
			(end 20.984972 -16.800068)
			(stroke
				(width 0.1)
				(type default)
			)
			(layer "F.Fab")
		)
		(fp_line
			(start -20.984972 -16.800068)
			(end 20.984972 -16.800068)
			(stroke
				(width 0.1)
				(type default)
			)
			(layer "F.Fab")
		)
		(fp_line
			(start -20.984972 0)
			(end -20.984972 -16.800068)
			(stroke
				(width 0.1)
				(type default)
			)
			(layer "F.Fab")
		)
		(fp_line
			(start -20.984972 0)
			(end -20.984972 -16.800068)
			(stroke
				(width 0.1)
				(type default)
			)
			(layer "F.Fab")
		)
		(fp_line
			(start -20.984972 13.679932)
			(end -20.984972 0)
			(stroke
				(width 0.1)
				(type default)
			)
			(layer "F.Fab")
		)
		(fp_line
			(start -20.984972 13.679932)
			(end -20.984972 0)
			(stroke
				(width 0.1)
				(type default)
			)
			(layer "F.Fab")
		)
		(fp_line
			(start -18.379948 -12.599924)
			(end -0.635 -12.599924)
			(stroke
				(width 0.1)
				(type default)
			)
			(layer "F.Fab")
		)
		(fp_line
			(start -18.379948 11.569954)
			(end -18.379948 -12.599924)
			(stroke
				(width 0.1)
				(type default)
			)
			(layer "F.Fab")
		)
		(fp_line
			(start -13.854938 13.679932)
			(end -20.984972 13.679932)
			(stroke
				(width 0.1)
				(type default)
			)
			(layer "F.Fab")
		)
		(fp_line
			(start -13.64996 11.569954)
			(end -18.379948 11.569954)
			(stroke
				(width 0.1)
				(type default)
			)
			(layer "F.Fab")
		)
		(fp_line
			(start -13.64996 13.679932)
			(end -13.64996 11.569954)
			(stroke
				(width 0.1)
				(type default)
			)
			(layer "F.Fab")
		)
		(fp_line
			(start -4.949952 11.569954)
			(end -4.949952 13.679932)
			(stroke
				(width 0.1)
				(type default)
			)
			(layer "F.Fab")
		)
		(fp_line
			(start -0.635 -12.599924)
			(end -0.635 11.569954)
			(stroke
				(width 0.1)
				(type default)
			)
			(layer "F.Fab")
		)
		(fp_line
			(start -0.635 11.569954)
			(end -4.949952 11.569954)
			(stroke
				(width 0.1)
				(type default)
			)
			(layer "F.Fab")
		)
		(fp_line
			(start 0.635 -12.599924)
			(end 18.379948 -12.599924)
			(stroke
				(width 0.1)
				(type default)
			)
			(layer "F.Fab")
		)
		(fp_line
			(start 0.635 11.569954)
			(end 0.635 -12.599924)
			(stroke
				(width 0.1)
				(type default)
			)
			(layer "F.Fab")
		)
		(fp_line
			(start 5.15493 13.679932)
			(end -5.15493 13.679932)
			(stroke
				(width 0.1)
				(type default)
			)
			(layer "F.Fab")
		)
		(fp_line
			(start 5.359908 11.569954)
			(end 0.635 11.569954)
			(stroke
				(width 0.1)
				(type default)
			)
			(layer "F.Fab")
		)
		(fp_line
			(start 5.359908 13.679932)
			(end 5.359908 11.569954)
			(stroke
				(width 0.1)
				(type default)
			)
			(layer "F.Fab")
		)
		(fp_line
			(start 14.059916 11.569954)
			(end 14.059916 13.679932)
			(stroke
				(width 0.1)
				(type default)
			)
			(layer "F.Fab")
		)
		(fp_line
			(start 18.379948 -12.599924)
			(end 18.379948 11.569954)
			(stroke
				(width 0.1)
				(type default)
			)
			(layer "F.Fab")
		)
		(fp_line
			(start 18.379948 11.569954)
			(end 14.059916 11.569954)
			(stroke
				(width 0.1)
				(type default)
			)
			(layer "F.Fab")
		)
		(fp_line
			(start 20.984972 -16.800068)
			(end 20.984972 13.679932)
			(stroke
				(width 0.1)
				(type default)
			)
			(layer "F.Fab")
		)
		(fp_line
			(start 20.984972 -16.800068)
			(end 20.984972 13.679932)
			(stroke
				(width 0.1)
				(type default)
			)
			(layer "F.Fab")
		)
		(fp_line
			(start 20.984972 13.679932)
			(end -20.984972 13.679932)
			(stroke
				(width 0.1)
				(type default)
			)
			(layer "F.Fab")
		)
		(fp_line
			(start 20.984972 13.679932)
			(end 13.854938 13.679932)
			(stroke
				(width 0.1)
				(type default)
			)
			(layer "F.Fab")
		)
		(fp_poly
			(pts
				(xy 11.90498 14.2367) (xy 10.76198 17.6657) (xy 13.04798 17.6657)
			)
			(stroke
				(width 0)
				(type default)
			)
			(fill yes)
			(layer "F.Fab")
		)
		(fp_text user "G3"
			(at -22.9108 5.908294 0)
			(unlocked yes)
			(layer "F.SilkS")
			(effects
				(font
					(size 0.7874 0.5842)
					(thickness 0.1524)
				)
				(justify left)
			)
		)
		(fp_text user "G1"
			(at -22.7584 -8.99033 0)
			(unlocked yes)
			(layer "F.SilkS")
			(effects
				(font
					(size 0.7874 0.5842)
					(thickness 0.1524)
				)
				(justify left)
			)
		)
		(fp_text user "G2"
			(at -22.5552 1.863852 0)
			(unlocked yes)
			(layer "F.SilkS")
			(effects
				(font
					(size 0.7874 0.5842)
					(thickness 0.1524)
				)
				(justify left)
			)
		)
		(fp_text user "G5"
			(at 21.2344 -0.091948 0)
			(unlocked yes)
			(layer "F.SilkS")
			(effects
				(font
					(size 0.7874 0.5842)
					(thickness 0.1524)
				)
				(justify left)
			)
		)
		(fp_text user "G6"
			(at 21.6662 5.908294 0)
			(unlocked yes)
			(layer "F.SilkS")
			(effects
				(font
					(size 0.7874 0.5842)
					(thickness 0.1524)
				)
				(justify left)
			)
		)
		(fp_text user "G4"
			(at 21.7424 -9.09193 0)
			(unlocked yes)
			(layer "F.SilkS")
			(effects
				(font
					(size 0.7874 0.5842)
					(thickness 0.1524)
				)
				(justify left)
			)
		)
		(fp_text user "G1"
			(at -21.5392 -9.108948 0)
			(unlocked yes)
			(layer "B.SilkS")
			(effects
				(font
					(size 0.7874 0.5842)
					(thickness 0.1524)
				)
				(justify left mirror)
			)
		)
		(fp_text user "G3"
			(at -21.5138 5.908294 0)
			(unlocked yes)
			(layer "B.SilkS")
			(effects
				(font
					(size 0.7874 0.5842)
					(thickness 0.1524)
				)
				(justify left mirror)
			)
		)
		(fp_text user "G2"
			(at -20.4216 -0.091948 0)
			(unlocked yes)
			(layer "B.SilkS")
			(effects
				(font
					(size 0.7874 0.5842)
					(thickness 0.1524)
				)
				(justify left mirror)
			)
		)
		(fp_text user "G5"
			(at 21.8948 -0.091948 0)
			(unlocked yes)
			(layer "B.SilkS")
			(effects
				(font
					(size 0.7874 0.5842)
					(thickness 0.1524)
				)
				(justify left mirror)
			)
		)
		(fp_text user "G4"
			(at 22.8346 -9.09193 0)
			(unlocked yes)
			(layer "B.SilkS")
			(effects
				(font
					(size 0.7874 0.5842)
					(thickness 0.1524)
				)
				(justify left mirror)
			)
		)
		(fp_text user "G6"
			(at 23.0886 5.908294 0)
			(unlocked yes)
			(layer "B.SilkS")
			(effects
				(font
					(size 0.7874 0.5842)
					(thickness 0.1524)
				)
				(justify left mirror)
			)
		)
		(fp_text user "G1"
			(at -21.5392 -9.108948 0)
			(unlocked yes)
			(layer "B.Fab")
			(effects
				(font
					(size 0.7874 0.5842)
					(thickness 0.000001)
				)
				(justify left mirror)
			)
		)
		(fp_text user "G3"
			(at -21.5138 5.908294 0)
			(unlocked yes)
			(layer "B.Fab")
			(effects
				(font
					(size 0.7874 0.5842)
					(thickness 0.000001)
				)
				(justify left mirror)
			)
		)
		(fp_text user "G2"
			(at -20.4216 -0.091948 0)
			(unlocked yes)
			(layer "B.Fab")
			(effects
				(font
					(size 0.7874 0.5842)
					(thickness 0.000001)
				)
				(justify left mirror)
			)
		)
		(fp_text user "G5"
			(at 21.8948 -0.091948 0)
			(unlocked yes)
			(layer "B.Fab")
			(effects
				(font
					(size 0.7874 0.5842)
					(thickness 0.000001)
				)
				(justify left mirror)
			)
		)
		(fp_text user "G4"
			(at 22.8346 -9.09193 0)
			(unlocked yes)
			(layer "B.Fab")
			(effects
				(font
					(size 0.7874 0.5842)
					(thickness 0.000001)
				)
				(justify left mirror)
			)
		)
		(fp_text user "G6"
			(at 23.0886 5.908294 0)
			(unlocked yes)
			(layer "B.Fab")
			(effects
				(font
					(size 0.7874 0.5842)
					(thickness 0.000001)
				)
				(justify left mirror)
			)
		)
		(fp_text user "G3"
			(at -22.9108 5.908294 0)
			(unlocked yes)
			(layer "F.Fab")
			(effects
				(font
					(size 0.7874 0.5842)
					(thickness 0.000001)
				)
				(justify left)
			)
		)
		(fp_text user "G1"
			(at -22.7076 -9.09193 0)
			(unlocked yes)
			(layer "F.Fab")
			(effects
				(font
					(size 0.7874 0.5842)
					(thickness 0.000001)
				)
				(justify left)
			)
		)
		(fp_text user "G2"
			(at -22.5806 -0.091948 0)
			(unlocked yes)
			(layer "F.Fab")
			(effects
				(font
					(size 0.7874 0.5842)
					(thickness 0.000001)
				)
				(justify left)
			)
		)
		(fp_text user "G5"
			(at 21.2344 -0.091948 0)
			(unlocked yes)
			(layer "F.Fab")
			(effects
				(font
					(size 0.7874 0.5842)
					(thickness 0.000001)
				)
				(justify left)
			)
		)
		(fp_text user "G6"
			(at 21.6662 5.908294 0)
			(unlocked yes)
			(layer "F.Fab")
			(effects
				(font
					(size 0.7874 0.5842)
					(thickness 0.000001)
				)
				(justify left)
			)
		)
		(fp_text user "G4"
			(at 21.7424 -9.09193 0)
			(unlocked yes)
			(layer "F.Fab")
			(effects
				(font
					(size 0.7874 0.5842)
					(thickness 0.000001)
				)
				(justify left)
			)
		)
		(pad "A1" smd rect
			(at 12.109958 12.62507)
			(size 0.9144 2.1336)
			(layers "F.Cu" "F.Mask" "F.Paste")
			(net "GND")
		)
		(pad "A2" smd rect
			(at 9.709912 12.62507)
			(size 0.9144 2.1336)
			(layers "F.Cu" "F.Mask" "F.Paste")
			(net "GND")
		)
		(pad "A3" smd rect
			(at 7.31012 12.62507)
			(size 0.9144 2.1336)
			(layers "F.Cu" "F.Mask" "F.Paste")
			(net "GND")
		)
		(pad "B1" smd rect
			(at -6.89991 12.62507)
			(size 0.9144 2.1336)
			(layers "F.Cu" "F.Mask" "F.Paste")
			(net "GND")
		)
		(pad "B2" smd rect
			(at -9.299956 12.62507)
			(size 0.9144 2.1336)
			(layers "F.Cu" "F.Mask" "F.Paste")
			(net "GND")
		)
		(pad "B3" smd rect
			(at -11.700002 12.62507)
			(size 0.9144 2.1336)
			(layers "F.Cu" "F.Mask" "F.Paste")
			(net "GND")
		)
		(pad "G1" thru_hole circle
			(at -19.61007 -8.999982)
			(size 3.5306 3.5306)
			(drill 2.5146)
			(layers "*.Cu" "*.Mask")
			(remove_unused_layers no)
			(net "GND")
			(clearance -0.254)
		)
		(pad "G2" thru_hole circle
			(at -19.120104 0)
			(size 2.3368 2.3368)
			(drill 1.5748)
			(layers "*.Cu" "*.Mask")
			(remove_unused_layers no)
			(net "GND")
			(clearance -0.127)
		)
		(pad "G3" thru_hole circle
			(at -19.61007 5.999988)
			(size 3.5306 3.5306)
			(drill 2.5146)
			(layers "*.Cu" "*.Mask")
			(remove_unused_layers no)
			(net "GND")
			(clearance -0.254)
		)
		(pad "G4" thru_hole circle
			(at 19.61007 -8.999982)
			(size 3.5306 3.5306)
			(drill 2.5146)
			(layers "*.Cu" "*.Mask")
			(remove_unused_layers no)
			(net "GND")
			(clearance -0.254)
		)
		(pad "G5" thru_hole circle
			(at 19.120104 0)
			(size 2.3368 2.3368)
			(drill 1.5748)
			(layers "*.Cu" "*.Mask")
			(remove_unused_layers no)
			(net "GND")
			(clearance -0.127)
		)
		(pad "G6" thru_hole circle
			(at 19.61007 5.999988)
			(size 3.5306 3.5306)
			(drill 2.5146)
			(layers "*.Cu" "*.Mask")
			(remove_unused_layers no)
			(net "GND")
			(clearance -0.254)
		)
	)
	(footprint ""
		(layer "F.Cu")
		(at 379.9332 -35.433 90)
		(property "Reference" "L5"
			(at -21.4376 33.47847 90)
			(unlocked yes)
			(layer "F.SilkS")
			(effects
				(font
					(size 0.7874 0.5842)
					(thickness 0.1524)
				)
				(justify left)
			)
		)
		(property "Value" ""
			(at 0 0 90)
			(layer "F.Fab")
			(effects
				(font
					(size 1.27 1.27)
				)
			)
		)
		(duplicate_pad_numbers_are_jumpers no)
		(fp_line
			(start -1.905 -0.8636)
			(end 1.905 -0.8636)
			(stroke
				(width 0.1524)
				(type default)
			)
			(layer "F.SilkS")
		)
		(fp_line
			(start 1.905 0.8382)
			(end 1.905 -0.8382)
			(stroke
				(width 0.1524)
				(type default)
			)
			(layer "F.SilkS")
		)
		(fp_line
			(start 0.127 0.8382)
			(end 0.127 -0.8382)
			(stroke
				(width 0.1524)
				(type default)
			)
			(layer "F.SilkS")
		)
		(fp_line
			(start -0.127 0.8382)
			(end -0.127 -0.8382)
			(stroke
				(width 0.1524)
				(type default)
			)
			(layer "F.SilkS")
		)
		(fp_line
			(start -1.905 0.8382)
			(end -1.905 -0.8382)
			(stroke
				(width 0.1524)
				(type default)
			)
			(layer "F.SilkS")
		)
		(fp_line
			(start 1.905 0.8636)
			(end -1.905 0.8636)
			(stroke
				(width 0.1524)
				(type default)
			)
			(layer "F.SilkS")
		)
		(fp_rect
			(start -1.524 0.7112)
			(end 1.524 -0.7366)
			(stroke
				(width 0)
				(type default)
			)
			(fill no)
			(layer "F.CrtYd")
		)
		(pad "1" smd rect
			(at 0.94996 0 90)
			(size 1.1176 1.3716)
			(layers "F.Cu" "F.Mask" "F.Paste")
			(net "P3V3_10G_3_VCCT_L")
		)
		(pad "2" smd rect
			(at -0.94996 0 90)
			(size 1.1176 1.3716)
			(layers "F.Cu" "F.Mask" "F.Paste")
			(net "P3V3_10G_3_VCCT")
		)
	)
	(footprint ""
		(layer "F.Cu")
		(at 351.208848 -25.440894 180)
		(property "Reference" "R23"
			(at 58.940192 4.22656 0)
			(unlocked yes)
			(layer "F.SilkS")
			(effects
				(font
					(size 0.7874 0.5842)
					(thickness 0.1524)
				)
				(justify left)
			)
		)
		(property "Value" ""
			(at 0 0 180)
			(layer "F.Fab")
			(effects
				(font
					(size 1.27 1.27)
				)
			)
		)
		(duplicate_pad_numbers_are_jumpers no)
		(fp_line
			(start 0.7874 0.4064)
			(end -0.7874 0.4064)
			(stroke
				(width 0.1524)
				(type default)
			)
			(layer "F.SilkS")
		)
		(fp_line
			(start 0.7874 -0.4064)
			(end 0.7874 0.4064)
			(stroke
				(width 0.1524)
				(type default)
			)
			(layer "F.SilkS")
		)
		(fp_line
			(start -0.7874 0.4064)
			(end -0.7874 -0.4064)
			(stroke
				(width 0.1524)
				(type default)
			)
			(layer "F.SilkS")
		)
		(fp_line
			(start -0.7874 -0.4064)
			(end 0.7874 -0.4064)
			(stroke
				(width 0.1524)
				(type default)
			)
			(layer "F.SilkS")
		)
		(fp_poly
			(pts
				(xy -0.508 0.2794) (xy -0.508 0.2286) (xy -0.635 0.2286) (xy -0.635 -0.254) (xy -0.5334 -0.254)
				(xy -0.5334 -0.2794) (xy 0.5334 -0.2794) (xy 0.5334 -0.254) (xy 0.635 -0.254) (xy 0.635 0.254) (xy 0.5334 0.254)
				(xy 0.5334 0.2794)
			)
			(stroke
				(width 0)
				(type default)
			)
			(fill no)
			(layer "F.CrtYd")
		)
		(pad "1" smd rect
			(at 0.40005 0 180)
			(size 0.4572 0.508)
			(layers "F.Cu" "F.Mask" "F.Paste")
			(net "P3V3_BLAD2")
		)
		(pad "2" smd rect
			(at -0.40005 0 180)
			(size 0.4572 0.508)
			(layers "F.Cu" "F.Mask" "F.Paste")
			(net "ENET10G_3_SCL")
		)
	)
	(footprint ""
		(layer "F.Cu")
		(at 344.535252 -44.8691 180)
		(property "Reference" "J23"
			(at 1.111504 -18.424652 0)
			(unlocked yes)
			(layer "F.SilkS")
			(effects
				(font
					(size 0.7874 0.5842)
					(thickness 0.1524)
				)
				(justify left)
			)
		)
		(property "Value" ""
			(at 0 0 180)
			(layer "F.Fab")
			(effects
				(font
					(size 1.27 1.27)
				)
			)
		)
		(duplicate_pad_numbers_are_jumpers no)
		(fp_line
			(start 9.655048 10.80008)
			(end 9.655048 6.1976)
			(stroke
				(width 0.1524)
				(type default)
			)
			(layer "F.SilkS")
		)
		(fp_line
			(start 9.655048 2.9718)
			(end 9.655048 -9.9822)
			(stroke
				(width 0.1524)
				(type default)
			)
			(layer "F.SilkS")
		)
		(fp_line
			(start 9.655048 -12.827)
			(end 9.655048 -17.649952)
			(stroke
				(width 0.1524)
				(type default)
			)
			(layer "F.SilkS")
		)
		(fp_line
			(start 9.655048 -17.649952)
			(end -9.655048 -17.649952)
			(stroke
				(width 0.1524)
				(type default)
			)
			(layer "F.SilkS")
		)
		(fp_line
			(start -9.655048 10.80008)
			(end 9.655048 10.80008)
			(stroke
				(width 0.1524)
				(type default)
			)
			(layer "F.SilkS")
		)
		(fp_line
			(start -9.655048 5.969)
			(end -9.655048 10.80008)
			(stroke
				(width 0.1524)
				(type default)
			)
			(layer "F.SilkS")
		)
		(fp_line
			(start -9.655048 0)
			(end -9.655048 3.1496)
			(stroke
				(width 0.1524)
				(type default)
			)
			(layer "F.SilkS")
		)
		(fp_line
			(start -9.655048 -17.649952)
			(end -9.655556 -16.722344)
			(stroke
				(width 0.1524)
				(type default)
			)
			(layer "F.SilkS")
		)
		(fp_line
			(start -9.656826 -14.280642)
			(end -9.663684 -0.70612)
			(stroke
				(width 0.1524)
				(type default)
			)
			(layer "F.SilkS")
		)
		(fp_line
			(start -9.663684 -0.70612)
			(end -9.655048 0)
			(stroke
				(width 0.1524)
				(type default)
			)
			(layer "F.SilkS")
		)
		(fp_poly
			(pts
				(xy -9.3599 -6.4389) (xy -11.4681 -7.0739) (xy -11.4681 -5.8293)
			)
			(stroke
				(width 0)
				(type default)
			)
			(fill yes)
			(layer "F.SilkS")
		)
		(fp_poly
			(pts
				(xy -3.9116 -9.6139) (xy -3.9116 -8.1788) (xy 5.1816 -8.1788) (xy 5.1816 -9.6139)
			)
			(stroke
				(width 0)
				(type default)
			)
			(fill no)
			(layer "B.CrtYd")
		)
		(fp_poly
			(pts
				(xy -3.9116 -16.2052) (xy -3.9116 -14.7701) (xy 5.1562 -14.7701) (xy 5.1562 -16.2052)
			)
			(stroke
				(width 0)
				(type default)
			)
			(fill no)
			(layer "B.CrtYd")
		)
		(fp_poly
			(pts
				(xy -5.1816 -7.0993) (xy -5.1816 -5.6388) (xy 3.9116 -5.6388) (xy 3.9116 -7.0993)
			)
			(stroke
				(width 0)
				(type default)
			)
			(fill no)
			(layer "B.CrtYd")
		)
		(fp_poly
			(pts
				(xy -5.1816 -13.6652) (xy -5.1816 -12.2428) (xy 3.9116 -12.2428) (xy 3.9116 -13.6652)
			)
			(stroke
				(width 0)
				(type default)
			)
			(fill no)
			(layer "B.CrtYd")
		)
		(fp_poly
			(pts
				(arc
					(start 6.931406 4.569968)
					(mid 10.078466 4.569968)
					(end 6.931406 4.569968)
				)
			)
			(stroke
				(width 0)
				(type default)
			)
			(fill no)
			(layer "B.CrtYd")
		)
		(fp_poly
			(pts
				(arc
					(start 6.928104 -11.43)
					(mid 10.081768 -11.43)
					(end 6.928104 -11.43)
				)
			)
			(stroke
				(width 0)
				(type default)
			)
			(fill no)
			(layer "B.CrtYd")
		)
		(fp_poly
			(pts
				(arc
					(start 6.167628 -5.839968)
					(mid 9.322308 -5.839968)
					(end 6.167628 -5.839968)
				)
			)
			(stroke
				(width 0)
				(type default)
			)
			(fill no)
			(layer "B.CrtYd")
		)
		(fp_poly
			(pts
				(arc
					(start -9.320784 -9.139936)
					(mid -6.169152 -9.139936)
					(end -9.320784 -9.139936)
				)
			)
			(stroke
				(width 0)
				(type default)
			)
			(fill no)
			(layer "B.CrtYd")
		)
		(fp_poly
			(pts
				(arc
					(start -10.076434 4.569968)
					(mid -6.933438 4.569968)
					(end -10.076434 4.569968)
				)
			)
			(stroke
				(width 0)
				(type default)
			)
			(fill no)
			(layer "B.CrtYd")
		)
		(fp_poly
			(pts
				(arc
					(start -10.080498 -15.489936)
					(mid -6.929374 -15.489936)
					(end -10.080498 -15.489936)
				)
			)
			(stroke
				(width 0)
				(type default)
			)
			(fill no)
			(layer "B.CrtYd")
		)
		(fp_poly
			(pts
				(arc
					(start 3.838194 0)
					(mid 7.591806 0)
					(end 3.838194 0)
				)
			)
			(stroke
				(width 0)
				(type default)
			)
			(fill no)
			(layer "B.CrtYd")
		)
		(fp_poly
			(pts
				(arc
					(start -7.590028 0)
					(mid -3.839972 0)
					(end -7.590028 0)
				)
			)
			(stroke
				(width 0)
				(type default)
			)
			(fill no)
			(layer "B.CrtYd")
		)
		(fp_poly
			(pts
				(xy -9.655048 0) (xy -9.655048 10.80008) (xy 9.655048 10.80008) (xy 9.655048 -17.649952) (xy -9.655048 -17.649952)
				(xy -9.663684 -0.70612)
			)
			(stroke
				(width 0)
				(type default)
			)
			(fill no)
			(layer "F.CrtYd")
		)
		(fp_text user "B2"
			(at 10.244836 -14.285976 90)
			(unlocked yes)
			(layer "F.SilkS")
			(effects
				(font
					(size 0.7874 0.5842)
					(thickness 0.1524)
				)
				(justify left)
			)
		)
		(fp_text user "A7"
			(at 10.223246 -6.767576 90)
			(unlocked yes)
			(layer "F.SilkS")
			(effects
				(font
					(size 0.7874 0.5842)
					(thickness 0.1524)
				)
				(justify left)
			)
		)
		(fp_text user "A8"
			(at 10.223246 -9.993376 90)
			(unlocked yes)
			(layer "F.SilkS")
			(effects
				(font
					(size 0.7874 0.5842)
					(thickness 0.1524)
				)
				(justify left)
			)
		)
		(fp_text user "B1"
			(at 10.219436 -16.825976 90)
			(unlocked yes)
			(layer "F.SilkS")
			(effects
				(font
					(size 0.7874 0.5842)
					(thickness 0.1524)
				)
				(justify left)
			)
		)
		(fp_text user "A1"
			(at -10.1981 -5.788152 90)
			(unlocked yes)
			(layer "F.SilkS")
			(effects
				(font
					(size 0.7874 0.5842)
					(thickness 0.1524)
				)
				(justify left)
			)
		)
		(fp_text user "A2"
			(at -10.2743 -9.877552 90)
			(unlocked yes)
			(layer "F.SilkS")
			(effects
				(font
					(size 0.7874 0.5842)
					(thickness 0.1524)
				)
				(justify left)
			)
		)
		(fp_text user "B7"
			(at -10.2997 -18.132552 90)
			(unlocked yes)
			(layer "F.SilkS")
			(effects
				(font
					(size 0.7874 0.5842)
					(thickness 0.1524)
				)
				(justify left)
			)
		)
		(fp_text user "B8"
			(at -10.3251 -13.560552 90)
			(unlocked yes)
			(layer "F.SilkS")
			(effects
				(font
					(size 0.7874 0.5842)
					(thickness 0.1524)
				)
				(justify left)
			)
		)
		(fp_text user "A8"
			(at 5.601716 -8.899906 0)
			(unlocked yes)
			(layer "B.SilkS")
			(effects
				(font
					(size 0.7874 0.5842)
					(thickness 0.1524)
				)
				(justify left mirror)
			)
		)
		(fp_text user "B1"
			(at 5.525516 -15.507716 0)
			(unlocked yes)
			(layer "B.SilkS")
			(effects
				(font
					(size 0.7874 0.5842)
					(thickness 0.1524)
				)
				(justify left mirror)
			)
		)
		(fp_text user "B2"
			(at 4.696714 -13.018516 0)
			(unlocked yes)
			(layer "B.SilkS")
			(effects
				(font
					(size 0.7874 0.5842)
					(thickness 0.1524)
				)
				(justify left mirror)
			)
		)
		(fp_text user "A7"
			(at 4.468114 -6.4897 0)
			(unlocked yes)
			(layer "B.SilkS")
			(effects
				(font
					(size 0.7874 0.5842)
					(thickness 0.1524)
				)
				(justify left mirror)
			)
		)
		(fp_text user "A2"
			(at -5.597906 -8.855202 0)
			(unlocked yes)
			(layer "B.SilkS")
			(effects
				(font
					(size 0.7874 0.5842)
					(thickness 0.1524)
				)
				(justify left mirror)
			)
		)
		(fp_text user "B7"
			(at -5.674106 -15.685516 0)
			(unlocked yes)
			(layer "B.SilkS")
			(effects
				(font
					(size 0.7874 0.5842)
					(thickness 0.1524)
				)
				(justify left mirror)
			)
		)
		(fp_text user "B8"
			(at -6.782308 -12.942316 0)
			(unlocked yes)
			(layer "B.SilkS")
			(effects
				(font
					(size 0.7874 0.5842)
					(thickness 0.1524)
				)
				(justify left mirror)
			)
		)
		(fp_text user "A1"
			(at -6.909308 -6.309106 0)
			(unlocked yes)
			(layer "B.SilkS")
			(effects
				(font
					(size 0.7874 0.5842)
					(thickness 0.1524)
				)
				(justify left mirror)
			)
		)
		(pad "" np_thru_hole circle
			(at -5.715 0 180)
			(size 3.2512 3.2512)
			(drill 3.2512)
			(layers "*.Cu" "*.Mask")
			(clearance 0.381)
			(thermal_gap 0.381)
		)
		(pad "" np_thru_hole circle
			(at 5.715 0 180)
			(size 3.2512 3.2512)
			(drill 3.2512)
			(layers "*.Cu" "*.Mask")
			(clearance 0.381)
			(thermal_gap 0.381)
		)
		(pad "A1" thru_hole rect
			(at -4.445 -6.35 180)
			(size 1.2954 1.2954)
			(drill 0.889)
			(layers "*.Cu" "*.Mask")
			(remove_unused_layers no)
			(net "ENET1G_3_MDI0P")
			(clearance 0.0508)
			(thermal_gap 0.0508)
			(padstack
				(mode front_inner_back)
				(layer "Inner"
					(shape circle)
					(size 1.2954 1.2954)
					(clearance 0.0508)
				)
				(layer "B.Cu"
					(shape rect)
					(size 1.2954 1.2954)
					(clearance 0.0508)
				)
			)
		)
		(pad "A2" thru_hole circle
			(at -3.175 -8.89 180)
			(size 1.2954 1.2954)
			(drill 0.889)
			(layers "*.Cu" "*.Mask")
			(remove_unused_layers no)
			(net "ENET1G_3_MDI0N")
			(clearance 0.0508)
			(thermal_gap 0.0508)
		)
		(pad "A3" thru_hole circle
			(at -1.905 -6.35 180)
			(size 1.2954 1.2954)
			(drill 0.889)
			(layers "*.Cu" "*.Mask")
			(remove_unused_layers no)
			(net "ENET1G_3_MDI1P")
			(clearance 0.0508)
			(thermal_gap 0.0508)
		)
		(pad "A4" thru_hole circle
			(at -0.635 -8.89 180)
			(size 1.2954 1.2954)
			(drill 0.889)
			(layers "*.Cu" "*.Mask")
			(remove_unused_layers no)
			(net "ENET1G_3_MDI2P")
			(clearance 0.0508)
			(thermal_gap 0.0508)
		)
		(pad "A5" thru_hole circle
			(at 0.635 -6.35 180)
			(size 1.2954 1.2954)
			(drill 0.889)
			(layers "*.Cu" "*.Mask")
			(remove_unused_layers no)
			(net "ENET1G_3_MDI2N")
			(clearance 0.0508)
			(thermal_gap 0.0508)
		)
		(pad "A6" thru_hole circle
			(at 1.905 -8.89 180)
			(size 1.2954 1.2954)
			(drill 0.889)
			(layers "*.Cu" "*.Mask")
			(remove_unused_layers no)
			(net "ENET1G_3_MDI1N")
			(clearance 0.0508)
			(thermal_gap 0.0508)
		)
		(pad "A7" thru_hole circle
			(at 3.175 -6.35 180)
			(size 1.2954 1.2954)
			(drill 0.889)
			(layers "*.Cu" "*.Mask")
			(remove_unused_layers no)
			(net "ENET1G_3_MDI3P")
			(clearance 0.0508)
			(thermal_gap 0.0508)
		)
		(pad "A8" thru_hole circle
			(at 4.445 -8.89 180)
			(size 1.2954 1.2954)
			(drill 0.889)
			(layers "*.Cu" "*.Mask")
			(remove_unused_layers no)
			(net "ENET1G_3_MDI3N")
			(clearance 0.0508)
			(thermal_gap 0.0508)
		)
		(pad "B1" thru_hole circle
			(at 4.445 -15.489936 180)
			(size 1.2954 1.2954)
			(drill 0.889)
			(layers "*.Cu" "*.Mask")
			(remove_unused_layers no)
			(net "ENET1G_4_MDI0P")
			(clearance 0.0508)
			(thermal_gap 0.0508)
		)
		(pad "B2" thru_hole circle
			(at 3.175 -12.949936 180)
			(size 1.2954 1.2954)
			(drill 0.889)
			(layers "*.Cu" "*.Mask")
			(remove_unused_layers no)
			(net "ENET1G_4_MDI0N")
			(clearance 0.0508)
			(thermal_gap 0.0508)
		)
		(pad "B3" thru_hole circle
			(at 1.905 -15.489936 180)
			(size 1.2954 1.2954)
			(drill 0.889)
			(layers "*.Cu" "*.Mask")
			(remove_unused_layers no)
			(net "ENET1G_4_MDI1P")
			(clearance 0.0508)
			(thermal_gap 0.0508)
		)
		(pad "B4" thru_hole circle
			(at 0.635 -12.949936 180)
			(size 1.2954 1.2954)
			(drill 0.889)
			(layers "*.Cu" "*.Mask")
			(remove_unused_layers no)
			(net "ENET1G_4_MDI2P")
			(clearance 0.0508)
			(thermal_gap 0.0508)
		)
		(pad "B5" thru_hole circle
			(at -0.635 -15.489936 180)
			(size 1.2954 1.2954)
			(drill 0.889)
			(layers "*.Cu" "*.Mask")
			(remove_unused_layers no)
			(net "ENET1G_4_MDI2N")
			(clearance 0.0508)
			(thermal_gap 0.0508)
		)
		(pad "B6" thru_hole circle
			(at -1.905 -12.949936 180)
			(size 1.2954 1.2954)
			(drill 0.889)
			(layers "*.Cu" "*.Mask")
			(remove_unused_layers no)
			(net "ENET1G_4_MDI1N")
			(clearance 0.0508)
			(thermal_gap 0.0508)
		)
		(pad "B7" thru_hole circle
			(at -3.175 -15.489936 180)
			(size 1.2954 1.2954)
			(drill 0.889)
			(layers "*.Cu" "*.Mask")
			(remove_unused_layers no)
			(net "ENET1G_4_MDI3P")
			(clearance 0.0508)
			(thermal_gap 0.0508)
		)
		(pad "B8" thru_hole circle
			(at -4.445 -12.949936 180)
			(size 1.2954 1.2954)
			(drill 0.889)
			(layers "*.Cu" "*.Mask")
			(remove_unused_layers no)
			(net "ENET1G_4_MDI3N")
			(clearance 0.0508)
			(thermal_gap 0.0508)
		)
		(pad "G1" thru_hole circle
			(at -8.504936 -15.489936 180)
			(size 3.048 3.048)
			(drill 2.032)
			(layers "*.Cu" "*.Mask")
			(remove_unused_layers no)
			(net "GND")
			(clearance -0.254)
		)
		(pad "G2" thru_hole circle
			(at -7.744968 -9.139936 180)
			(size 3.048 3.048)
			(drill 2.032)
			(layers "*.Cu" "*.Mask")
			(remove_unused_layers no)
			(net "GND")
			(clearance -0.254)
		)
		(pad "G3" thru_hole circle
			(at -8.504936 4.569968 180)
			(size 3.048 3.048)
			(drill 2.032)
			(layers "*.Cu" "*.Mask")
			(remove_unused_layers no)
			(net "GND")
			(clearance -0.254)
		)
		(pad "G4" thru_hole circle
			(at 8.504936 4.569968 180)
			(size 3.048 3.048)
			(drill 2.032)
			(layers "*.Cu" "*.Mask")
			(remove_unused_layers no)
			(net "GND")
			(clearance -0.254)
		)
		(pad "G5" thru_hole circle
			(at 7.744968 -5.839968 180)
			(size 3.048 3.048)
			(drill 2.032)
			(layers "*.Cu" "*.Mask")
			(remove_unused_layers no)
			(net "GND")
			(clearance -0.254)
		)
		(pad "G6" thru_hole circle
			(at 8.504936 -11.43 180)
			(size 3.048 3.048)
			(drill 2.032)
			(layers "*.Cu" "*.Mask")
			(remove_unused_layers no)
			(net "GND")
			(clearance -0.254)
		)
		(zone
			(layers "F.Cu" "B.Cu" "In1.Cu" "In2.Cu" "In3.Cu" "In4.Cu" "In5.Cu" "In6.Cu")
			(hatch none 0.5)
			(connect_pads
				(clearance 0)
			)
			(min_thickness 0.25)
			(keepout
				(tracks not_allowed)
				(vias allowed)
				(pads allowed)
				(copperpour not_allowed)
				(footprints allowed)
			)
			(placement
				(enabled no)
				(sheetname "")
			)
			(fill
				(thermal_gap 0.5)
				(thermal_bridge_width 0.5)
				(island_removal_mode 0)
			)
			(polygon
				(pts
					(arc
						(start 340.854538 -44.8691)
						(mid 336.785966 -44.8691)
						(end 340.854538 -44.8691)
					)
				)
			)
		)
		(zone
			(layers "F.Cu" "B.Cu" "In1.Cu" "In2.Cu" "In3.Cu" "In4.Cu" "In5.Cu" "In6.Cu")
			(hatch none 0.5)
			(connect_pads
				(clearance 0)
			)
			(min_thickness 0.25)
			(keepout
				(tracks not_allowed)
				(vias allowed)
				(pads allowed)
				(copperpour not_allowed)
				(footprints allowed)
			)
			(placement
				(enabled no)
				(sheetname "")
			)
			(fill
				(thermal_gap 0.5)
				(thermal_bridge_width 0.5)
				(island_removal_mode 0)
			)
			(polygon
				(pts
					(arc
						(start 352.28276 -44.8691)
						(mid 348.217744 -44.8691)
						(end 352.28276 -44.8691)
					)
				)
			)
		)
	)
	(footprint ""
		(layer "F.Cu")
		(at 29.707332 -16.383 90)
		(property "Reference" "R89"
			(at -3.7846 -0.549148 90)
			(unlocked yes)
			(layer "F.SilkS")
			(effects
				(font
					(size 0.7874 0.5842)
					(thickness 0.1524)
				)
				(justify left)
			)
		)
		(property "Value" ""
			(at 0 0 90)
			(layer "F.Fab")
			(effects
				(font
					(size 1.27 1.27)
				)
			)
		)
		(duplicate_pad_numbers_are_jumpers no)
		(fp_line
			(start 0.7874 -0.4064)
			(end 0.7874 0.4064)
			(stroke
				(width 0.1524)
				(type default)
			)
			(layer "F.SilkS")
		)
		(fp_line
			(start -0.7874 -0.4064)
			(end 0.7874 -0.4064)
			(stroke
				(width 0.1524)
				(type default)
			)
			(layer "F.SilkS")
		)
		(fp_line
			(start 0.7874 0.4064)
			(end -0.7874 0.4064)
			(stroke
				(width 0.1524)
				(type default)
			)
			(layer "F.SilkS")
		)
		(fp_line
			(start -0.7874 0.4064)
			(end -0.7874 -0.4064)
			(stroke
				(width 0.1524)
				(type default)
			)
			(layer "F.SilkS")
		)
		(fp_poly
			(pts
				(xy -0.508 0.2794) (xy -0.508 0.2286) (xy -0.635 0.2286) (xy -0.635 -0.254) (xy -0.5334 -0.254)
				(xy -0.5334 -0.2794) (xy 0.5334 -0.2794) (xy 0.5334 -0.254) (xy 0.635 -0.254) (xy 0.635 0.254) (xy 0.5334 0.254)
				(xy 0.5334 0.2794)
			)
			(stroke
				(width 0)
				(type default)
			)
			(fill no)
			(layer "F.CrtYd")
		)
		(pad "1" smd rect
			(at 0.40005 0 90)
			(size 0.4572 0.508)
			(layers "F.Cu" "F.Mask" "F.Paste")
			(net "N39395053")
		)
		(pad "2" smd rect
			(at -0.40005 0 90)
			(size 0.4572 0.508)
			(layers "F.Cu" "F.Mask" "F.Paste")
			(net "GND")
		)
	)
	(footprint ""
		(layer "F.Cu")
		(at 324.358 -2.6416 90)
		(property "Reference" "C32"
			(at -1.651 -5.730748 90)
			(unlocked yes)
			(layer "F.SilkS")
			(effects
				(font
					(size 0.7874 0.5842)
					(thickness 0.1524)
				)
				(justify left)
			)
		)
		(property "Value" ""
			(at 0 0 90)
			(layer "F.Fab")
			(effects
				(font
					(size 1.27 1.27)
				)
			)
		)
		(duplicate_pad_numbers_are_jumpers no)
		(fp_line
			(start 0.7874 -0.4064)
			(end 0.7874 0.4064)
			(stroke
				(width 0.1524)
				(type default)
			)
			(layer "F.SilkS")
		)
		(fp_line
			(start -0.7874 -0.4064)
			(end 0.7874 -0.4064)
			(stroke
				(width 0.1524)
				(type default)
			)
			(layer "F.SilkS")
		)
		(fp_line
			(start 0 0.381)
			(end 0 -0.381)
			(stroke
				(width 0.1524)
				(type default)
			)
			(layer "F.SilkS")
		)
		(fp_line
			(start 0.7874 0.4064)
			(end -0.7874 0.4064)
			(stroke
				(width 0.1524)
				(type default)
			)
			(layer "F.SilkS")
		)
		(fp_line
			(start -0.7874 0.4064)
			(end -0.7874 -0.4064)
			(stroke
				(width 0.1524)
				(type default)
			)
			(layer "F.SilkS")
		)
		(fp_poly
			(pts
				(xy -0.5334 0.254) (xy -0.635 0.254) (xy -0.635 0.2286) (xy -0.635 -0.254) (xy -0.5334 -0.254) (xy -0.5334 -0.2794)
				(xy 0.5334 -0.2794) (xy 0.5334 -0.254) (xy 0.635 -0.254) (xy 0.635 0.254) (xy 0.5334 0.254) (xy 0.5334 0.2794)
				(xy -0.508 0.2794) (xy -0.5334 0.2794)
			)
			(stroke
				(width 0)
				(type default)
			)
			(fill no)
			(layer "F.CrtYd")
		)
		(pad "1" smd rect
			(at 0.40005 0 90)
			(size 0.4572 0.508)
			(layers "F.Cu" "F.Mask" "F.Paste")
			(net "P3V3_10G_4_VCCR")
		)
		(pad "2" smd rect
			(at -0.40005 0 90)
			(size 0.4572 0.508)
			(layers "F.Cu" "F.Mask" "F.Paste")
			(net "GND")
		)
	)
	(footprint ""
		(layer "F.Cu")
		(at 378.431552 -26.227278)
		(property "Reference" "R48"
			(at 33.5026 16.875252 0)
			(unlocked yes)
			(layer "F.SilkS")
			(effects
				(font
					(size 0.7874 0.5842)
					(thickness 0.1524)
				)
				(justify left)
			)
		)
		(property "Value" ""
			(at 0 0 0)
			(layer "F.Fab")
			(effects
				(font
					(size 1.27 1.27)
				)
			)
		)
		(duplicate_pad_numbers_are_jumpers no)
		(fp_line
			(start -0.7874 -0.4064)
			(end 0.7874 -0.4064)
			(stroke
				(width 0.1524)
				(type default)
			)
			(layer "F.SilkS")
		)
		(fp_line
			(start -0.7874 0.4064)
			(end -0.7874 -0.4064)
			(stroke
				(width 0.1524)
				(type default)
			)
			(layer "F.SilkS")
		)
		(fp_line
			(start 0.7874 -0.4064)
			(end 0.7874 0.4064)
			(stroke
				(width 0.1524)
				(type default)
			)
			(layer "F.SilkS")
		)
		(fp_line
			(start 0.7874 0.4064)
			(end -0.7874 0.4064)
			(stroke
				(width 0.1524)
				(type default)
			)
			(layer "F.SilkS")
		)
		(fp_poly
			(pts
				(xy -0.508 0.2794) (xy -0.508 0.2286) (xy -0.635 0.2286) (xy -0.635 -0.254) (xy -0.5334 -0.254)
				(xy -0.5334 -0.2794) (xy 0.5334 -0.2794) (xy 0.5334 -0.254) (xy 0.635 -0.254) (xy 0.635 0.254) (xy 0.5334 0.254)
				(xy 0.5334 0.2794)
			)
			(stroke
				(width 0)
				(type default)
			)
			(fill no)
			(layer "F.CrtYd")
		)
		(pad "1" smd rect
			(at 0.40005 0)
			(size 0.4572 0.508)
			(layers "F.Cu" "F.Mask" "F.Paste")
			(net "GND")
		)
		(pad "2" smd rect
			(at -0.40005 0)
			(size 0.4572 0.508)
			(layers "F.Cu" "F.Mask" "F.Paste")
			(net "ENET10G_3_RS0")
		)
	)
	(footprint ""
		(layer "F.Cu")
		(at 117.31244 -25.45461)
		(property "Reference" "R10"
			(at -61.341 5.115052 0)
			(unlocked yes)
			(layer "F.SilkS")
			(effects
				(font
					(size 0.7874 0.5842)
					(thickness 0.1524)
				)
				(justify left)
			)
		)
		(property "Value" ""
			(at 0 0 0)
			(layer "F.Fab")
			(effects
				(font
					(size 1.27 1.27)
				)
			)
		)
		(duplicate_pad_numbers_are_jumpers no)
		(fp_line
			(start -0.7874 -0.4064)
			(end 0.7874 -0.4064)
			(stroke
				(width 0.1524)
				(type default)
			)
			(layer "F.SilkS")
		)
		(fp_line
			(start -0.7874 0.4064)
			(end -0.7874 -0.4064)
			(stroke
				(width 0.1524)
				(type default)
			)
			(layer "F.SilkS")
		)
		(fp_line
			(start 0.7874 -0.4064)
			(end 0.7874 0.4064)
			(stroke
				(width 0.1524)
				(type default)
			)
			(layer "F.SilkS")
		)
		(fp_line
			(start 0.7874 0.4064)
			(end -0.7874 0.4064)
			(stroke
				(width 0.1524)
				(type default)
			)
			(layer "F.SilkS")
		)
		(fp_poly
			(pts
				(xy -0.508 0.2794) (xy -0.508 0.2286) (xy -0.635 0.2286) (xy -0.635 -0.254) (xy -0.5334 -0.254)
				(xy -0.5334 -0.2794) (xy 0.5334 -0.2794) (xy 0.5334 -0.254) (xy 0.635 -0.254) (xy 0.635 0.254) (xy 0.5334 0.254)
				(xy 0.5334 0.2794)
			)
			(stroke
				(width 0)
				(type default)
			)
			(fill no)
			(layer "F.CrtYd")
		)
		(pad "1" smd rect
			(at 0.40005 0)
			(size 0.4572 0.508)
			(layers "F.Cu" "F.Mask" "F.Paste")
			(net "P3V3_BLAD1")
		)
		(pad "2" smd rect
			(at -0.40005 0)
			(size 0.4572 0.508)
			(layers "F.Cu" "F.Mask" "F.Paste")
			(net "ENET10G_2_MOD_DEF0")
		)
	)
	(footprint ""
		(layer "F.Cu")
		(at 14.310106 -34.500058)
		(property "Reference" "J20"
			(at 3.20421 4.4323 90)
			(unlocked yes)
			(layer "F.SilkS")
			(effects
				(font
					(size 0.7874 0.5842)
					(thickness 0.1524)
				)
				(justify left)
			)
		)
		(property "Value" ""
			(at 0 0 0)
			(layer "F.Fab")
			(effects
				(font
					(size 1.27 1.27)
				)
			)
		)
		(duplicate_pad_numbers_are_jumpers no)
		(fp_line
			(start -6.299962 10.500106)
			(end -4.899914 10.500106)
			(stroke
				(width 0.1524)
				(type default)
			)
			(layer "F.SilkS")
		)
		(fp_line
			(start -6.299962 13.5001)
			(end -6.299962 10.500106)
			(stroke
				(width 0.1524)
				(type default)
			)
			(layer "F.SilkS")
		)
		(fp_line
			(start -4.899914 -3.325114)
			(end -4.776724 -3.325114)
			(stroke
				(width 0.1524)
				(type default)
			)
			(layer "F.SilkS")
		)
		(fp_line
			(start -4.899914 13.5001)
			(end -6.299962 13.5001)
			(stroke
				(width 0.1524)
				(type default)
			)
			(layer "F.SilkS")
		)
		(fp_line
			(start -4.899914 27.325066)
			(end -4.899914 -3.325114)
			(stroke
				(width 0.1524)
				(type default)
			)
			(layer "F.SilkS")
		)
		(fp_line
			(start -4.776724 27.325066)
			(end -4.878324 27.325066)
			(stroke
				(width 0.1524)
				(type default)
			)
			(layer "F.SilkS")
		)
		(fp_line
			(start -3.100578 -3.325114)
			(end 2.469896 -3.325114)
			(stroke
				(width 0.1524)
				(type default)
			)
			(layer "F.SilkS")
		)
		(fp_line
			(start 2.469896 -3.325114)
			(end 2.469896 27.325066)
			(stroke
				(width 0.1524)
				(type default)
			)
			(layer "F.SilkS")
		)
		(fp_line
			(start 2.469896 27.325066)
			(end -3.100578 27.325066)
			(stroke
				(width 0.1524)
				(type default)
			)
			(layer "F.SilkS")
		)
		(fp_poly
			(pts
				(xy 0.125476 -3.577082) (xy -0.828294 -5.48513) (xy 1.0795 -5.48513)
			)
			(stroke
				(width 0)
				(type default)
			)
			(fill yes)
			(layer "F.SilkS")
		)
		(fp_poly
			(pts
				(xy -6.275578 13.498576) (xy -6.275578 10.501376) (xy -4.903978 10.501376) (xy -4.903978 13.498576)
			)
			(stroke
				(width 0)
				(type default)
			)
			(fill yes)
			(layer "F.SilkS")
		)
		(fp_poly
			(pts
				(xy -3.862324 24.856694) (xy -3.862324 -0.873506) (xy -2.135124 -0.873506) (xy -2.135124 24.856694)
			)
			(stroke
				(width 0)
				(type default)
			)
			(fill no)
			(layer "B.CrtYd")
		)
		(fp_poly
			(pts
				(xy 0.862076 -0.873506) (xy 0.862076 24.856694) (xy -0.85852 24.856694) (xy -0.839724 -0.873506)
			)
			(stroke
				(width 0)
				(type default)
			)
			(fill no)
			(layer "B.CrtYd")
		)
		(fp_poly
			(pts
				(arc
					(start -3.127248 -2.999994)
					(mid -4.752848 -2.999994)
					(end -3.127248 -2.999994)
				)
			)
			(stroke
				(width 0)
				(type default)
			)
			(fill no)
			(layer "B.CrtYd")
		)
		(fp_poly
			(pts
				(arc
					(start -3.127248 26.999946)
					(mid -4.752848 26.999946)
					(end -3.127248 26.999946)
				)
			)
			(stroke
				(width 0)
				(type default)
			)
			(fill no)
			(layer "B.CrtYd")
		)
		(fp_poly
			(pts
				(xy 2.487422 27.337512) (xy -3.201924 27.337512) (xy -3.201924 27.828494) (xy -4.675124 27.828494)
				(xy -4.675124 27.337512) (xy -4.903978 27.337512) (xy -4.903978 13.498576) (xy -6.300978 13.498576)
				(xy -6.300978 10.501376) (xy -4.903978 10.501376) (xy -4.903978 -3.337306) (xy -4.675124 -3.337306)
				(xy -4.675124 -3.819906) (xy -3.201924 -3.819906) (xy -3.201924 -3.337306) (xy 2.487422 -3.337306)
			)
			(stroke
				(width 0)
				(type default)
			)
			(fill no)
			(layer "F.CrtYd")
		)
		(fp_line
			(start -4.899914 -3.325114)
			(end -3.100578 -3.325114)
			(stroke
				(width 0.1)
				(type default)
			)
			(layer "F.Fab")
		)
		(fp_line
			(start -4.899914 27.325066)
			(end -4.899914 -3.325114)
			(stroke
				(width 0.1)
				(type default)
			)
			(layer "F.Fab")
		)
		(fp_line
			(start -3.100578 -3.325114)
			(end 2.469896 -3.325114)
			(stroke
				(width 0.1)
				(type default)
			)
			(layer "F.Fab")
		)
		(fp_line
			(start 2.469896 -3.325114)
			(end 2.469896 27.325066)
			(stroke
				(width 0.1)
				(type default)
			)
			(layer "F.Fab")
		)
		(fp_line
			(start 2.469896 27.325066)
			(end -4.899914 27.325066)
			(stroke
				(width 0.1)
				(type default)
			)
			(layer "F.Fab")
		)
		(fp_poly
			(pts
				(xy -0.026924 -4.059682) (xy -0.980694 -5.96773) (xy 0.9271 -5.96773)
			)
			(stroke
				(width 0)
				(type default)
			)
			(fill yes)
			(layer "F.Fab")
		)
		(fp_text user "13"
			(at -3.902202 -4.907026 0)
			(unlocked yes)
			(layer "F.SilkS")
			(effects
				(font
					(size 0.7874 0.5842)
					(thickness 0.1524)
				)
				(justify left)
			)
		)
		(fp_text user "18"
			(at -0.893826 28.816554 90)
			(unlocked yes)
			(layer "F.SilkS")
			(effects
				(font
					(size 0.7874 0.5842)
					(thickness 0.1524)
				)
				(justify left)
			)
		)
		(fp_text user "9"
			(at 2.981198 23.938738 0)
			(unlocked yes)
			(layer "F.SilkS")
			(effects
				(font
					(size 0.7874 0.5842)
					(thickness 0.1524)
				)
				(justify left)
			)
		)
		(fp_text user "1"
			(at 3.143758 -1.143254 0)
			(unlocked yes)
			(layer "F.SilkS")
			(effects
				(font
					(size 0.7874 0.5842)
					(thickness 0.1524)
				)
				(justify left)
			)
		)
		(fp_text user "13"
			(at -2.988818 -2.346706 90)
			(unlocked yes)
			(layer "B.SilkS")
			(effects
				(font
					(size 0.7874 0.5842)
					(thickness 0.1524)
				)
				(justify left mirror)
			)
		)
		(fp_text user "18"
			(at -2.032254 24.932894 90)
			(unlocked yes)
			(layer "B.SilkS")
			(effects
				(font
					(size 0.7874 0.5842)
					(thickness 0.1524)
				)
				(justify left mirror)
			)
		)
		(fp_text user "1"
			(at -0.093218 -1.953006 90)
			(unlocked yes)
			(layer "B.SilkS")
			(effects
				(font
					(size 0.7874 0.5842)
					(thickness 0.1524)
				)
				(justify left mirror)
			)
		)
		(fp_text user "9"
			(at -0.093218 24.949912 90)
			(unlocked yes)
			(layer "B.SilkS")
			(effects
				(font
					(size 0.7874 0.5842)
					(thickness 0.1524)
				)
				(justify left mirror)
			)
		)
		(fp_text user "13"
			(at -2.988818 -2.346706 90)
			(unlocked yes)
			(layer "B.Fab")
			(effects
				(font
					(size 0.7874 0.5842)
					(thickness 0.000001)
				)
				(justify left mirror)
			)
		)
		(fp_text user "18"
			(at -2.895854 24.780494 90)
			(unlocked yes)
			(layer "B.Fab")
			(effects
				(font
					(size 0.7874 0.5842)
					(thickness 0.000001)
				)
				(justify left mirror)
			)
		)
		(fp_text user "1"
			(at -0.093218 -1.953006 90)
			(unlocked yes)
			(layer "B.Fab")
			(effects
				(font
					(size 0.7874 0.5842)
					(thickness 0.000001)
				)
				(justify left mirror)
			)
		)
		(fp_text user "9"
			(at -0.093218 24.949912 90)
			(unlocked yes)
			(layer "B.Fab")
			(effects
				(font
					(size 0.7874 0.5842)
					(thickness 0.000001)
				)
				(justify left mirror)
			)
		)
		(fp_text user "13"
			(at -3.090418 -3.769106 90)
			(unlocked yes)
			(layer "F.Fab")
			(effects
				(font
					(size 0.7874 0.5842)
					(thickness 0.000001)
				)
				(justify left)
			)
		)
		(fp_text user "18"
			(at -2.895854 29.047694 90)
			(unlocked yes)
			(layer "F.Fab")
			(effects
				(font
					(size 0.7874 0.5842)
					(thickness 0.000001)
				)
				(justify left)
			)
		)
		(fp_text user "9"
			(at -0.178054 28.133294 90)
			(unlocked yes)
			(layer "F.Fab")
			(effects
				(font
					(size 0.7874 0.5842)
					(thickness 0.000001)
				)
				(justify left)
			)
		)
		(fp_text user "1"
			(at -0.118618 -3.578606 90)
			(unlocked yes)
			(layer "F.Fab")
			(effects
				(font
					(size 0.7874 0.5842)
					(thickness 0.000001)
				)
				(justify left)
			)
		)
		(pad "" np_thru_hole circle
			(at -3.940048 -2.999994 90)
			(size 1.0922 1.0922)
			(drill 1.0922)
			(layers "*.Cu" "*.Mask")
			(clearance 0.381)
			(thermal_gap 0.381)
		)
		(pad "" np_thru_hole circle
			(at -3.940048 26.999946 90)
			(size 1.0922 1.0922)
			(drill 1.0922)
			(layers "*.Cu" "*.Mask")
			(clearance 0.381)
			(thermal_gap 0.381)
		)
		(pad "1" thru_hole rect
			(at 0 0 90)
			(size 1.6002 1.6002)
			(drill 1.0922)
			(layers "*.Cu" "*.Mask")
			(remove_unused_layers no)
			(net "GND")
			(clearance 0)
			(padstack
				(mode front_inner_back)
				(layer "Inner"
					(shape circle)
					(size 1.6002 1.6002)
					(clearance 0)
				)
				(layer "B.Cu"
					(shape rect)
					(size 1.6002 1.6002)
					(clearance 0)
				)
			)
		)
		(pad "2" thru_hole circle
			(at 0 2.999994 90)
			(size 1.6002 1.6002)
			(drill 1.0922)
			(layers "*.Cu" "*.Mask")
			(remove_unused_layers no)
			(net "GND")
			(clearance 0)
		)
		(pad "3" thru_hole circle
			(at 0 5.999988 90)
			(size 1.6002 1.6002)
			(drill 1.0922)
			(layers "*.Cu" "*.Mask")
			(remove_unused_layers no)
			(net "GND")
			(clearance 0)
		)
		(pad "4" thru_hole circle
			(at 0 8.999982 90)
			(size 1.6002 1.6002)
			(drill 1.0922)
			(layers "*.Cu" "*.Mask")
			(remove_unused_layers no)
			(net "GND")
			(clearance 0)
		)
		(pad "5" thru_hole circle
			(at 0 11.999976 90)
			(size 1.6002 1.6002)
			(drill 1.0922)
			(layers "*.Cu" "*.Mask")
			(remove_unused_layers no)
			(net "GND")
			(clearance 0)
		)
		(pad "6" thru_hole circle
			(at 0 14.99997 90)
			(size 1.6002 1.6002)
			(drill 1.0922)
			(layers "*.Cu" "*.Mask")
			(remove_unused_layers no)
			(net "GND")
			(clearance 0)
		)
		(pad "7" thru_hole circle
			(at 0 17.999964 90)
			(size 1.6002 1.6002)
			(drill 1.0922)
			(layers "*.Cu" "*.Mask")
			(remove_unused_layers no)
			(net "GND")
			(clearance 0)
		)
		(pad "8" thru_hole circle
			(at 0 20.999958 90)
			(size 1.6002 1.6002)
			(drill 1.0922)
			(layers "*.Cu" "*.Mask")
			(remove_unused_layers no)
			(net "GND")
			(clearance 0)
		)
		(pad "9" thru_hole circle
			(at 0 23.999952 90)
			(size 1.6002 1.6002)
			(drill 1.0922)
			(layers "*.Cu" "*.Mask")
			(remove_unused_layers no)
			(net "GND")
			(clearance 0)
		)
		(pad "10" thru_hole circle
			(at -2.999994 0 90)
			(size 1.6002 1.6002)
			(drill 1.0922)
			(layers "*.Cu" "*.Mask")
			(remove_unused_layers no)
			(net "10")
			(clearance 0)
		)
		(pad "11" thru_hole circle
			(at -2.999994 2.999994 90)
			(size 1.6002 1.6002)
			(drill 1.0922)
			(layers "*.Cu" "*.Mask")
			(remove_unused_layers no)
			(net "P12V")
			(clearance 0)
		)
		(pad "12" thru_hole circle
			(at -2.999994 5.999988 90)
			(size 1.6002 1.6002)
			(drill 1.0922)
			(layers "*.Cu" "*.Mask")
			(remove_unused_layers no)
			(net "P12V")
			(clearance 0)
		)
		(pad "13" thru_hole circle
			(at -2.999994 8.999982 90)
			(size 1.6002 1.6002)
			(drill 1.0922)
			(layers "*.Cu" "*.Mask")
			(remove_unused_layers no)
			(net "P12V")
			(clearance 0)
		)
		(pad "14" thru_hole circle
			(at -2.999994 11.999976 90)
			(size 1.6002 1.6002)
			(drill 1.0922)
			(layers "*.Cu" "*.Mask")
			(remove_unused_layers no)
			(net "P12V")
			(clearance 0)
		)
		(pad "15" thru_hole circle
			(at -2.999994 14.99997 90)
			(size 1.6002 1.6002)
			(drill 1.0922)
			(layers "*.Cu" "*.Mask")
			(remove_unused_layers no)
			(net "P12V")
			(clearance 0)
		)
		(pad "16" thru_hole circle
			(at -2.999994 17.999964 90)
			(size 1.6002 1.6002)
			(drill 1.0922)
			(layers "*.Cu" "*.Mask")
			(remove_unused_layers no)
			(net "P12V")
			(clearance 0)
		)
		(pad "17" thru_hole circle
			(at -2.999994 20.999958 90)
			(size 1.6002 1.6002)
			(drill 1.0922)
			(layers "*.Cu" "*.Mask")
			(remove_unused_layers no)
			(net "P12V")
			(clearance 0)
		)
		(pad "18" thru_hole circle
			(at -2.999994 23.999952 90)
			(size 1.6002 1.6002)
			(drill 1.0922)
			(layers "*.Cu" "*.Mask")
			(remove_unused_layers no)
			(net "P12V")
			(clearance 0)
		)
		(zone
			(layers "F.Cu" "B.Cu" "In1.Cu" "In2.Cu" "In3.Cu" "In4.Cu" "In5.Cu" "In6.Cu")
			(hatch none 0.5)
			(connect_pads
				(clearance 0)
			)
			(min_thickness 0.25)
			(keepout
				(tracks not_allowed)
				(vias allowed)
				(pads allowed)
				(copperpour not_allowed)
				(footprints allowed)
			)
			(placement
				(enabled no)
				(sheetname "")
			)
			(fill
				(thermal_gap 0.5)
				(thermal_bridge_width 0.5)
				(island_removal_mode 0)
			)
			(polygon
				(pts
					(arc
						(start 11.335258 -37.500052)
						(mid 9.404858 -37.500052)
						(end 11.335258 -37.500052)
					)
				)
			)
		)
		(zone
			(layers "F.Cu" "B.Cu" "In1.Cu" "In2.Cu" "In3.Cu" "In4.Cu" "In5.Cu" "In6.Cu")
			(hatch none 0.5)
			(connect_pads
				(clearance 0)
			)
			(min_thickness 0.25)
			(keepout
				(tracks not_allowed)
				(vias allowed)
				(pads allowed)
				(copperpour not_allowed)
				(footprints allowed)
			)
			(placement
				(enabled no)
				(sheetname "")
			)
			(fill
				(thermal_gap 0.5)
				(thermal_bridge_width 0.5)
				(island_removal_mode 0)
			)
			(polygon
				(pts
					(arc
						(start 11.335258 -7.500112)
						(mid 9.404858 -7.500112)
						(end 11.335258 -7.500112)
					)
				)
			)
		)
	)
	(footprint ""
		(layer "F.Cu")
		(at 90.9828 -33.056068)
		(property "Reference" "R79"
			(at -7.0866 2.82067 0)
			(unlocked yes)
			(layer "F.SilkS")
			(effects
				(font
					(size 0.7874 0.5842)
					(thickness 0.1524)
				)
				(justify left)
			)
		)
		(property "Value" ""
			(at 0 0 0)
			(layer "F.Fab")
			(effects
				(font
					(size 1.27 1.27)
				)
			)
		)
		(duplicate_pad_numbers_are_jumpers no)
		(fp_line
			(start -1.905 -0.8636)
			(end 1.905 -0.8636)
			(stroke
				(width 0.1524)
				(type default)
			)
			(layer "F.SilkS")
		)
		(fp_line
			(start -1.905 0.8636)
			(end -1.905 -0.8636)
			(stroke
				(width 0.1524)
				(type default)
			)
			(layer "F.SilkS")
		)
		(fp_line
			(start 1.905 -0.8636)
			(end 1.905 0.8636)
			(stroke
				(width 0.1524)
				(type default)
			)
			(layer "F.SilkS")
		)
		(fp_line
			(start 1.905 0.8636)
			(end -1.905 0.8636)
			(stroke
				(width 0.1524)
				(type default)
			)
			(layer "F.SilkS")
		)
		(fp_poly
			(pts
				(xy 1.524 0.6858) (xy 1.524 -0.6858) (xy 1.524 -0.7366) (xy -1.524 -0.7366) (xy -1.524 -0.6858)
				(xy -1.524 0.6858) (xy -1.524 0.7366) (xy 1.524 0.7366)
			)
			(stroke
				(width 0)
				(type default)
			)
			(fill no)
			(layer "F.CrtYd")
		)
		(pad "1" smd rect
			(at 0.94996 0)
			(size 1.1176 1.3716)
			(layers "F.Cu" "F.Mask" "F.Paste")
			(net "P3V3_BLAD1")
		)
		(pad "2" smd rect
			(at -0.94996 0)
			(size 1.1176 1.3716)
			(layers "F.Cu" "F.Mask" "F.Paste")
			(net "P3V3_10G_2_VCCR")
		)
	)
	(footprint ""
		(layer "F.Cu")
		(at 120.971818 -23.357332)
		(property "Reference" "R59"
			(at -61.6204 5.343652 0)
			(unlocked yes)
			(layer "F.SilkS")
			(effects
				(font
					(size 0.7874 0.5842)
					(thickness 0.1524)
				)
				(justify left)
			)
		)
		(property "Value" ""
			(at 0 0 0)
			(layer "F.Fab")
			(effects
				(font
					(size 1.27 1.27)
				)
			)
		)
		(duplicate_pad_numbers_are_jumpers no)
		(fp_line
			(start -0.7874 -0.4064)
			(end 0.7874 -0.4064)
			(stroke
				(width 0.1524)
				(type default)
			)
			(layer "F.SilkS")
		)
		(fp_line
			(start -0.7874 0.4064)
			(end -0.7874 -0.4064)
			(stroke
				(width 0.1524)
				(type default)
			)
			(layer "F.SilkS")
		)
		(fp_line
			(start 0.7874 -0.4064)
			(end 0.7874 0.4064)
			(stroke
				(width 0.1524)
				(type default)
			)
			(layer "F.SilkS")
		)
		(fp_line
			(start 0.7874 0.4064)
			(end -0.7874 0.4064)
			(stroke
				(width 0.1524)
				(type default)
			)
			(layer "F.SilkS")
		)
		(fp_poly
			(pts
				(xy -0.508 0.2794) (xy -0.508 0.2286) (xy -0.635 0.2286) (xy -0.635 -0.254) (xy -0.5334 -0.254)
				(xy -0.5334 -0.2794) (xy 0.5334 -0.2794) (xy 0.5334 -0.254) (xy 0.635 -0.254) (xy 0.635 0.254) (xy 0.5334 0.254)
				(xy 0.5334 0.2794)
			)
			(stroke
				(width 0)
				(type default)
			)
			(fill no)
			(layer "F.CrtYd")
		)
		(pad "1" smd rect
			(at 0.40005 0)
			(size 0.4572 0.508)
			(layers "F.Cu" "F.Mask" "F.Paste")
			(net "GND")
		)
		(pad "2" smd rect
			(at -0.40005 0)
			(size 0.4572 0.508)
			(layers "F.Cu" "F.Mask" "F.Paste")
			(net "SFP2_PRESENT_N")
		)
	)
	(footprint ""
		(layer "F.Cu")
		(at 30.977332 -16.383 90)
		(property "Reference" "R87"
			(at -3.81 -0.701548 90)
			(unlocked yes)
			(layer "F.SilkS")
			(effects
				(font
					(size 0.7874 0.5842)
					(thickness 0.1524)
				)
				(justify left)
			)
		)
		(property "Value" ""
			(at 0 0 90)
			(layer "F.Fab")
			(effects
				(font
					(size 1.27 1.27)
				)
			)
		)
		(duplicate_pad_numbers_are_jumpers no)
		(fp_line
			(start 0.7874 -0.4064)
			(end 0.7874 0.4064)
			(stroke
				(width 0.1524)
				(type default)
			)
			(layer "F.SilkS")
		)
		(fp_line
			(start -0.7874 -0.4064)
			(end 0.7874 -0.4064)
			(stroke
				(width 0.1524)
				(type default)
			)
			(layer "F.SilkS")
		)
		(fp_line
			(start 0.7874 0.4064)
			(end -0.7874 0.4064)
			(stroke
				(width 0.1524)
				(type default)
			)
			(layer "F.SilkS")
		)
		(fp_line
			(start -0.7874 0.4064)
			(end -0.7874 -0.4064)
			(stroke
				(width 0.1524)
				(type default)
			)
			(layer "F.SilkS")
		)
		(fp_poly
			(pts
				(xy -0.508 0.2794) (xy -0.508 0.2286) (xy -0.635 0.2286) (xy -0.635 -0.254) (xy -0.5334 -0.254)
				(xy -0.5334 -0.2794) (xy 0.5334 -0.2794) (xy 0.5334 -0.254) (xy 0.635 -0.254) (xy 0.635 0.254) (xy 0.5334 0.254)
				(xy 0.5334 0.2794)
			)
			(stroke
				(width 0)
				(type default)
			)
			(fill no)
			(layer "F.CrtYd")
		)
		(pad "1" smd rect
			(at 0.40005 0 90)
			(size 0.4572 0.508)
			(layers "F.Cu" "F.Mask" "F.Paste")
			(net "N39391900")
		)
		(pad "2" smd rect
			(at -0.40005 0 90)
			(size 0.4572 0.508)
			(layers "F.Cu" "F.Mask" "F.Paste")
			(net "GND")
		)
	)
	(footprint ""
		(layer "F.Cu")
		(at 375.82856 -26.227278 180)
		(property "Reference" "R27"
			(at -33.78708 -16.853408 0)
			(unlocked yes)
			(layer "F.SilkS")
			(effects
				(font
					(size 0.7874 0.5842)
					(thickness 0.1524)
				)
				(justify left)
			)
		)
		(property "Value" ""
			(at 0 0 180)
			(layer "F.Fab")
			(effects
				(font
					(size 1.27 1.27)
				)
			)
		)
		(duplicate_pad_numbers_are_jumpers no)
		(fp_line
			(start 0.7874 0.4064)
			(end -0.7874 0.4064)
			(stroke
				(width 0.1524)
				(type default)
			)
			(layer "F.SilkS")
		)
		(fp_line
			(start 0.7874 -0.4064)
			(end 0.7874 0.4064)
			(stroke
				(width 0.1524)
				(type default)
			)
			(layer "F.SilkS")
		)
		(fp_line
			(start -0.7874 0.4064)
			(end -0.7874 -0.4064)
			(stroke
				(width 0.1524)
				(type default)
			)
			(layer "F.SilkS")
		)
		(fp_line
			(start -0.7874 -0.4064)
			(end 0.7874 -0.4064)
			(stroke
				(width 0.1524)
				(type default)
			)
			(layer "F.SilkS")
		)
		(fp_poly
			(pts
				(xy -0.508 0.2794) (xy -0.508 0.2286) (xy -0.635 0.2286) (xy -0.635 -0.254) (xy -0.5334 -0.254)
				(xy -0.5334 -0.2794) (xy 0.5334 -0.2794) (xy 0.5334 -0.254) (xy 0.635 -0.254) (xy 0.635 0.254) (xy 0.5334 0.254)
				(xy 0.5334 0.2794)
			)
			(stroke
				(width 0)
				(type default)
			)
			(fill no)
			(layer "F.CrtYd")
		)
		(pad "1" smd rect
			(at 0.40005 0 180)
			(size 0.4572 0.508)
			(layers "F.Cu" "F.Mask" "F.Paste")
			(net "P3V3_BLAD2")
		)
		(pad "2" smd rect
			(at -0.40005 0 180)
			(size 0.4572 0.508)
			(layers "F.Cu" "F.Mask" "F.Paste")
			(net "ENET10G_3_RS0")
		)
	)
	(footprint ""
		(layer "F.Cu")
		(at 25.841706 -16.354552 -90)
		(property "Reference" "R33"
			(at 3.727704 -0.16764 90)
			(unlocked yes)
			(layer "F.SilkS")
			(effects
				(font
					(size 0.7874 0.5842)
					(thickness 0.1524)
				)
				(justify left)
			)
		)
		(property "Value" ""
			(at 0 0 270)
			(layer "F.Fab")
			(effects
				(font
					(size 1.27 1.27)
				)
			)
		)
		(duplicate_pad_numbers_are_jumpers no)
		(fp_line
			(start -0.7874 0.4064)
			(end -0.7874 -0.4064)
			(stroke
				(width 0.1524)
				(type default)
			)
			(layer "F.SilkS")
		)
		(fp_line
			(start 0.7874 0.4064)
			(end -0.7874 0.4064)
			(stroke
				(width 0.1524)
				(type default)
			)
			(layer "F.SilkS")
		)
		(fp_line
			(start -0.7874 -0.4064)
			(end 0.7874 -0.4064)
			(stroke
				(width 0.1524)
				(type default)
			)
			(layer "F.SilkS")
		)
		(fp_line
			(start 0.7874 -0.4064)
			(end 0.7874 0.4064)
			(stroke
				(width 0.1524)
				(type default)
			)
			(layer "F.SilkS")
		)
		(fp_poly
			(pts
				(xy -0.508 0.2794) (xy -0.508 0.2286) (xy -0.635 0.2286) (xy -0.635 -0.254) (xy -0.5334 -0.254)
				(xy -0.5334 -0.2794) (xy 0.5334 -0.2794) (xy 0.5334 -0.254) (xy 0.635 -0.254) (xy 0.635 0.254) (xy 0.5334 0.254)
				(xy 0.5334 0.2794)
			)
			(stroke
				(width 0)
				(type default)
			)
			(fill no)
			(layer "F.CrtYd")
		)
		(pad "1" smd rect
			(at 0.40005 0 270)
			(size 0.4572 0.508)
			(layers "F.Cu" "F.Mask" "F.Paste")
			(net "GND")
		)
		(pad "2" smd rect
			(at -0.40005 0 270)
			(size 0.4572 0.508)
			(layers "F.Cu" "F.Mask" "F.Paste")
			(net "PS_EN_PSU_N")
		)
	)
	(footprint ""
		(layer "F.Cu")
		(at 90.997786 -23.442676 -90)
		(property "Reference" "C3"
			(at -0.612648 5.55752 90)
			(unlocked yes)
			(layer "F.SilkS")
			(effects
				(font
					(size 0.7874 0.5842)
					(thickness 0.1524)
				)
				(justify left)
			)
		)
		(property "Value" ""
			(at 0 0 270)
			(layer "F.Fab")
			(effects
				(font
					(size 1.27 1.27)
				)
			)
		)
		(duplicate_pad_numbers_are_jumpers no)
		(fp_line
			(start -0.7874 0.4064)
			(end -0.7874 -0.4064)
			(stroke
				(width 0.1524)
				(type default)
			)
			(layer "F.SilkS")
		)
		(fp_line
			(start 0.7874 0.4064)
			(end -0.7874 0.4064)
			(stroke
				(width 0.1524)
				(type default)
			)
			(layer "F.SilkS")
		)
		(fp_line
			(start 0 0.381)
			(end 0 -0.381)
			(stroke
				(width 0.1524)
				(type default)
			)
			(layer "F.SilkS")
		)
		(fp_line
			(start -0.7874 -0.4064)
			(end 0.7874 -0.4064)
			(stroke
				(width 0.1524)
				(type default)
			)
			(layer "F.SilkS")
		)
		(fp_line
			(start 0.7874 -0.4064)
			(end 0.7874 0.4064)
			(stroke
				(width 0.1524)
				(type default)
			)
			(layer "F.SilkS")
		)
		(fp_poly
			(pts
				(xy -0.5334 0.254) (xy -0.635 0.254) (xy -0.635 0.2286) (xy -0.635 -0.254) (xy -0.5334 -0.254) (xy -0.5334 -0.2794)
				(xy 0.5334 -0.2794) (xy 0.5334 -0.254) (xy 0.635 -0.254) (xy 0.635 0.254) (xy 0.5334 0.254) (xy 0.5334 0.2794)
				(xy -0.508 0.2794) (xy -0.5334 0.2794)
			)
			(stroke
				(width 0)
				(type default)
			)
			(fill no)
			(layer "F.CrtYd")
		)
		(pad "1" smd rect
			(at 0.40005 0 270)
			(size 0.4572 0.508)
			(layers "F.Cu" "F.Mask" "F.Paste")
			(net "P12V")
		)
		(pad "2" smd rect
			(at -0.40005 0 270)
			(size 0.4572 0.508)
			(layers "F.Cu" "F.Mask" "F.Paste")
			(net "GND")
		)
	)
	(footprint ""
		(layer "F.Cu")
		(at 366.4204 -3.1242 90)
		(property "Reference" "C25"
			(at -2.3622 2.270252 90)
			(unlocked yes)
			(layer "F.SilkS")
			(effects
				(font
					(size 0.7874 0.5842)
					(thickness 0.1524)
				)
				(justify left)
			)
		)
		(property "Value" ""
			(at 0 0 90)
			(layer "F.Fab")
			(effects
				(font
					(size 1.27 1.27)
				)
			)
		)
		(duplicate_pad_numbers_are_jumpers no)
		(fp_line
			(start 0.7874 -0.4064)
			(end 0.7874 0.4064)
			(stroke
				(width 0.1524)
				(type default)
			)
			(layer "F.SilkS")
		)
		(fp_line
			(start -0.7874 -0.4064)
			(end 0.7874 -0.4064)
			(stroke
				(width 0.1524)
				(type default)
			)
			(layer "F.SilkS")
		)
		(fp_line
			(start 0 0.381)
			(end 0 -0.381)
			(stroke
				(width 0.1524)
				(type default)
			)
			(layer "F.SilkS")
		)
		(fp_line
			(start 0.7874 0.4064)
			(end -0.7874 0.4064)
			(stroke
				(width 0.1524)
				(type default)
			)
			(layer "F.SilkS")
		)
		(fp_line
			(start -0.7874 0.4064)
			(end -0.7874 -0.4064)
			(stroke
				(width 0.1524)
				(type default)
			)
			(layer "F.SilkS")
		)
		(fp_poly
			(pts
				(xy -0.5334 0.254) (xy -0.635 0.254) (xy -0.635 0.2286) (xy -0.635 -0.254) (xy -0.5334 -0.254) (xy -0.5334 -0.2794)
				(xy 0.5334 -0.2794) (xy 0.5334 -0.254) (xy 0.635 -0.254) (xy 0.635 0.254) (xy 0.5334 0.254) (xy 0.5334 0.2794)
				(xy -0.508 0.2794) (xy -0.5334 0.2794)
			)
			(stroke
				(width 0)
				(type default)
			)
			(fill no)
			(layer "F.CrtYd")
		)
		(pad "1" smd rect
			(at 0.40005 0 90)
			(size 0.4572 0.508)
			(layers "F.Cu" "F.Mask" "F.Paste")
			(net "P3V3_10G_3_VCCT")
		)
		(pad "2" smd rect
			(at -0.40005 0 90)
			(size 0.4572 0.508)
			(layers "F.Cu" "F.Mask" "F.Paste")
			(net "GND")
		)
	)
	(footprint ""
		(layer "F.Cu")
		(at 157.781752 -25.439878)
		(property "Reference" "R42"
			(at 33.5534 17.942052 0)
			(unlocked yes)
			(layer "F.SilkS")
			(effects
				(font
					(size 0.7874 0.5842)
					(thickness 0.1524)
				)
				(justify left)
			)
		)
		(property "Value" ""
			(at 0 0 0)
			(layer "F.Fab")
			(effects
				(font
					(size 1.27 1.27)
				)
			)
		)
		(duplicate_pad_numbers_are_jumpers no)
		(fp_line
			(start -0.7874 -0.4064)
			(end 0.7874 -0.4064)
			(stroke
				(width 0.1524)
				(type default)
			)
			(layer "F.SilkS")
		)
		(fp_line
			(start -0.7874 0.4064)
			(end -0.7874 -0.4064)
			(stroke
				(width 0.1524)
				(type default)
			)
			(layer "F.SilkS")
		)
		(fp_line
			(start 0.7874 -0.4064)
			(end 0.7874 0.4064)
			(stroke
				(width 0.1524)
				(type default)
			)
			(layer "F.SilkS")
		)
		(fp_line
			(start 0.7874 0.4064)
			(end -0.7874 0.4064)
			(stroke
				(width 0.1524)
				(type default)
			)
			(layer "F.SilkS")
		)
		(fp_poly
			(pts
				(xy -0.508 0.2794) (xy -0.508 0.2286) (xy -0.635 0.2286) (xy -0.635 -0.254) (xy -0.5334 -0.254)
				(xy -0.5334 -0.2794) (xy 0.5334 -0.2794) (xy 0.5334 -0.254) (xy 0.635 -0.254) (xy 0.635 0.254) (xy 0.5334 0.254)
				(xy 0.5334 0.2794)
			)
			(stroke
				(width 0)
				(type default)
			)
			(fill no)
			(layer "F.CrtYd")
		)
		(pad "1" smd rect
			(at 0.40005 0)
			(size 0.4572 0.508)
			(layers "F.Cu" "F.Mask" "F.Paste")
			(net "GND")
		)
		(pad "2" smd rect
			(at -0.40005 0)
			(size 0.4572 0.508)
			(layers "F.Cu" "F.Mask" "F.Paste")
			(net "ENET10G_1_RS0")
		)
	)
	(footprint ""
		(layer "F.Cu")
		(at 102.5144 -2.921 90)
		(property "Reference" "C24"
			(at -2.3622 -4.917948 90)
			(unlocked yes)
			(layer "F.SilkS")
			(effects
				(font
					(size 0.7874 0.5842)
					(thickness 0.1524)
				)
				(justify left)
			)
		)
		(property "Value" ""
			(at 0 0 90)
			(layer "F.Fab")
			(effects
				(font
					(size 1.27 1.27)
				)
			)
		)
		(duplicate_pad_numbers_are_jumpers no)
		(fp_line
			(start 0.7874 -0.4064)
			(end 0.7874 0.4064)
			(stroke
				(width 0.1524)
				(type default)
			)
			(layer "F.SilkS")
		)
		(fp_line
			(start -0.7874 -0.4064)
			(end 0.7874 -0.4064)
			(stroke
				(width 0.1524)
				(type default)
			)
			(layer "F.SilkS")
		)
		(fp_line
			(start 0 0.381)
			(end 0 -0.381)
			(stroke
				(width 0.1524)
				(type default)
			)
			(layer "F.SilkS")
		)
		(fp_line
			(start 0.7874 0.4064)
			(end -0.7874 0.4064)
			(stroke
				(width 0.1524)
				(type default)
			)
			(layer "F.SilkS")
		)
		(fp_line
			(start -0.7874 0.4064)
			(end -0.7874 -0.4064)
			(stroke
				(width 0.1524)
				(type default)
			)
			(layer "F.SilkS")
		)
		(fp_poly
			(pts
				(xy -0.5334 0.254) (xy -0.635 0.254) (xy -0.635 0.2286) (xy -0.635 -0.254) (xy -0.5334 -0.254) (xy -0.5334 -0.2794)
				(xy 0.5334 -0.2794) (xy 0.5334 -0.254) (xy 0.635 -0.254) (xy 0.635 0.254) (xy 0.5334 0.254) (xy 0.5334 0.2794)
				(xy -0.508 0.2794) (xy -0.5334 0.2794)
			)
			(stroke
				(width 0)
				(type default)
			)
			(fill no)
			(layer "F.CrtYd")
		)
		(pad "1" smd rect
			(at 0.40005 0 90)
			(size 0.4572 0.508)
			(layers "F.Cu" "F.Mask" "F.Paste")
			(net "P3V3_10G_2_VCCR")
		)
		(pad "2" smd rect
			(at -0.40005 0 90)
			(size 0.4572 0.508)
			(layers "F.Cu" "F.Mask" "F.Paste")
			(net "GND")
		)
	)
	(footprint ""
		(layer "F.Cu")
		(at 377.8504 -35.433 90)
		(property "Reference" "L7"
			(at -21.463 33.70707 90)
			(unlocked yes)
			(layer "F.SilkS")
			(effects
				(font
					(size 0.7874 0.5842)
					(thickness 0.1524)
				)
				(justify left)
			)
		)
		(property "Value" ""
			(at 0 0 90)
			(layer "F.Fab")
			(effects
				(font
					(size 1.27 1.27)
				)
			)
		)
		(duplicate_pad_numbers_are_jumpers no)
		(fp_line
			(start -1.905 -0.8636)
			(end 1.905 -0.8636)
			(stroke
				(width 0.1524)
				(type default)
			)
			(layer "F.SilkS")
		)
		(fp_line
			(start 1.905 0.8382)
			(end 1.905 -0.8382)
			(stroke
				(width 0.1524)
				(type default)
			)
			(layer "F.SilkS")
		)
		(fp_line
			(start 0.127 0.8382)
			(end 0.127 -0.8382)
			(stroke
				(width 0.1524)
				(type default)
			)
			(layer "F.SilkS")
		)
		(fp_line
			(start -0.127 0.8382)
			(end -0.127 -0.8382)
			(stroke
				(width 0.1524)
				(type default)
			)
			(layer "F.SilkS")
		)
		(fp_line
			(start -1.905 0.8382)
			(end -1.905 -0.8382)
			(stroke
				(width 0.1524)
				(type default)
			)
			(layer "F.SilkS")
		)
		(fp_line
			(start 1.905 0.8636)
			(end -1.905 0.8636)
			(stroke
				(width 0.1524)
				(type default)
			)
			(layer "F.SilkS")
		)
		(fp_rect
			(start -1.524 0.7112)
			(end 1.524 -0.7366)
			(stroke
				(width 0)
				(type default)
			)
			(fill no)
			(layer "F.CrtYd")
		)
		(pad "1" smd rect
			(at 0.94996 0 90)
			(size 1.1176 1.3716)
			(layers "F.Cu" "F.Mask" "F.Paste")
			(net "P3V3_10G_3_VCCR_L")
		)
		(pad "2" smd rect
			(at -0.94996 0 90)
			(size 1.1176 1.3716)
			(layers "F.Cu" "F.Mask" "F.Paste")
			(net "P3V3_10G_3_VCCR")
		)
	)
	(footprint ""
		(layer "F.Cu")
		(at 156.959046 -34.3154 90)
		(property "Reference" "L3"
			(at -22.8346 33.770062 90)
			(unlocked yes)
			(layer "F.SilkS")
			(effects
				(font
					(size 0.7874 0.5842)
					(thickness 0.1524)
				)
				(justify left)
			)
		)
		(property "Value" ""
			(at 0 0 90)
			(layer "F.Fab")
			(effects
				(font
					(size 1.27 1.27)
				)
			)
		)
		(duplicate_pad_numbers_are_jumpers no)
		(fp_line
			(start -1.905 -0.8636)
			(end 1.905 -0.8636)
			(stroke
				(width 0.1524)
				(type default)
			)
			(layer "F.SilkS")
		)
		(fp_line
			(start 1.905 0.8382)
			(end 1.905 -0.8382)
			(stroke
				(width 0.1524)
				(type default)
			)
			(layer "F.SilkS")
		)
		(fp_line
			(start 0.127 0.8382)
			(end 0.127 -0.8382)
			(stroke
				(width 0.1524)
				(type default)
			)
			(layer "F.SilkS")
		)
		(fp_line
			(start -0.127 0.8382)
			(end -0.127 -0.8382)
			(stroke
				(width 0.1524)
				(type default)
			)
			(layer "F.SilkS")
		)
		(fp_line
			(start -1.905 0.8382)
			(end -1.905 -0.8382)
			(stroke
				(width 0.1524)
				(type default)
			)
			(layer "F.SilkS")
		)
		(fp_line
			(start 1.905 0.8636)
			(end -1.905 0.8636)
			(stroke
				(width 0.1524)
				(type default)
			)
			(layer "F.SilkS")
		)
		(fp_rect
			(start -1.524 0.7112)
			(end 1.524 -0.7366)
			(stroke
				(width 0)
				(type default)
			)
			(fill no)
			(layer "F.CrtYd")
		)
		(pad "1" smd rect
			(at 0.94996 0 90)
			(size 1.1176 1.3716)
			(layers "F.Cu" "F.Mask" "F.Paste")
			(net "P3V3_10G_1_VCCR_L")
		)
		(pad "2" smd rect
			(at -0.94996 0 90)
			(size 1.1176 1.3716)
			(layers "F.Cu" "F.Mask" "F.Paste")
			(net "P3V3_10G_1_VCCR")
		)
	)
	(footprint ""
		(layer "F.Cu")
		(at 376.099832 -41.221914)
		(property "Reference" "FS5"
			(at 35.30854 24.241252 0)
			(unlocked yes)
			(layer "F.SilkS")
			(effects
				(font
					(size 0.7874 0.5842)
					(thickness 0.1524)
				)
				(justify left)
			)
		)
		(property "Value" ""
			(at 0 0 0)
			(layer "F.Fab")
			(effects
				(font
					(size 1.27 1.27)
				)
			)
		)
		(duplicate_pad_numbers_are_jumpers no)
		(fp_line
			(start -0.650494 -1.050036)
			(end 3.550412 -1.050036)
			(stroke
				(width 0.1524)
				(type default)
			)
			(layer "F.SilkS")
		)
		(fp_line
			(start -0.650494 1.050036)
			(end -0.650494 -1.050036)
			(stroke
				(width 0.1524)
				(type default)
			)
			(layer "F.SilkS")
		)
		(fp_line
			(start 3.550412 -1.050036)
			(end 3.550412 1.050036)
			(stroke
				(width 0.1524)
				(type default)
			)
			(layer "F.SilkS")
		)
		(fp_line
			(start 3.550412 1.050036)
			(end -0.650494 1.050036)
			(stroke
				(width 0.1524)
				(type default)
			)
			(layer "F.SilkS")
		)
		(fp_poly
			(pts
				(xy 3.228086 -0.9652) (xy 3.228086 -1.100074) (xy -0.327914 -1.100074) (xy -0.327914 -0.9652) (xy -0.556514 -0.9652)
				(xy -0.556514 0.9652) (xy -0.327914 0.9652) (xy -0.327914 1.100074) (xy 3.228086 1.100074) (xy 3.228086 0.9652)
				(xy 3.456686 0.9652) (xy 3.456686 -0.9652)
			)
			(stroke
				(width 0)
				(type default)
			)
			(fill no)
			(layer "F.CrtYd")
		)
		(fp_text user "1"
			(at -0.315214 -1.946148 0)
			(unlocked yes)
			(layer "F.SilkS")
			(effects
				(font
					(size 0.7874 0.5842)
					(thickness 0.1524)
				)
				(justify left)
			)
		)
		(fp_text user "2"
			(at 4.028186 -0.066548 0)
			(unlocked yes)
			(layer "F.SilkS")
			(effects
				(font
					(size 0.7874 0.5842)
					(thickness 0.1524)
				)
				(justify left)
			)
		)
		(pad "1" smd rect
			(at 0 0)
			(size 1.016 1.8034)
			(layers "F.Cu" "F.Mask" "F.Paste")
			(net "P3V3_BLAD2")
		)
		(pad "2" smd rect
			(at 2.899918 0)
			(size 1.016 1.8034)
			(layers "F.Cu" "F.Mask" "F.Paste")
			(net "P3V3_10G_3_VCCT_L")
		)
	)
	(footprint ""
		(layer "F.Cu")
		(at 92.16644 -29.122878)
		(property "Reference" "R4"
			(at -7.0866 1.025652 0)
			(unlocked yes)
			(layer "F.SilkS")
			(effects
				(font
					(size 0.7874 0.5842)
					(thickness 0.1524)
				)
				(justify left)
			)
		)
		(property "Value" ""
			(at 0 0 0)
			(layer "F.Fab")
			(effects
				(font
					(size 1.27 1.27)
				)
			)
		)
		(duplicate_pad_numbers_are_jumpers no)
		(fp_line
			(start -0.7874 -0.4064)
			(end 0.7874 -0.4064)
			(stroke
				(width 0.1524)
				(type default)
			)
			(layer "F.SilkS")
		)
		(fp_line
			(start -0.7874 0.4064)
			(end -0.7874 -0.4064)
			(stroke
				(width 0.1524)
				(type default)
			)
			(layer "F.SilkS")
		)
		(fp_line
			(start 0.7874 -0.4064)
			(end 0.7874 0.4064)
			(stroke
				(width 0.1524)
				(type default)
			)
			(layer "F.SilkS")
		)
		(fp_line
			(start 0.7874 0.4064)
			(end -0.7874 0.4064)
			(stroke
				(width 0.1524)
				(type default)
			)
			(layer "F.SilkS")
		)
		(fp_poly
			(pts
				(xy -0.508 0.2794) (xy -0.508 0.2286) (xy -0.635 0.2286) (xy -0.635 -0.254) (xy -0.5334 -0.254)
				(xy -0.5334 -0.2794) (xy 0.5334 -0.2794) (xy 0.5334 -0.254) (xy 0.635 -0.254) (xy 0.635 0.254) (xy 0.5334 0.254)
				(xy 0.5334 0.2794)
			)
			(stroke
				(width 0)
				(type default)
			)
			(fill no)
			(layer "F.CrtYd")
		)
		(pad "1" smd rect
			(at 0.40005 0)
			(size 0.4572 0.508)
			(layers "F.Cu" "F.Mask" "F.Paste")
			(net "P3V3_BLAD1")
		)
		(pad "2" smd rect
			(at -0.40005 0)
			(size 0.4572 0.508)
			(layers "F.Cu" "F.Mask" "F.Paste")
			(net "ENET10G_2_TX_DIS")
		)
	)
	(footprint ""
		(layer "F.Cu")
		(at 3.578352 -20.360132 180)
		(property "Reference" "JP8"
			(at 2.686304 -3.612134 0)
			(unlocked yes)
			(layer "F.SilkS")
			(effects
				(font
					(size 0.7874 0.5842)
					(thickness 0.1524)
				)
				(justify left)
			)
		)
		(property "Value" ""
			(at 0 0 180)
			(layer "F.Fab")
			(effects
				(font
					(size 1.27 1.27)
				)
			)
		)
		(duplicate_pad_numbers_are_jumpers no)
		(fp_line
			(start 2.54 1.27)
			(end -2.54 1.27)
			(stroke
				(width 0.1524)
				(type default)
			)
			(layer "F.SilkS")
		)
		(fp_line
			(start 2.54 -1.27)
			(end 2.54 1.27)
			(stroke
				(width 0.1524)
				(type default)
			)
			(layer "F.SilkS")
		)
		(fp_line
			(start -2.54 1.27)
			(end -2.54 -1.27)
			(stroke
				(width 0.1524)
				(type default)
			)
			(layer "F.SilkS")
		)
		(fp_line
			(start -2.54 -1.27)
			(end 2.54 -1.27)
			(stroke
				(width 0.1524)
				(type default)
			)
			(layer "F.SilkS")
		)
		(fp_poly
			(pts
				(xy -2.78638 -0.799084) (xy -4.10718 -1.383284) (xy -4.10718 -0.164084)
			)
			(stroke
				(width 0)
				(type default)
			)
			(fill yes)
			(layer "F.SilkS")
		)
		(fp_poly
			(pts
				(xy -2.1082 -0.8382) (xy -2.1082 0.8382) (xy 2.1082 0.8382) (xy 2.1082 -0.8382)
			)
			(stroke
				(width 0)
				(type default)
			)
			(fill no)
			(layer "B.CrtYd")
		)
		(fp_rect
			(start -2.54 1.27)
			(end 2.54 -1.27)
			(stroke
				(width 0)
				(type default)
			)
			(fill no)
			(layer "F.CrtYd")
		)
		(fp_line
			(start 2.54 1.27)
			(end -2.54 1.27)
			(stroke
				(width 0.1)
				(type default)
			)
			(layer "F.Fab")
		)
		(fp_line
			(start 2.54 -1.27)
			(end 2.54 1.27)
			(stroke
				(width 0.1)
				(type default)
			)
			(layer "F.Fab")
		)
		(fp_line
			(start -2.54 1.27)
			(end -2.54 -1.27)
			(stroke
				(width 0.1)
				(type default)
			)
			(layer "F.Fab")
		)
		(fp_line
			(start -2.54 -1.27)
			(end 2.54 -1.27)
			(stroke
				(width 0.1)
				(type default)
			)
			(layer "F.Fab")
		)
		(fp_text user "2"
			(at 3.219704 -1.783334 0)
			(unlocked yes)
			(layer "F.SilkS")
			(effects
				(font
					(size 0.7874 0.5842)
					(thickness 0.1524)
				)
				(justify left)
			)
		)
		(fp_text user "1"
			(at -2.647696 0.070866 0)
			(unlocked yes)
			(layer "F.SilkS")
			(effects
				(font
					(size 0.7874 0.5842)
					(thickness 0.1524)
				)
				(justify left)
			)
		)
		(fp_text user "2"
			(at 2.406904 -0.005334 0)
			(unlocked yes)
			(layer "B.SilkS")
			(effects
				(font
					(size 0.7874 0.5842)
					(thickness 0.1524)
				)
				(justify left mirror)
			)
		)
		(fp_text user "1"
			(at -2.876296 -0.030734 0)
			(unlocked yes)
			(layer "B.SilkS")
			(effects
				(font
					(size 0.7874 0.5842)
					(thickness 0.1524)
				)
				(justify left mirror)
			)
		)
		(pad "1" thru_hole rect
			(at -1.27 0 180)
			(size 1.6764 1.6764)
			(drill 1.1684)
			(layers "*.Cu" "*.Mask")
			(remove_unused_layers no)
			(net "NODE3_EN")
			(clearance 0)
			(padstack
				(mode front_inner_back)
				(layer "Inner"
					(shape circle)
					(size 1.6764 1.6764)
					(clearance 0)
				)
				(layer "B.Cu"
					(shape rect)
					(size 1.6764 1.6764)
					(clearance 0)
				)
			)
		)
		(pad "2" thru_hole circle
			(at 1.27 0 180)
			(size 1.6764 1.6764)
			(drill 1.1684)
			(layers "*.Cu" "*.Mask")
			(remove_unused_layers no)
			(net "N39398095")
			(clearance 0)
		)
	)
	(footprint ""
		(layer "F.Cu")
		(at 310.308752 -27.523694 180)
		(property "Reference" "R52"
			(at 6.775704 1.30556 0)
			(unlocked yes)
			(layer "F.SilkS")
			(effects
				(font
					(size 0.7874 0.5842)
					(thickness 0.1524)
				)
				(justify left)
			)
		)
		(property "Value" ""
			(at 0 0 180)
			(layer "F.Fab")
			(effects
				(font
					(size 1.27 1.27)
				)
			)
		)
		(duplicate_pad_numbers_are_jumpers no)
		(fp_line
			(start 0.7874 0.4064)
			(end -0.7874 0.4064)
			(stroke
				(width 0.1524)
				(type default)
			)
			(layer "F.SilkS")
		)
		(fp_line
			(start 0.7874 -0.4064)
			(end 0.7874 0.4064)
			(stroke
				(width 0.1524)
				(type default)
			)
			(layer "F.SilkS")
		)
		(fp_line
			(start -0.7874 0.4064)
			(end -0.7874 -0.4064)
			(stroke
				(width 0.1524)
				(type default)
			)
			(layer "F.SilkS")
		)
		(fp_line
			(start -0.7874 -0.4064)
			(end 0.7874 -0.4064)
			(stroke
				(width 0.1524)
				(type default)
			)
			(layer "F.SilkS")
		)
		(fp_poly
			(pts
				(xy -0.508 0.2794) (xy -0.508 0.2286) (xy -0.635 0.2286) (xy -0.635 -0.254) (xy -0.5334 -0.254)
				(xy -0.5334 -0.2794) (xy 0.5334 -0.2794) (xy 0.5334 -0.254) (xy 0.635 -0.254) (xy 0.635 0.254) (xy 0.5334 0.254)
				(xy 0.5334 0.2794)
			)
			(stroke
				(width 0)
				(type default)
			)
			(fill no)
			(layer "F.CrtYd")
		)
		(pad "1" smd rect
			(at 0.40005 0 180)
			(size 0.4572 0.508)
			(layers "F.Cu" "F.Mask" "F.Paste")
			(net "GND")
		)
		(pad "2" smd rect
			(at -0.40005 0 180)
			(size 0.4572 0.508)
			(layers "F.Cu" "F.Mask" "F.Paste")
			(net "ENET10G_4_RS0")
		)
	)
	(footprint ""
		(layer "F.Cu")
		(at 130.101848 -25.440894 180)
		(property "Reference" "R7"
			(at 61.677296 -5.09524 0)
			(unlocked yes)
			(layer "F.SilkS")
			(effects
				(font
					(size 0.7874 0.5842)
					(thickness 0.1524)
				)
				(justify left)
			)
		)
		(property "Value" ""
			(at 0 0 180)
			(layer "F.Fab")
			(effects
				(font
					(size 1.27 1.27)
				)
			)
		)
		(duplicate_pad_numbers_are_jumpers no)
		(fp_line
			(start 0.7874 0.4064)
			(end -0.7874 0.4064)
			(stroke
				(width 0.1524)
				(type default)
			)
			(layer "F.SilkS")
		)
		(fp_line
			(start 0.7874 -0.4064)
			(end 0.7874 0.4064)
			(stroke
				(width 0.1524)
				(type default)
			)
			(layer "F.SilkS")
		)
		(fp_line
			(start -0.7874 0.4064)
			(end -0.7874 -0.4064)
			(stroke
				(width 0.1524)
				(type default)
			)
			(layer "F.SilkS")
		)
		(fp_line
			(start -0.7874 -0.4064)
			(end 0.7874 -0.4064)
			(stroke
				(width 0.1524)
				(type default)
			)
			(layer "F.SilkS")
		)
		(fp_poly
			(pts
				(xy -0.508 0.2794) (xy -0.508 0.2286) (xy -0.635 0.2286) (xy -0.635 -0.254) (xy -0.5334 -0.254)
				(xy -0.5334 -0.2794) (xy 0.5334 -0.2794) (xy 0.5334 -0.254) (xy 0.635 -0.254) (xy 0.635 0.254) (xy 0.5334 0.254)
				(xy 0.5334 0.2794)
			)
			(stroke
				(width 0)
				(type default)
			)
			(fill no)
			(layer "F.CrtYd")
		)
		(pad "1" smd rect
			(at 0.40005 0 180)
			(size 0.4572 0.508)
			(layers "F.Cu" "F.Mask" "F.Paste")
			(net "P3V3_BLAD1")
		)
		(pad "2" smd rect
			(at -0.40005 0 180)
			(size 0.4572 0.508)
			(layers "F.Cu" "F.Mask" "F.Paste")
			(net "ENET10G_1_SCL")
		)
	)
	(footprint ""
		(layer "F.Cu")
		(at 378.431552 -27.776678)
		(property "Reference" "R49"
			(at 33.4772 17.307052 0)
			(unlocked yes)
			(layer "F.SilkS")
			(effects
				(font
					(size 0.7874 0.5842)
					(thickness 0.1524)
				)
				(justify left)
			)
		)
		(property "Value" ""
			(at 0 0 0)
			(layer "F.Fab")
			(effects
				(font
					(size 1.27 1.27)
				)
			)
		)
		(duplicate_pad_numbers_are_jumpers no)
		(fp_line
			(start -0.7874 -0.4064)
			(end 0.7874 -0.4064)
			(stroke
				(width 0.1524)
				(type default)
			)
			(layer "F.SilkS")
		)
		(fp_line
			(start -0.7874 0.4064)
			(end -0.7874 -0.4064)
			(stroke
				(width 0.1524)
				(type default)
			)
			(layer "F.SilkS")
		)
		(fp_line
			(start 0.7874 -0.4064)
			(end 0.7874 0.4064)
			(stroke
				(width 0.1524)
				(type default)
			)
			(layer "F.SilkS")
		)
		(fp_line
			(start 0.7874 0.4064)
			(end -0.7874 0.4064)
			(stroke
				(width 0.1524)
				(type default)
			)
			(layer "F.SilkS")
		)
		(fp_poly
			(pts
				(xy -0.508 0.2794) (xy -0.508 0.2286) (xy -0.635 0.2286) (xy -0.635 -0.254) (xy -0.5334 -0.254)
				(xy -0.5334 -0.2794) (xy 0.5334 -0.2794) (xy 0.5334 -0.254) (xy 0.635 -0.254) (xy 0.635 0.254) (xy 0.5334 0.254)
				(xy 0.5334 0.2794)
			)
			(stroke
				(width 0)
				(type default)
			)
			(fill no)
			(layer "F.CrtYd")
		)
		(pad "1" smd rect
			(at 0.40005 0)
			(size 0.4572 0.508)
			(layers "F.Cu" "F.Mask" "F.Paste")
			(net "GND")
		)
		(pad "2" smd rect
			(at -0.40005 0)
			(size 0.4572 0.508)
			(layers "F.Cu" "F.Mask" "F.Paste")
			(net "ENET10G_3_RS1")
		)
	)
	(footprint ""
		(layer "F.Cu")
		(at 86.480142 -33.7312 90)
		(property "Reference" "L4"
			(at -0.5842 -3.668014 90)
			(unlocked yes)
			(layer "F.SilkS")
			(effects
				(font
					(size 0.7874 0.5842)
					(thickness 0.1524)
				)
				(justify left)
			)
		)
		(property "Value" ""
			(at 0 0 90)
			(layer "F.Fab")
			(effects
				(font
					(size 1.27 1.27)
				)
			)
		)
		(duplicate_pad_numbers_are_jumpers no)
		(fp_line
			(start -1.905 -0.8636)
			(end 1.905 -0.8636)
			(stroke
				(width 0.1524)
				(type default)
			)
			(layer "F.SilkS")
		)
		(fp_line
			(start 1.905 0.8382)
			(end 1.905 -0.8382)
			(stroke
				(width 0.1524)
				(type default)
			)
			(layer "F.SilkS")
		)
		(fp_line
			(start 0.127 0.8382)
			(end 0.127 -0.8382)
			(stroke
				(width 0.1524)
				(type default)
			)
			(layer "F.SilkS")
		)
		(fp_line
			(start -0.127 0.8382)
			(end -0.127 -0.8382)
			(stroke
				(width 0.1524)
				(type default)
			)
			(layer "F.SilkS")
		)
		(fp_line
			(start -1.905 0.8382)
			(end -1.905 -0.8382)
			(stroke
				(width 0.1524)
				(type default)
			)
			(layer "F.SilkS")
		)
		(fp_line
			(start 1.905 0.8636)
			(end -1.905 0.8636)
			(stroke
				(width 0.1524)
				(type default)
			)
			(layer "F.SilkS")
		)
		(fp_rect
			(start -1.524 0.7112)
			(end 1.524 -0.7366)
			(stroke
				(width 0)
				(type default)
			)
			(fill no)
			(layer "F.CrtYd")
		)
		(pad "1" smd rect
			(at 0.94996 0 90)
			(size 1.1176 1.3716)
			(layers "F.Cu" "F.Mask" "F.Paste")
			(net "P3V3_10G_2_VCCR_L")
		)
		(pad "2" smd rect
			(at -0.94996 0 90)
			(size 1.1176 1.3716)
			(layers "F.Cu" "F.Mask" "F.Paste")
			(net "P3V3_10G_2_VCCR")
		)
	)
	(footprint ""
		(layer "F.Cu")
		(at 279.81021 -4.700016 180)
		(property "Reference" "H2"
			(at 0.23622 11.596116 0)
			(unlocked yes)
			(layer "F.SilkS")
			(effects
				(font
					(size 0.7874 0.5842)
					(thickness 0.1524)
				)
				(justify left)
			)
		)
		(property "Value" ""
			(at 0 0 180)
			(layer "F.Fab")
			(effects
				(font
					(size 1.27 1.27)
				)
			)
		)
		(duplicate_pad_numbers_are_jumpers no)
		(fp_poly
			(pts
				(arc
					(start 3.999992 5.999988)
					(mid 0 9.99998)
					(end -3.999992 5.999988)
				)
				(arc
					(start -3.999992 0)
					(mid 0 -3.999992)
					(end 3.999992 0)
				)
			)
			(stroke
				(width 0)
				(type default)
			)
			(fill no)
			(layer "B.CrtYd")
		)
		(fp_poly
			(pts
				(arc
					(start 3.999992 5.999988)
					(mid 0 9.99998)
					(end -3.999992 5.999988)
				)
				(arc
					(start -3.999992 0)
					(mid 0 -3.999992)
					(end 3.999992 0)
				)
			)
			(stroke
				(width 0)
				(type default)
			)
			(fill no)
			(layer "F.CrtYd")
		)
		(pad "" np_thru_hole circle
			(at 0 0 180)
			(size 3.5052 3.5052)
			(drill 3.5052)
			(layers "*.Cu" "*.Mask")
			(clearance 0.381)
			(thermal_gap 0.381)
		)
		(zone
			(layers "F.Cu" "B.Cu" "In1.Cu" "In2.Cu" "In3.Cu" "In4.Cu" "In5.Cu" "In6.Cu")
			(hatch none 0.5)
			(connect_pads
				(clearance 0)
			)
			(min_thickness 0.25)
			(keepout
				(tracks not_allowed)
				(vias allowed)
				(pads allowed)
				(copperpour not_allowed)
				(footprints allowed)
			)
			(placement
				(enabled no)
				(sheetname "")
			)
			(fill
				(thermal_gap 0.5)
				(thermal_bridge_width 0.5)
				(island_removal_mode 0)
			)
			(polygon
				(pts
					(arc
						(start 277.39848 -8.152638)
						(mid 279.81021 -14.207926)
						(end 282.22194 -8.152638)
					)
					(arc
						(start 282.22194 -8.152638)
						(mid 282.108311 -7.989777)
						(end 282.06827 -7.79526)
					)
					(arc
						(start 282.06827 -4.700016)
						(mid 279.81021 -2.441956)
						(end 277.55215 -4.700016)
					)
					(arc
						(start 277.55215 -7.79526)
						(mid 277.512164 -7.9898)
						(end 277.39848 -8.152638)
					)
				)
			)
		)
	)
	(footprint ""
		(layer "F.Cu")
		(at 310.308752 -26.126694 180)
		(property "Reference" "R53"
			(at 6.826504 1.50876 0)
			(unlocked yes)
			(layer "F.SilkS")
			(effects
				(font
					(size 0.7874 0.5842)
					(thickness 0.1524)
				)
				(justify left)
			)
		)
		(property "Value" ""
			(at 0 0 180)
			(layer "F.Fab")
			(effects
				(font
					(size 1.27 1.27)
				)
			)
		)
		(duplicate_pad_numbers_are_jumpers no)
		(fp_line
			(start 0.7874 0.4064)
			(end -0.7874 0.4064)
			(stroke
				(width 0.1524)
				(type default)
			)
			(layer "F.SilkS")
		)
		(fp_line
			(start 0.7874 -0.4064)
			(end 0.7874 0.4064)
			(stroke
				(width 0.1524)
				(type default)
			)
			(layer "F.SilkS")
		)
		(fp_line
			(start -0.7874 0.4064)
			(end -0.7874 -0.4064)
			(stroke
				(width 0.1524)
				(type default)
			)
			(layer "F.SilkS")
		)
		(fp_line
			(start -0.7874 -0.4064)
			(end 0.7874 -0.4064)
			(stroke
				(width 0.1524)
				(type default)
			)
			(layer "F.SilkS")
		)
		(fp_poly
			(pts
				(xy -0.508 0.2794) (xy -0.508 0.2286) (xy -0.635 0.2286) (xy -0.635 -0.254) (xy -0.5334 -0.254)
				(xy -0.5334 -0.2794) (xy 0.5334 -0.2794) (xy 0.5334 -0.254) (xy 0.635 -0.254) (xy 0.635 0.254) (xy 0.5334 0.254)
				(xy 0.5334 0.2794)
			)
			(stroke
				(width 0)
				(type default)
			)
			(fill no)
			(layer "F.CrtYd")
		)
		(pad "1" smd rect
			(at 0.40005 0 180)
			(size 0.4572 0.508)
			(layers "F.Cu" "F.Mask" "F.Paste")
			(net "GND")
		)
		(pad "2" smd rect
			(at -0.40005 0 180)
			(size 0.4572 0.508)
			(layers "F.Cu" "F.Mask" "F.Paste")
			(net "ENET10G_4_RS1")
		)
	)
	(footprint ""
		(layer "F.Cu")
		(at 376.460004 -10.6299)
		(property "Reference" "J6"
			(at -1.0414 -11.166348 0)
			(unlocked yes)
			(layer "F.SilkS")
			(effects
				(font
					(size 0.7874 0.5842)
					(thickness 0.1524)
				)
				(justify left)
			)
		)
		(property "Value" ""
			(at 0 0 0)
			(layer "F.Fab")
			(effects
				(font
					(size 1.27 1.27)
				)
			)
		)
		(duplicate_pad_numbers_are_jumpers no)
		(fp_line
			(start -5.32511 -10.500106)
			(end -5.32511 0)
			(stroke
				(width 0.1524)
				(type default)
			)
			(layer "F.SilkS")
		)
		(fp_line
			(start -5.32511 0)
			(end -5.32511 43.029886)
			(stroke
				(width 0.1524)
				(type default)
			)
			(layer "F.SilkS")
		)
		(fp_line
			(start -5.32511 13.129768)
			(end 5.32511 13.129768)
			(stroke
				(width 0.1524)
				(type default)
			)
			(layer "F.SilkS")
		)
		(fp_line
			(start -5.32511 43.029886)
			(end 5.32511 43.029886)
			(stroke
				(width 0.1524)
				(type default)
			)
			(layer "F.SilkS")
		)
		(fp_line
			(start 5.32511 -10.500106)
			(end -5.32511 -10.500106)
			(stroke
				(width 0.1524)
				(type default)
			)
			(layer "F.SilkS")
		)
		(fp_line
			(start 5.32511 43.029886)
			(end 5.32511 -10.500106)
			(stroke
				(width 0.1524)
				(type default)
			)
			(layer "F.SilkS")
		)
		(fp_poly
			(pts
				(xy -7.80669 4.393438) (xy -6.53161 5.668772) (xy -6.523228 5.6769) (xy -5.956808 3.764788)
			)
			(stroke
				(width 0)
				(type default)
			)
			(fill yes)
			(layer "F.SilkS")
		)
		(fp_poly
			(pts
				(arc
					(start 2.758694 0)
					(mid -2.758694 0)
					(end 2.758694 0)
				)
			)
			(stroke
				(width 0)
				(type default)
			)
			(fill no)
			(layer "B.CrtYd")
		)
		(fp_poly
			(pts
				(arc
					(start 2.758694 5.62991)
					(mid -2.758694 5.62991)
					(end 2.758694 5.62991)
				)
			)
			(stroke
				(width 0)
				(type default)
			)
			(fill no)
			(layer "B.CrtYd")
		)
		(fp_poly
			(pts
				(arc
					(start 2.95275 -6.620002)
					(mid -2.95275 -6.620002)
					(end 2.95275 -6.620002)
				)
			)
			(stroke
				(width 0)
				(type default)
			)
			(fill no)
			(layer "B.CrtYd")
		)
		(fp_poly
			(pts
				(xy -5.32511 0) (xy -5.32511 43.029886) (xy 5.32511 43.029886) (xy 5.32511 -10.500106) (xy -5.32511 -10.500106)
			)
			(stroke
				(width 0)
				(type default)
			)
			(fill no)
			(layer "F.CrtYd")
		)
		(fp_line
			(start -5.32511 -10.500106)
			(end -5.32511 0)
			(stroke
				(width 0.1)
				(type default)
			)
			(layer "F.Fab")
		)
		(fp_line
			(start -5.32511 0)
			(end -5.32511 43.029886)
			(stroke
				(width 0.1)
				(type default)
			)
			(layer "F.Fab")
		)
		(fp_line
			(start -5.32511 13.129768)
			(end 5.32511 13.129768)
			(stroke
				(width 0.1)
				(type default)
			)
			(layer "F.Fab")
		)
		(fp_line
			(start -5.32511 43.029886)
			(end 5.32511 43.029886)
			(stroke
				(width 0.1)
				(type default)
			)
			(layer "F.Fab")
		)
		(fp_line
			(start 5.32511 -10.500106)
			(end -5.32511 -10.500106)
			(stroke
				(width 0.1)
				(type default)
			)
			(layer "F.Fab")
		)
		(fp_line
			(start 5.32511 43.029886)
			(end 5.32511 -10.500106)
			(stroke
				(width 0.1)
				(type default)
			)
			(layer "F.Fab")
		)
		(fp_poly
			(pts
				(xy -7.86638 -0.8636) (xy -7.86638 0.9398) (xy -7.86638 0.951484) (xy -6.11378 0)
			)
			(stroke
				(width 0)
				(type default)
			)
			(fill yes)
			(layer "F.Fab")
		)
		(fp_text user "1"
			(at -6.082284 3.796284 0)
			(unlocked yes)
			(layer "F.SilkS")
			(effects
				(font
					(size 0.7874 0.5842)
					(thickness 0.1524)
				)
				(justify left)
			)
		)
		(fp_text user "1"
			(at -2.9464 0.043688 0)
			(unlocked yes)
			(layer "B.SilkS")
			(effects
				(font
					(size 0.7874 0.5842)
					(thickness 0.1524)
				)
				(justify left mirror)
			)
		)
		(fp_text user "1"
			(at -2.9464 0.043688 0)
			(unlocked yes)
			(layer "B.Fab")
			(effects
				(font
					(size 0.7874 0.5842)
					(thickness 0.000001)
				)
				(justify left mirror)
			)
		)
		(fp_text user "1"
			(at -6.031484 -0.039116 0)
			(unlocked yes)
			(layer "F.Fab")
			(effects
				(font
					(size 0.7874 0.5842)
					(thickness 0.000001)
				)
				(justify left)
			)
		)
		(pad "1" thru_hole circle
			(at 0 0)
			(size 5.4102 5.4102)
			(drill 4.0132)
			(layers "*.Cu" "*.Mask")
			(remove_unused_layers no)
			(net "GND")
			(clearance -0.4445)
		)
		(pad "2" thru_hole circle
			(at 0 5.62991)
			(size 5.4102 5.4102)
			(drill 4.0132)
			(layers "*.Cu" "*.Mask")
			(remove_unused_layers no)
			(net "GND")
			(clearance -0.4445)
		)
		(pad "3" thru_hole circle
			(at 0 -6.620002)
			(size 5.7912 5.7912)
			(drill 4.0132)
			(layers "*.Cu" "*.Mask")
			(remove_unused_layers no)
			(net "GND")
			(clearance -0.635)
		)
	)
	(footprint ""
		(layer "F.Cu")
		(at 88.017096 -23.621746 -90)
		(property "Reference" "C2"
			(at -1.092708 4.608322 90)
			(unlocked yes)
			(layer "F.SilkS")
			(effects
				(font
					(size 0.7874 0.5842)
					(thickness 0.1524)
				)
			)
		)
		(property "Value" ""
			(at 0 0 270)
			(layer "F.Fab")
			(effects
				(font
					(size 1.27 1.27)
				)
			)
		)
		(duplicate_pad_numbers_are_jumpers no)
		(fp_line
			(start -1.2954 0.5842)
			(end -1.2954 -0.5842)
			(stroke
				(width 0.1524)
				(type default)
			)
			(layer "F.SilkS")
		)
		(fp_line
			(start 1.2954 0.5842)
			(end -1.2954 0.5842)
			(stroke
				(width 0.1524)
				(type default)
			)
			(layer "F.SilkS")
		)
		(fp_line
			(start -1.2954 -0.5842)
			(end 1.2954 -0.5842)
			(stroke
				(width 0.1524)
				(type default)
			)
			(layer "F.SilkS")
		)
		(fp_line
			(start 0 -0.5842)
			(end 0 0.5842)
			(stroke
				(width 0.1524)
				(type default)
			)
			(layer "F.SilkS")
		)
		(fp_line
			(start 1.2954 -0.5842)
			(end 1.2954 0.5842)
			(stroke
				(width 0.1524)
				(type default)
			)
			(layer "F.SilkS")
		)
		(fp_poly
			(pts
				(xy 0.8636 -0.4572) (xy 0.8636 -0.3556) (xy 1.143 -0.3556) (xy 1.143 0.3556) (xy 0.8636 0.3556)
				(xy 0.8636 0.4572) (xy -0.8636 0.4572) (xy -0.8636 0.3556) (xy -1.143 0.3556) (xy -1.143 -0.3556)
				(xy -0.8636 -0.3556) (xy -0.8636 -0.4572)
			)
			(stroke
				(width 0)
				(type default)
			)
			(fill no)
			(layer "F.CrtYd")
		)
		(fp_line
			(start -0.884936 0.504952)
			(end -0.884936 -0.504952)
			(stroke
				(width 0.1)
				(type default)
			)
			(layer "F.Fab")
		)
		(fp_line
			(start 0.884936 0.504952)
			(end -0.884936 0.504952)
			(stroke
				(width 0.1)
				(type default)
			)
			(layer "F.Fab")
		)
		(fp_line
			(start -0.884936 -0.504952)
			(end 0.884936 -0.504952)
			(stroke
				(width 0.1)
				(type default)
			)
			(layer "F.Fab")
		)
		(fp_line
			(start 0.884936 -0.504952)
			(end 0.884936 0.504952)
			(stroke
				(width 0.1)
				(type default)
			)
			(layer "F.Fab")
		)
		(pad "1" smd rect
			(at 0.7366 0)
			(size 0.7112 0.8128)
			(layers "F.Cu" "F.Mask" "F.Paste")
			(net "P12V")
		)
		(pad "2" smd rect
			(at -0.7366 0)
			(size 0.7112 0.8128)
			(layers "F.Cu" "F.Mask" "F.Paste")
			(net "GND")
		)
	)
	(footprint ""
		(layer "F.Cu")
		(at 77.920088 -10.6299)
		(property "Reference" "J11"
			(at -5.4102 -11.267948 0)
			(unlocked yes)
			(layer "F.SilkS")
			(effects
				(font
					(size 0.7874 0.5842)
					(thickness 0.1524)
				)
				(justify left)
			)
		)
		(property "Value" ""
			(at 0 0 0)
			(layer "F.Fab")
			(effects
				(font
					(size 1.27 1.27)
				)
			)
		)
		(duplicate_pad_numbers_are_jumpers no)
		(fp_line
			(start -5.32511 -10.500106)
			(end -5.32511 0)
			(stroke
				(width 0.1524)
				(type default)
			)
			(layer "F.SilkS")
		)
		(fp_line
			(start -5.32511 0)
			(end -5.32511 43.029886)
			(stroke
				(width 0.1524)
				(type default)
			)
			(layer "F.SilkS")
		)
		(fp_line
			(start -5.32511 13.129768)
			(end 5.32511 13.129768)
			(stroke
				(width 0.1524)
				(type default)
			)
			(layer "F.SilkS")
		)
		(fp_line
			(start -5.32511 43.029886)
			(end 5.32511 43.029886)
			(stroke
				(width 0.1524)
				(type default)
			)
			(layer "F.SilkS")
		)
		(fp_line
			(start 5.32511 -10.500106)
			(end -5.32511 -10.500106)
			(stroke
				(width 0.1524)
				(type default)
			)
			(layer "F.SilkS")
		)
		(fp_line
			(start 5.32511 43.029886)
			(end 5.32511 -10.500106)
			(stroke
				(width 0.1524)
				(type default)
			)
			(layer "F.SilkS")
		)
		(fp_poly
			(pts
				(xy -7.86638 -0.8636) (xy -7.86638 0.9398) (xy -7.86638 0.951484) (xy -6.11378 0)
			)
			(stroke
				(width 0)
				(type default)
			)
			(fill yes)
			(layer "F.SilkS")
		)
		(fp_poly
			(pts
				(arc
					(start 2.758694 0)
					(mid -2.758694 0)
					(end 2.758694 0)
				)
			)
			(stroke
				(width 0)
				(type default)
			)
			(fill no)
			(layer "B.CrtYd")
		)
		(fp_poly
			(pts
				(arc
					(start 2.758694 5.62991)
					(mid -2.758694 5.62991)
					(end 2.758694 5.62991)
				)
			)
			(stroke
				(width 0)
				(type default)
			)
			(fill no)
			(layer "B.CrtYd")
		)
		(fp_poly
			(pts
				(arc
					(start 2.95275 -6.620002)
					(mid -2.95275 -6.620002)
					(end 2.95275 -6.620002)
				)
			)
			(stroke
				(width 0)
				(type default)
			)
			(fill no)
			(layer "B.CrtYd")
		)
		(fp_poly
			(pts
				(xy -5.32511 0) (xy -5.32511 43.029886) (xy 5.32511 43.029886) (xy 5.32511 -10.500106) (xy -5.32511 -10.500106)
			)
			(stroke
				(width 0)
				(type default)
			)
			(fill no)
			(layer "F.CrtYd")
		)
		(fp_line
			(start -5.32511 -10.500106)
			(end -5.32511 0)
			(stroke
				(width 0.1)
				(type default)
			)
			(layer "F.Fab")
		)
		(fp_line
			(start -5.32511 0)
			(end -5.32511 43.029886)
			(stroke
				(width 0.1)
				(type default)
			)
			(layer "F.Fab")
		)
		(fp_line
			(start -5.32511 13.129768)
			(end 5.32511 13.129768)
			(stroke
				(width 0.1)
				(type default)
			)
			(layer "F.Fab")
		)
		(fp_line
			(start -5.32511 43.029886)
			(end 5.32511 43.029886)
			(stroke
				(width 0.1)
				(type default)
			)
			(layer "F.Fab")
		)
		(fp_line
			(start 5.32511 -10.500106)
			(end -5.32511 -10.500106)
			(stroke
				(width 0.1)
				(type default)
			)
			(layer "F.Fab")
		)
		(fp_line
			(start 5.32511 43.029886)
			(end 5.32511 -10.500106)
			(stroke
				(width 0.1)
				(type default)
			)
			(layer "F.Fab")
		)
		(fp_poly
			(pts
				(xy -7.86638 -0.8636) (xy -7.86638 0.9398) (xy -7.86638 0.951484) (xy -6.11378 0)
			)
			(stroke
				(width 0)
				(type default)
			)
			(fill yes)
			(layer "F.Fab")
		)
		(fp_text user "1"
			(at -6.031484 -0.039116 0)
			(unlocked yes)
			(layer "F.SilkS")
			(effects
				(font
					(size 0.7874 0.5842)
					(thickness 0.1524)
				)
				(justify left)
			)
		)
		(fp_text user "1"
			(at -2.9464 0.043688 0)
			(unlocked yes)
			(layer "B.SilkS")
			(effects
				(font
					(size 0.7874 0.5842)
					(thickness 0.1524)
				)
				(justify left mirror)
			)
		)
		(fp_text user "1"
			(at -2.9464 0.043688 0)
			(unlocked yes)
			(layer "B.Fab")
			(effects
				(font
					(size 0.7874 0.5842)
					(thickness 0.000001)
				)
				(justify left mirror)
			)
		)
		(fp_text user "1"
			(at -6.031484 -0.039116 0)
			(unlocked yes)
			(layer "F.Fab")
			(effects
				(font
					(size 0.7874 0.5842)
					(thickness 0.000001)
				)
				(justify left)
			)
		)
		(pad "1" thru_hole circle
			(at 0 0)
			(size 5.4102 5.4102)
			(drill 4.0132)
			(layers "*.Cu" "*.Mask")
			(remove_unused_layers no)
			(net "GND")
			(clearance -0.4445)
		)
		(pad "2" thru_hole circle
			(at 0 5.62991)
			(size 5.4102 5.4102)
			(drill 4.0132)
			(layers "*.Cu" "*.Mask")
			(remove_unused_layers no)
			(net "GND")
			(clearance -0.4445)
		)
		(pad "3" thru_hole circle
			(at 0 -6.620002)
			(size 5.7912 5.7912)
			(drill 4.0132)
			(layers "*.Cu" "*.Mask")
			(remove_unused_layers no)
			(net "GND")
			(clearance -0.635)
		)
	)
	(footprint ""
		(layer "F.Cu")
		(at 117.31244 -24.36241)
		(property "Reference" "R8"
			(at -61.341 5.115052 0)
			(unlocked yes)
			(layer "F.SilkS")
			(effects
				(font
					(size 0.7874 0.5842)
					(thickness 0.1524)
				)
				(justify left)
			)
		)
		(property "Value" ""
			(at 0 0 0)
			(layer "F.Fab")
			(effects
				(font
					(size 1.27 1.27)
				)
			)
		)
		(duplicate_pad_numbers_are_jumpers no)
		(fp_line
			(start -0.7874 -0.4064)
			(end 0.7874 -0.4064)
			(stroke
				(width 0.1524)
				(type default)
			)
			(layer "F.SilkS")
		)
		(fp_line
			(start -0.7874 0.4064)
			(end -0.7874 -0.4064)
			(stroke
				(width 0.1524)
				(type default)
			)
			(layer "F.SilkS")
		)
		(fp_line
			(start 0.7874 -0.4064)
			(end 0.7874 0.4064)
			(stroke
				(width 0.1524)
				(type default)
			)
			(layer "F.SilkS")
		)
		(fp_line
			(start 0.7874 0.4064)
			(end -0.7874 0.4064)
			(stroke
				(width 0.1524)
				(type default)
			)
			(layer "F.SilkS")
		)
		(fp_poly
			(pts
				(xy -0.508 0.2794) (xy -0.508 0.2286) (xy -0.635 0.2286) (xy -0.635 -0.254) (xy -0.5334 -0.254)
				(xy -0.5334 -0.2794) (xy 0.5334 -0.2794) (xy 0.5334 -0.254) (xy 0.635 -0.254) (xy 0.635 0.254) (xy 0.5334 0.254)
				(xy 0.5334 0.2794)
			)
			(stroke
				(width 0)
				(type default)
			)
			(fill no)
			(layer "F.CrtYd")
		)
		(pad "1" smd rect
			(at 0.40005 0)
			(size 0.4572 0.508)
			(layers "F.Cu" "F.Mask" "F.Paste")
			(net "P3V3_BLAD1")
		)
		(pad "2" smd rect
			(at -0.40005 0)
			(size 0.4572 0.508)
			(layers "F.Cu" "F.Mask" "F.Paste")
			(net "ENET10G_2_SCL")
		)
	)
	(footprint ""
		(layer "F.Cu")
		(at 128.530096 -2.100072 180)
		(property "Reference" "J24"
			(at -4.923028 -1.445768 90)
			(unlocked yes)
			(layer "F.SilkS")
			(effects
				(font
					(size 0.7874 0.5842)
					(thickness 0.1524)
				)
				(justify left)
			)
		)
		(property "Value" ""
			(at 0 0 180)
			(layer "F.Fab")
			(effects
				(font
					(size 1.27 1.27)
				)
			)
		)
		(duplicate_pad_numbers_are_jumpers no)
		(fp_line
			(start 13.999972 18.375122)
			(end 13.999972 6.891528)
			(stroke
				(width 0.1524)
				(type default)
			)
			(layer "F.SilkS")
		)
		(fp_line
			(start 13.999972 2.522728)
			(end 13.999972 -14.675104)
			(stroke
				(width 0.1524)
				(type default)
			)
			(layer "F.SilkS")
		)
		(fp_line
			(start 13.999972 -14.675104)
			(end -3.999992 -14.675104)
			(stroke
				(width 0.1524)
				(type default)
			)
			(layer "F.SilkS")
		)
		(fp_line
			(start 10.999978 15.375128)
			(end 10.999978 -11.67511)
			(stroke
				(width 0.1524)
				(type default)
			)
			(layer "F.SilkS")
		)
		(fp_line
			(start 10.999978 -11.67511)
			(end -0.999998 -11.67511)
			(stroke
				(width 0.1524)
				(type default)
			)
			(layer "F.SilkS")
		)
		(fp_line
			(start -0.999998 15.375128)
			(end 10.999978 15.375128)
			(stroke
				(width 0.1524)
				(type default)
			)
			(layer "F.SilkS")
		)
		(fp_line
			(start -0.999998 -11.67511)
			(end -0.999998 15.375128)
			(stroke
				(width 0.1524)
				(type default)
			)
			(layer "F.SilkS")
		)
		(fp_line
			(start -3.999992 18.375122)
			(end 13.999972 18.375122)
			(stroke
				(width 0.1524)
				(type default)
			)
			(layer "F.SilkS")
		)
		(fp_line
			(start -3.999992 -14.675104)
			(end -3.999992 18.375122)
			(stroke
				(width 0.1524)
				(type default)
			)
			(layer "F.SilkS")
		)
		(fp_poly
			(pts
				(xy -2.261108 0.508) (xy -2.261108 -0.508) (xy -1.245108 0)
			)
			(stroke
				(width 0)
				(type default)
			)
			(fill yes)
			(layer "F.SilkS")
		)
		(fp_line
			(start 13.999972 18.042128)
			(end 13.999972 10.828528)
			(stroke
				(width 0.1524)
				(type default)
			)
			(layer "B.SilkS")
		)
		(fp_line
			(start 13.999972 6.942328)
			(end 13.999972 5.291328)
			(stroke
				(width 0.1524)
				(type default)
			)
			(layer "B.SilkS")
		)
		(fp_line
			(start 13.999972 4.097528)
			(end 13.999972 -14.675104)
			(stroke
				(width 0.1524)
				(type default)
			)
			(layer "B.SilkS")
		)
		(fp_line
			(start 13.999972 -14.675104)
			(end -3.999992 -14.675104)
			(stroke
				(width 0.1524)
				(type default)
			)
			(layer "B.SilkS")
		)
		(fp_line
			(start 11.283696 18.375122)
			(end 13.417296 18.375122)
			(stroke
				(width 0.1524)
				(type default)
			)
			(layer "B.SilkS")
		)
		(fp_line
			(start -3.999992 18.375122)
			(end 10.318496 18.375122)
			(stroke
				(width 0.1524)
				(type default)
			)
			(layer "B.SilkS")
		)
		(fp_line
			(start -3.999992 14.105128)
			(end -3.999992 18.375122)
			(stroke
				(width 0.1524)
				(type default)
			)
			(layer "B.SilkS")
		)
		(fp_line
			(start -3.999992 7.755128)
			(end -3.999992 8.948928)
			(stroke
				(width 0.1524)
				(type default)
			)
			(layer "B.SilkS")
		)
		(fp_line
			(start -3.999992 3.360928)
			(end -3.999992 4.249928)
			(stroke
				(width 0.1524)
				(type default)
			)
			(layer "B.SilkS")
		)
		(fp_line
			(start -3.999992 -14.675104)
			(end -3.999992 1.557528)
			(stroke
				(width 0.1524)
				(type default)
			)
			(layer "B.SilkS")
		)
		(fp_poly
			(pts
				(xy 9.49198 11.707876) (xy 9.49198 11.608054) (xy 10.50798 11.608054) (xy 10.50798 -0.608076) (xy 0.508 -0.608076)
				(xy 0.508 -0.508) (xy -0.508 -0.508) (xy -0.508 11.707876)
			)
			(stroke
				(width 0)
				(type default)
			)
			(fill no)
			(layer "B.CrtYd")
		)
		(fp_poly
			(pts
				(xy -0.999998 15.375128) (xy 10.999978 15.375128) (xy 10.999978 -11.67511) (xy -0.999998 -11.67511)
			)
			(stroke
				(width 0)
				(type default)
			)
			(fill no)
			(layer "F.CrtYd")
		)
		(fp_line
			(start 13.999972 18.375122)
			(end 13.999972 -14.675104)
			(stroke
				(width 0.1)
				(type default)
			)
			(layer "B.Fab")
		)
		(fp_line
			(start 13.999972 -14.675104)
			(end -3.999992 -14.675104)
			(stroke
				(width 0.1)
				(type default)
			)
			(layer "B.Fab")
		)
		(fp_line
			(start -3.999992 18.375122)
			(end 13.999972 18.375122)
			(stroke
				(width 0.1)
				(type default)
			)
			(layer "B.Fab")
		)
		(fp_line
			(start -3.999992 -14.675104)
			(end -3.999992 18.375122)
			(stroke
				(width 0.1)
				(type default)
			)
			(layer "B.Fab")
		)
		(fp_line
			(start 10.999978 15.375128)
			(end 10.999978 -11.67511)
			(stroke
				(width 0.1)
				(type default)
			)
			(layer "F.Fab")
		)
		(fp_line
			(start 10.999978 -11.67511)
			(end -0.999998 -11.67511)
			(stroke
				(width 0.1)
				(type default)
			)
			(layer "F.Fab")
		)
		(fp_line
			(start -0.999998 15.375128)
			(end 10.999978 15.375128)
			(stroke
				(width 0.1)
				(type default)
			)
			(layer "F.Fab")
		)
		(fp_line
			(start -0.999998 -11.67511)
			(end -0.999998 15.375128)
			(stroke
				(width 0.1)
				(type default)
			)
			(layer "F.Fab")
		)
		(fp_poly
			(pts
				(xy -2.261108 0.508) (xy -2.261108 -0.508) (xy -1.245108 0)
			)
			(stroke
				(width 0)
				(type default)
			)
			(fill yes)
			(layer "F.Fab")
		)
		(fp_text user "PRESS-FIT"
			(at 11.840718 -1.24333 90)
			(unlocked yes)
			(layer "F.SilkS")
			(effects
				(font
					(size 1.6002 1.1938)
					(thickness 0.1524)
				)
				(justify left)
			)
		)
		(fp_text user "6"
			(at 10.002012 16.057118 0)
			(unlocked yes)
			(layer "F.SilkS")
			(effects
				(font
					(size 0.7874 0.5842)
					(thickness 0.1524)
				)
			)
		)
		(fp_text user "5"
			(at 7.995412 16.006318 0)
			(unlocked yes)
			(layer "F.SilkS")
			(effects
				(font
					(size 0.7874 0.5842)
					(thickness 0.1524)
				)
			)
		)
		(fp_text user "4"
			(at 6.065012 16.057118 0)
			(unlocked yes)
			(layer "F.SilkS")
			(effects
				(font
					(size 0.7874 0.5842)
					(thickness 0.1524)
				)
			)
		)
		(fp_text user "3"
			(at 4.109212 15.980918 0)
			(unlocked yes)
			(layer "F.SilkS")
			(effects
				(font
					(size 0.7874 0.5842)
					(thickness 0.1524)
				)
			)
		)
		(fp_text user "2"
			(at 2.178812 16.057118 0)
			(unlocked yes)
			(layer "F.SilkS")
			(effects
				(font
					(size 0.7874 0.5842)
					(thickness 0.1524)
				)
			)
		)
		(fp_text user "1"
			(at -0.056388 16.006318 0)
			(unlocked yes)
			(layer "F.SilkS")
			(effects
				(font
					(size 0.7874 0.5842)
					(thickness 0.1524)
				)
			)
		)
		(fp_text user "G"
			(at -1.615186 8.4455 0)
			(unlocked yes)
			(layer "F.SilkS")
			(effects
				(font
					(size 0.7874 0.5842)
					(thickness 0.1524)
				)
			)
		)
		(fp_text user "I"
			(at -1.649222 11.210798 180)
			(unlocked yes)
			(layer "F.SilkS")
			(effects
				(font
					(size 0.7874 0.5842)
					(thickness 0.1524)
				)
			)
		)
		(fp_text user "H"
			(at -1.649222 9.81075 180)
			(unlocked yes)
			(layer "F.SilkS")
			(effects
				(font
					(size 0.7874 0.5842)
					(thickness 0.1524)
				)
			)
		)
		(fp_text user "A"
			(at -1.656588 -0.856996 0)
			(unlocked yes)
			(layer "F.SilkS")
			(effects
				(font
					(size 0.7874 0.5842)
					(thickness 0.1524)
				)
			)
		)
		(fp_text user "E"
			(at -1.665986 5.530596 0)
			(unlocked yes)
			(layer "F.SilkS")
			(effects
				(font
					(size 0.7874 0.5842)
					(thickness 0.1524)
				)
			)
		)
		(fp_text user "C"
			(at -1.665986 2.768092 0)
			(unlocked yes)
			(layer "F.SilkS")
			(effects
				(font
					(size 0.7874 0.5842)
					(thickness 0.1524)
				)
			)
		)
		(fp_text user "F"
			(at -1.716786 6.924548 0)
			(unlocked yes)
			(layer "F.SilkS")
			(effects
				(font
					(size 0.7874 0.5842)
					(thickness 0.1524)
				)
			)
		)
		(fp_text user "D"
			(at -1.716786 4.162044 0)
			(unlocked yes)
			(layer "F.SilkS")
			(effects
				(font
					(size 0.7874 0.5842)
					(thickness 0.1524)
				)
			)
		)
		(fp_text user "B"
			(at -1.716786 1.29794 0)
			(unlocked yes)
			(layer "F.SilkS")
			(effects
				(font
					(size 0.7874 0.5842)
					(thickness 0.1524)
				)
			)
		)
		(fp_text user "6"
			(at 9.99998 -1.666748 180)
			(unlocked yes)
			(layer "B.SilkS")
			(effects
				(font
					(size 0.7874 0.5842)
					(thickness 0.000001)
				)
				(justify mirror)
			)
		)
		(fp_text user "5"
			(at 7.96798 -1.615948 180)
			(unlocked yes)
			(layer "B.SilkS")
			(effects
				(font
					(size 0.7874 0.5842)
					(thickness 0.000001)
				)
				(justify mirror)
			)
		)
		(fp_text user "4"
			(at 5.88518 -1.615948 180)
			(unlocked yes)
			(layer "B.SilkS")
			(effects
				(font
					(size 0.7874 0.5842)
					(thickness 0.000001)
				)
				(justify mirror)
			)
		)
		(fp_text user "3"
			(at 3.90398 -1.615948 180)
			(unlocked yes)
			(layer "B.SilkS")
			(effects
				(font
					(size 0.7874 0.5842)
					(thickness 0.000001)
				)
				(justify mirror)
			)
		)
		(fp_text user "2"
			(at 1.97358 -1.615948 180)
			(unlocked yes)
			(layer "B.SilkS")
			(effects
				(font
					(size 0.7874 0.5842)
					(thickness 0.000001)
				)
				(justify mirror)
			)
		)
		(fp_text user "1"
			(at -0.00762 -1.615948 180)
			(unlocked yes)
			(layer "B.SilkS")
			(effects
				(font
					(size 0.7874 0.5842)
					(thickness 0.000001)
				)
				(justify mirror)
			)
		)
		(fp_text user "C"
			(at -0.903986 1.929892 0)
			(unlocked yes)
			(layer "B.SilkS")
			(effects
				(font
					(size 0.7874 0.5842)
					(thickness 0.1524)
				)
				(justify mirror)
			)
		)
		(fp_text user "F"
			(at -1.284986 6.772148 0)
			(unlocked yes)
			(layer "B.SilkS")
			(effects
				(font
					(size 0.7874 0.5842)
					(thickness 0.1524)
				)
				(justify mirror)
			)
		)
		(fp_text user "E"
			(at -1.310386 5.809996 0)
			(unlocked yes)
			(layer "B.SilkS")
			(effects
				(font
					(size 0.7874 0.5842)
					(thickness 0.1524)
				)
				(justify mirror)
			)
		)
		(fp_text user "G"
			(at -1.361186 7.9375 0)
			(unlocked yes)
			(layer "B.SilkS")
			(effects
				(font
					(size 0.7874 0.5842)
					(thickness 0.1524)
				)
				(justify mirror)
			)
		)
		(fp_text user "I"
			(at -1.547622 11.515598 180)
			(unlocked yes)
			(layer "B.SilkS")
			(effects
				(font
					(size 0.7874 0.5842)
					(thickness 0.1524)
				)
				(justify mirror)
			)
		)
		(fp_text user "H"
			(at -1.547622 10.11555 180)
			(unlocked yes)
			(layer "B.SilkS")
			(effects
				(font
					(size 0.7874 0.5842)
					(thickness 0.1524)
				)
				(justify mirror)
			)
		)
		(fp_text user "B"
			(at -1.589786 1.14554 0)
			(unlocked yes)
			(layer "B.SilkS")
			(effects
				(font
					(size 0.7874 0.5842)
					(thickness 0.1524)
				)
				(justify mirror)
			)
		)
		(fp_text user "A"
			(at -1.681988 -0.094996 0)
			(unlocked yes)
			(layer "B.SilkS")
			(effects
				(font
					(size 0.7874 0.5842)
					(thickness 0.1524)
				)
				(justify mirror)
			)
		)
		(fp_text user "D"
			(at -2.097786 4.263644 0)
			(unlocked yes)
			(layer "B.SilkS")
			(effects
				(font
					(size 0.7874 0.5842)
					(thickness 0.1524)
				)
				(justify mirror)
			)
		)
		(fp_text user "PRESS-FIT"
			(at -2.580132 15.219934 0)
			(unlocked yes)
			(layer "B.SilkS")
			(effects
				(font
					(size 1.6002 1.1938)
					(thickness 0.1524)
				)
				(justify left mirror)
			)
		)
		(fp_text user "PRESS-FIT"
			(at 12.75969 -0.0381 270)
			(unlocked yes)
			(layer "B.Fab")
			(effects
				(font
					(size 1.6002 1.1938)
					(thickness 0.000001)
				)
				(justify left mirror)
			)
		)
		(fp_text user "6"
			(at 9.99998 -1.666748 180)
			(unlocked yes)
			(layer "B.Fab")
			(effects
				(font
					(size 0.7874 0.5842)
					(thickness 0.000001)
				)
				(justify mirror)
			)
		)
		(fp_text user "5"
			(at 7.96798 -1.615948 180)
			(unlocked yes)
			(layer "B.Fab")
			(effects
				(font
					(size 0.7874 0.5842)
					(thickness 0.000001)
				)
				(justify mirror)
			)
		)
		(fp_text user "4"
			(at 5.88518 -1.615948 180)
			(unlocked yes)
			(layer "B.Fab")
			(effects
				(font
					(size 0.7874 0.5842)
					(thickness 0.000001)
				)
				(justify mirror)
			)
		)
		(fp_text user "3"
			(at 3.90398 -1.615948 180)
			(unlocked yes)
			(layer "B.Fab")
			(effects
				(font
					(size 0.7874 0.5842)
					(thickness 0.000001)
				)
				(justify mirror)
			)
		)
		(fp_text user "2"
			(at 1.97358 -1.615948 180)
			(unlocked yes)
			(layer "B.Fab")
			(effects
				(font
					(size 0.7874 0.5842)
					(thickness 0.000001)
				)
				(justify mirror)
			)
		)
		(fp_text user "1"
			(at -0.00762 -1.615948 180)
			(unlocked yes)
			(layer "B.Fab")
			(effects
				(font
					(size 0.7874 0.5842)
					(thickness 0.000001)
				)
				(justify mirror)
			)
		)
		(fp_text user "A"
			(at -1.50622 -0.041148 180)
			(unlocked yes)
			(layer "B.Fab")
			(effects
				(font
					(size 0.7874 0.5842)
					(thickness 0.000001)
				)
				(justify mirror)
			)
		)
		(fp_text user "I"
			(at -1.522222 11.210798 180)
			(unlocked yes)
			(layer "B.Fab")
			(effects
				(font
					(size 0.7874 0.5842)
					(thickness 0.000001)
				)
				(justify mirror)
			)
		)
		(fp_text user "H"
			(at -1.522222 9.81075 180)
			(unlocked yes)
			(layer "B.Fab")
			(effects
				(font
					(size 0.7874 0.5842)
					(thickness 0.000001)
				)
				(justify mirror)
			)
		)
		(fp_text user "G"
			(at -1.522222 8.410956 180)
			(unlocked yes)
			(layer "B.Fab")
			(effects
				(font
					(size 0.7874 0.5842)
					(thickness 0.000001)
				)
				(justify mirror)
			)
		)
		(fp_text user "F"
			(at -1.522222 7.010908 180)
			(unlocked yes)
			(layer "B.Fab")
			(effects
				(font
					(size 0.7874 0.5842)
					(thickness 0.000001)
				)
				(justify mirror)
			)
		)
		(fp_text user "E"
			(at -1.522222 5.61086 180)
			(unlocked yes)
			(layer "B.Fab")
			(effects
				(font
					(size 0.7874 0.5842)
					(thickness 0.000001)
				)
				(justify mirror)
			)
		)
		(fp_text user "D"
			(at -1.522222 4.210812 180)
			(unlocked yes)
			(layer "B.Fab")
			(effects
				(font
					(size 0.7874 0.5842)
					(thickness 0.000001)
				)
				(justify mirror)
			)
		)
		(fp_text user "C"
			(at -1.522222 2.810764 180)
			(unlocked yes)
			(layer "B.Fab")
			(effects
				(font
					(size 0.7874 0.5842)
					(thickness 0.000001)
				)
				(justify mirror)
			)
		)
		(fp_text user "B"
			(at -1.522222 1.410716 180)
			(unlocked yes)
			(layer "B.Fab")
			(effects
				(font
					(size 0.7874 0.5842)
					(thickness 0.000001)
				)
				(justify mirror)
			)
		)
		(fp_text user "PRESS-FIT"
			(at 12.758674 14.569186 270)
			(unlocked yes)
			(layer "F.Fab")
			(effects
				(font
					(size 1.6002 1.1938)
					(thickness 0.000001)
				)
				(justify left)
			)
		)
		(fp_text user "6"
			(at 10.12698 16.013938 180)
			(unlocked yes)
			(layer "F.Fab")
			(effects
				(font
					(size 0.7874 0.5842)
					(thickness 0.000001)
				)
			)
		)
		(fp_text user "5"
			(at 8.09498 16.064738 180)
			(unlocked yes)
			(layer "F.Fab")
			(effects
				(font
					(size 0.7874 0.5842)
					(thickness 0.000001)
				)
			)
		)
		(fp_text user "4"
			(at 6.01218 16.064738 180)
			(unlocked yes)
			(layer "F.Fab")
			(effects
				(font
					(size 0.7874 0.5842)
					(thickness 0.000001)
				)
			)
		)
		(fp_text user "3"
			(at 4.03098 16.064738 180)
			(unlocked yes)
			(layer "F.Fab")
			(effects
				(font
					(size 0.7874 0.5842)
					(thickness 0.000001)
				)
			)
		)
		(fp_text user "2"
			(at 2.10058 16.064738 180)
			(unlocked yes)
			(layer "F.Fab")
			(effects
				(font
					(size 0.7874 0.5842)
					(thickness 0.000001)
				)
			)
		)
		(fp_text user "1"
			(at 0.11938 16.064738 180)
			(unlocked yes)
			(layer "F.Fab")
			(effects
				(font
					(size 0.7874 0.5842)
					(thickness 0.000001)
				)
			)
		)
		(fp_text user "I"
			(at -1.649222 11.210798 180)
			(unlocked yes)
			(layer "F.Fab")
			(effects
				(font
					(size 0.7874 0.5842)
					(thickness 0.000001)
				)
			)
		)
		(fp_text user "H"
			(at -1.649222 9.81075 180)
			(unlocked yes)
			(layer "F.Fab")
			(effects
				(font
					(size 0.7874 0.5842)
					(thickness 0.000001)
				)
			)
		)
		(fp_text user "G"
			(at -1.649222 8.410956 180)
			(unlocked yes)
			(layer "F.Fab")
			(effects
				(font
					(size 0.7874 0.5842)
					(thickness 0.000001)
				)
			)
		)
		(fp_text user "F"
			(at -1.649222 7.010908 180)
			(unlocked yes)
			(layer "F.Fab")
			(effects
				(font
					(size 0.7874 0.5842)
					(thickness 0.000001)
				)
			)
		)
		(fp_text user "E"
			(at -1.649222 5.61086 180)
			(unlocked yes)
			(layer "F.Fab")
			(effects
				(font
					(size 0.7874 0.5842)
					(thickness 0.000001)
				)
			)
		)
		(fp_text user "D"
			(at -1.649222 4.210812 180)
			(unlocked yes)
			(layer "F.Fab")
			(effects
				(font
					(size 0.7874 0.5842)
					(thickness 0.000001)
				)
			)
		)
		(fp_text user "C"
			(at -1.649222 2.810764 180)
			(unlocked yes)
			(layer "F.Fab")
			(effects
				(font
					(size 0.7874 0.5842)
					(thickness 0.000001)
				)
			)
		)
		(fp_text user "B"
			(at -1.649222 1.410716 180)
			(unlocked yes)
			(layer "F.Fab")
			(effects
				(font
					(size 0.7874 0.5842)
					(thickness 0.000001)
				)
			)
		)
		(fp_text user "A"
			(at -1.68402 -0.803148 180)
			(unlocked yes)
			(layer "F.Fab")
			(effects
				(font
					(size 0.7874 0.5842)
					(thickness 0.000001)
				)
			)
		)
		(pad "A1" thru_hole rect
			(at 0 0)
			(size 0.9144 0.9144)
			(drill 0.508)
			(layers "*.Cu" "*.Mask")
			(remove_unused_layers no)
			(net "ENET1G_1_MDI0P")
			(clearance 0.0508)
			(thermal_gap 0.0508)
			(padstack
				(mode front_inner_back)
				(layer "Inner"
					(shape circle)
					(size 0.9144 0.9144)
					(clearance 0.0508)
				)
				(layer "B.Cu"
					(shape rect)
					(size 0.9144 0.9144)
					(clearance 0.0508)
				)
			)
		)
		(pad "A2" thru_hole circle
			(at 1.999996 -0.100076)
			(size 0.9144 0.9144)
			(drill 0.508)
			(layers "*.Cu" "*.Mask")
			(remove_unused_layers no)
			(net "GND")
			(clearance 0.0508)
			(thermal_gap 0.0508)
		)
		(pad "A3" thru_hole circle
			(at 3.999992 0)
			(size 0.9144 0.9144)
			(drill 0.508)
			(layers "*.Cu" "*.Mask")
			(remove_unused_layers no)
			(net "ENET1G_1_MDI3P")
			(clearance 0.0508)
			(thermal_gap 0.0508)
		)
		(pad "A4" thru_hole circle
			(at 5.999988 -0.100076)
			(size 0.9144 0.9144)
			(drill 0.508)
			(layers "*.Cu" "*.Mask")
			(remove_unused_layers no)
			(net "GND")
			(clearance 0.0508)
			(thermal_gap 0.0508)
		)
		(pad "A5" thru_hole circle
			(at 7.999984 0)
			(size 0.9144 0.9144)
			(drill 0.508)
			(layers "*.Cu" "*.Mask")
			(remove_unused_layers no)
			(net "ENET1G_2_MDI1P")
			(clearance 0.0508)
			(thermal_gap 0.0508)
		)
		(pad "A6" thru_hole circle
			(at 9.99998 -0.100076)
			(size 0.9144 0.9144)
			(drill 0.508)
			(layers "*.Cu" "*.Mask")
			(remove_unused_layers no)
			(net "GND")
			(clearance 0.0508)
			(thermal_gap 0.0508)
		)
		(pad "B1" thru_hole circle
			(at 0 1.400048)
			(size 0.9144 0.9144)
			(drill 0.508)
			(layers "*.Cu" "*.Mask")
			(remove_unused_layers no)
			(net "ENET1G_1_MDI0N")
			(clearance 0.0508)
			(thermal_gap 0.0508)
		)
		(pad "B2" thru_hole circle
			(at 1.999996 1.299972)
			(size 0.9144 0.9144)
			(drill 0.508)
			(layers "*.Cu" "*.Mask")
			(remove_unused_layers no)
			(net "ENET1G_1_MDI2P")
			(clearance 0.0508)
			(thermal_gap 0.0508)
		)
		(pad "B3" thru_hole circle
			(at 3.999992 1.400048)
			(size 0.9144 0.9144)
			(drill 0.508)
			(layers "*.Cu" "*.Mask")
			(remove_unused_layers no)
			(net "ENET1G_1_MDI3N")
			(clearance 0.0508)
			(thermal_gap 0.0508)
		)
		(pad "B4" thru_hole circle
			(at 5.999988 1.299972)
			(size 0.9144 0.9144)
			(drill 0.508)
			(layers "*.Cu" "*.Mask")
			(remove_unused_layers no)
			(net "ENET1G_2_MDI0P")
			(clearance 0.0508)
			(thermal_gap 0.0508)
		)
		(pad "B5" thru_hole circle
			(at 7.999984 1.400048)
			(size 0.9144 0.9144)
			(drill 0.508)
			(layers "*.Cu" "*.Mask")
			(remove_unused_layers no)
			(net "ENET1G_2_MDI1N")
			(clearance 0.0508)
			(thermal_gap 0.0508)
		)
		(pad "B6" thru_hole circle
			(at 9.99998 1.299972)
			(size 0.9144 0.9144)
			(drill 0.508)
			(layers "*.Cu" "*.Mask")
			(remove_unused_layers no)
			(net "ENET1G_2_MDI3P")
			(clearance 0.0508)
			(thermal_gap 0.0508)
		)
		(pad "C1" thru_hole circle
			(at 0 2.800096)
			(size 0.9144 0.9144)
			(drill 0.508)
			(layers "*.Cu" "*.Mask")
			(remove_unused_layers no)
			(net "GND")
			(clearance 0.0508)
			(thermal_gap 0.0508)
		)
		(pad "C2" thru_hole circle
			(at 1.999996 2.70002)
			(size 0.9144 0.9144)
			(drill 0.508)
			(layers "*.Cu" "*.Mask")
			(remove_unused_layers no)
			(net "ENET1G_1_MDI2N")
			(clearance 0.0508)
			(thermal_gap 0.0508)
		)
		(pad "C3" thru_hole circle
			(at 3.999992 2.800096)
			(size 0.9144 0.9144)
			(drill 0.508)
			(layers "*.Cu" "*.Mask")
			(remove_unused_layers no)
			(net "GND")
			(clearance 0.0508)
			(thermal_gap 0.0508)
		)
		(pad "C4" thru_hole circle
			(at 5.999988 2.70002)
			(size 0.9144 0.9144)
			(drill 0.508)
			(layers "*.Cu" "*.Mask")
			(remove_unused_layers no)
			(net "ENET1G_2_MDI0N")
			(clearance 0.0508)
			(thermal_gap 0.0508)
		)
		(pad "C5" thru_hole circle
			(at 7.999984 2.800096)
			(size 0.9144 0.9144)
			(drill 0.508)
			(layers "*.Cu" "*.Mask")
			(remove_unused_layers no)
			(net "GND")
			(clearance 0.0508)
			(thermal_gap 0.0508)
		)
		(pad "C6" thru_hole circle
			(at 9.99998 2.70002)
			(size 0.9144 0.9144)
			(drill 0.508)
			(layers "*.Cu" "*.Mask")
			(remove_unused_layers no)
			(net "ENET1G_2_MDI3N")
			(clearance 0.0508)
			(thermal_gap 0.0508)
		)
		(pad "D1" thru_hole circle
			(at 0 4.19989)
			(size 0.9144 0.9144)
			(drill 0.508)
			(layers "*.Cu" "*.Mask")
			(remove_unused_layers no)
			(net "ENET10G_1_RDP")
			(clearance 0.0508)
			(thermal_gap 0.0508)
		)
		(pad "D2" thru_hole circle
			(at 1.999996 4.100068)
			(size 0.9144 0.9144)
			(drill 0.508)
			(layers "*.Cu" "*.Mask")
			(remove_unused_layers no)
			(net "GND")
			(clearance 0.0508)
			(thermal_gap 0.0508)
		)
		(pad "D3" thru_hole circle
			(at 3.999992 4.19989)
			(size 0.9144 0.9144)
			(drill 0.508)
			(layers "*.Cu" "*.Mask")
			(remove_unused_layers no)
			(net "ENET10G_1_SDA")
			(clearance 0.0508)
			(thermal_gap 0.0508)
		)
		(pad "D4" thru_hole circle
			(at 5.999988 4.100068)
			(size 0.9144 0.9144)
			(drill 0.508)
			(layers "*.Cu" "*.Mask")
			(remove_unused_layers no)
			(net "GND")
			(clearance 0.0508)
			(thermal_gap 0.0508)
		)
		(pad "D5" thru_hole circle
			(at 7.999984 4.19989)
			(size 0.9144 0.9144)
			(drill 0.508)
			(layers "*.Cu" "*.Mask")
			(remove_unused_layers no)
			(net "ENET1G_2_MDI2P")
			(clearance 0.0508)
			(thermal_gap 0.0508)
		)
		(pad "D6" thru_hole circle
			(at 9.99998 4.100068)
			(size 0.9144 0.9144)
			(drill 0.508)
			(layers "*.Cu" "*.Mask")
			(remove_unused_layers no)
			(net "GND")
			(clearance 0.0508)
			(thermal_gap 0.0508)
		)
		(pad "E1" thru_hole circle
			(at 0 5.599938)
			(size 0.9144 0.9144)
			(drill 0.508)
			(layers "*.Cu" "*.Mask")
			(remove_unused_layers no)
			(net "ENET10G_1_RDN")
			(clearance 0.0508)
			(thermal_gap 0.0508)
		)
		(pad "E2" thru_hole circle
			(at 1.999996 5.500116)
			(size 0.9144 0.9144)
			(drill 0.508)
			(layers "*.Cu" "*.Mask")
			(remove_unused_layers no)
			(net "ENET1G_1_MDI1P")
			(clearance 0.0508)
			(thermal_gap 0.0508)
		)
		(pad "E3" thru_hole circle
			(at 3.999992 5.599938)
			(size 0.9144 0.9144)
			(drill 0.508)
			(layers "*.Cu" "*.Mask")
			(remove_unused_layers no)
			(net "ENET10G_1_SCL")
			(clearance 0.0508)
			(thermal_gap 0.0508)
		)
		(pad "E4" thru_hole circle
			(at 5.999988 5.500116)
			(size 0.9144 0.9144)
			(drill 0.508)
			(layers "*.Cu" "*.Mask")
			(remove_unused_layers no)
			(net "ENET10G_2_SDA")
			(clearance 0.0508)
			(thermal_gap 0.0508)
		)
		(pad "E5" thru_hole circle
			(at 7.999984 5.599938)
			(size 0.9144 0.9144)
			(drill 0.508)
			(layers "*.Cu" "*.Mask")
			(remove_unused_layers no)
			(net "ENET1G_2_MDI2N")
			(clearance 0.0508)
			(thermal_gap 0.0508)
		)
		(pad "E6" thru_hole circle
			(at 9.99998 5.500116)
			(size 0.9144 0.9144)
			(drill 0.508)
			(layers "*.Cu" "*.Mask")
			(remove_unused_layers no)
			(net "ENET10G_2_RDP")
			(clearance 0.0508)
			(thermal_gap 0.0508)
		)
		(pad "F1" thru_hole circle
			(at 0 6.999986)
			(size 0.9144 0.9144)
			(drill 0.508)
			(layers "*.Cu" "*.Mask")
			(remove_unused_layers no)
			(net "GND")
			(clearance 0.0508)
			(thermal_gap 0.0508)
		)
		(pad "F2" thru_hole circle
			(at 1.999996 6.89991)
			(size 0.9144 0.9144)
			(drill 0.508)
			(layers "*.Cu" "*.Mask")
			(remove_unused_layers no)
			(net "ENET1G_1_MDI1N")
			(clearance 0.0508)
			(thermal_gap 0.0508)
		)
		(pad "F3" thru_hole circle
			(at 3.999992 6.999986)
			(size 0.9144 0.9144)
			(drill 0.508)
			(layers "*.Cu" "*.Mask")
			(remove_unused_layers no)
			(net "SKU_PIN_BLAD1_1")
			(clearance 0.0508)
			(thermal_gap 0.0508)
		)
		(pad "F4" thru_hole circle
			(at 5.999988 6.89991)
			(size 0.9144 0.9144)
			(drill 0.508)
			(layers "*.Cu" "*.Mask")
			(remove_unused_layers no)
			(net "ENET10G_2_SCL")
			(clearance 0.0508)
			(thermal_gap 0.0508)
		)
		(pad "F5" thru_hole circle
			(at 7.999984 6.999986)
			(size 0.9144 0.9144)
			(drill 0.508)
			(layers "*.Cu" "*.Mask")
			(remove_unused_layers no)
			(net "GND")
			(clearance 0.0508)
			(thermal_gap 0.0508)
		)
		(pad "F6" thru_hole circle
			(at 9.99998 6.89991)
			(size 0.9144 0.9144)
			(drill 0.508)
			(layers "*.Cu" "*.Mask")
			(remove_unused_layers no)
			(net "ENET10G_2_RDN")
			(clearance 0.0508)
			(thermal_gap 0.0508)
		)
		(pad "G1" thru_hole circle
			(at 0 8.400034)
			(size 0.9144 0.9144)
			(drill 0.508)
			(layers "*.Cu" "*.Mask")
			(remove_unused_layers no)
			(net "ENET10G_1_TDP")
			(clearance 0.0508)
			(thermal_gap 0.0508)
		)
		(pad "G2" thru_hole circle
			(at 1.999996 8.299958)
			(size 0.9144 0.9144)
			(drill 0.508)
			(layers "*.Cu" "*.Mask")
			(remove_unused_layers no)
			(net "GND")
			(clearance 0.0508)
			(thermal_gap 0.0508)
		)
		(pad "G3" thru_hole circle
			(at 3.999992 8.400034)
			(size 0.9144 0.9144)
			(drill 0.508)
			(layers "*.Cu" "*.Mask")
			(remove_unused_layers no)
			(net "NODE1_RXD")
			(clearance 0.0508)
			(thermal_gap 0.0508)
		)
		(pad "G4" thru_hole circle
			(at 5.999988 8.299958)
			(size 0.9144 0.9144)
			(drill 0.508)
			(layers "*.Cu" "*.Mask")
			(remove_unused_layers no)
			(net "NODE2_RXD")
			(clearance 0.0508)
			(thermal_gap 0.0508)
		)
		(pad "G5" thru_hole circle
			(at 7.999984 8.400034)
			(size 0.9144 0.9144)
			(drill 0.508)
			(layers "*.Cu" "*.Mask")
			(remove_unused_layers no)
			(net "NODE2_EN")
			(clearance 0.0508)
			(thermal_gap 0.0508)
		)
		(pad "G6" thru_hole circle
			(at 9.99998 8.299958)
			(size 0.9144 0.9144)
			(drill 0.508)
			(layers "*.Cu" "*.Mask")
			(remove_unused_layers no)
			(net "GND")
			(clearance 0.0508)
			(thermal_gap 0.0508)
		)
		(pad "H1" thru_hole circle
			(at 0 9.800082)
			(size 0.9144 0.9144)
			(drill 0.508)
			(layers "*.Cu" "*.Mask")
			(remove_unused_layers no)
			(net "ENET10G_1_TDN")
			(clearance 0.0508)
			(thermal_gap 0.0508)
		)
		(pad "H2" thru_hole circle
			(at 1.999996 9.700006)
			(size 0.9144 0.9144)
			(drill 0.508)
			(layers "*.Cu" "*.Mask")
			(remove_unused_layers no)
			(net "NODE1_EN")
			(clearance 0.0508)
			(thermal_gap 0.0508)
		)
		(pad "H3" thru_hole circle
			(at 3.999992 9.800082)
			(size 0.9144 0.9144)
			(drill 0.508)
			(layers "*.Cu" "*.Mask")
			(remove_unused_layers no)
			(net "NODE1_TXD")
			(clearance 0.0508)
			(thermal_gap 0.0508)
		)
		(pad "H4" thru_hole circle
			(at 5.999988 9.700006)
			(size 0.9144 0.9144)
			(drill 0.508)
			(layers "*.Cu" "*.Mask")
			(remove_unused_layers no)
			(net "NODE2_TXD")
			(clearance 0.0508)
			(thermal_gap 0.0508)
		)
		(pad "H5" thru_hole circle
			(at 7.999984 9.800082)
			(size 0.9144 0.9144)
			(drill 0.508)
			(layers "*.Cu" "*.Mask")
			(remove_unused_layers no)
			(net "SFP2_PRESENT_N")
			(clearance 0.0508)
			(thermal_gap 0.0508)
		)
		(pad "H6" thru_hole circle
			(at 9.99998 9.700006)
			(size 0.9144 0.9144)
			(drill 0.508)
			(layers "*.Cu" "*.Mask")
			(remove_unused_layers no)
			(net "ENET10G_2_TDP")
			(clearance 0.0508)
			(thermal_gap 0.0508)
		)
		(pad "I1" thru_hole circle
			(at 0 11.199876)
			(size 0.9144 0.9144)
			(drill 0.508)
			(layers "*.Cu" "*.Mask")
			(remove_unused_layers no)
			(net "GND")
			(clearance 0.0508)
			(thermal_gap 0.0508)
		)
		(pad "I2" thru_hole circle
			(at 1.999996 11.100054)
			(size 0.9144 0.9144)
			(drill 0.508)
			(layers "*.Cu" "*.Mask")
			(remove_unused_layers no)
			(net "SFP1_PRESENT_N")
			(clearance 0.0508)
			(thermal_gap 0.0508)
		)
		(pad "I3" thru_hole circle
			(at 3.999992 11.199876)
			(size 0.9144 0.9144)
			(drill 0.508)
			(layers "*.Cu" "*.Mask")
			(remove_unused_layers no)
			(net "P3V3_BLAD1")
			(clearance 0.0508)
			(thermal_gap 0.0508)
		)
		(pad "I4" thru_hole circle
			(at 5.999988 11.100054)
			(size 0.9144 0.9144)
			(drill 0.508)
			(layers "*.Cu" "*.Mask")
			(remove_unused_layers no)
			(net "SKU_PIN_BLAD1_2")
			(clearance 0.0508)
			(thermal_gap 0.0508)
		)
		(pad "I5" thru_hole circle
			(at 7.999984 11.199876)
			(size 0.9144 0.9144)
			(drill 0.508)
			(layers "*.Cu" "*.Mask")
			(remove_unused_layers no)
			(net "BLADE1_MATED_N")
			(clearance 0.0508)
			(thermal_gap 0.0508)
		)
		(pad "I6" thru_hole circle
			(at 9.99998 11.100054)
			(size 0.9144 0.9144)
			(drill 0.508)
			(layers "*.Cu" "*.Mask")
			(remove_unused_layers no)
			(net "ENET10G_2_TDN")
			(clearance 0.0508)
			(thermal_gap 0.0508)
		)
		(zone
			(layer "B.Cu")
			(hatch none 0.5)
			(connect_pads
				(clearance 0)
			)
			(min_thickness 0.25)
			(keepout
				(tracks allowed)
				(vias not_allowed)
				(pads allowed)
				(copperpour not_allowed)
				(footprints allowed)
			)
			(placement
				(enabled no)
				(sheetname "")
			)
			(fill
				(thermal_gap 0.5)
				(thermal_bridge_width 0.5)
				(island_removal_mode 0)
			)
			(polygon
				(pts
					(xy 119.038116 -13.807948) (xy 119.038116 -13.708126) (xy 118.022116 -13.708126) (xy 118.022116 -1.491996)
					(xy 128.022096 -1.491996) (xy 128.022096 -1.592072) (xy 129.038096 -1.592072) (xy 129.038096 -13.807948)
				)
			)
		)
	)
	(footprint ""
		(layer "F.Cu")
		(at 130.146552 -22.210268)
		(property "Reference" "R67"
			(at -61.8236 5.140452 0)
			(unlocked yes)
			(layer "F.SilkS")
			(effects
				(font
					(size 0.7874 0.5842)
					(thickness 0.1524)
				)
				(justify left)
			)
		)
		(property "Value" ""
			(at 0 0 0)
			(layer "F.Fab")
			(effects
				(font
					(size 1.27 1.27)
				)
			)
		)
		(duplicate_pad_numbers_are_jumpers no)
		(fp_line
			(start -0.7874 -0.4064)
			(end 0.7874 -0.4064)
			(stroke
				(width 0.1524)
				(type default)
			)
			(layer "F.SilkS")
		)
		(fp_line
			(start -0.7874 0.4064)
			(end -0.7874 -0.4064)
			(stroke
				(width 0.1524)
				(type default)
			)
			(layer "F.SilkS")
		)
		(fp_line
			(start 0.7874 -0.4064)
			(end 0.7874 0.4064)
			(stroke
				(width 0.1524)
				(type default)
			)
			(layer "F.SilkS")
		)
		(fp_line
			(start 0.7874 0.4064)
			(end -0.7874 0.4064)
			(stroke
				(width 0.1524)
				(type default)
			)
			(layer "F.SilkS")
		)
		(fp_poly
			(pts
				(xy -0.508 0.2794) (xy -0.508 0.2286) (xy -0.635 0.2286) (xy -0.635 -0.254) (xy -0.5334 -0.254)
				(xy -0.5334 -0.2794) (xy 0.5334 -0.2794) (xy 0.5334 -0.254) (xy 0.635 -0.254) (xy 0.635 0.254) (xy 0.5334 0.254)
				(xy 0.5334 0.2794)
			)
			(stroke
				(width 0)
				(type default)
			)
			(fill no)
			(layer "F.CrtYd")
		)
		(pad "1" smd rect
			(at 0.40005 0)
			(size 0.4572 0.508)
			(layers "F.Cu" "F.Mask" "F.Paste")
			(net "ENET10G_1_LOS")
		)
		(pad "2" smd rect
			(at -0.40005 0)
			(size 0.4572 0.508)
			(layers "F.Cu" "F.Mask" "F.Paste")
			(net "SFP1_PRESENT_N")
		)
	)
	(footprint ""
		(layer "F.Cu")
		(at 312.1406 -32.065468)
		(property "Reference" "R83"
			(at -1.3716 -8.88873 0)
			(unlocked yes)
			(layer "F.SilkS")
			(effects
				(font
					(size 0.7874 0.5842)
					(thickness 0.1524)
				)
				(justify left)
			)
		)
		(property "Value" ""
			(at 0 0 0)
			(layer "F.Fab")
			(effects
				(font
					(size 1.27 1.27)
				)
			)
		)
		(duplicate_pad_numbers_are_jumpers no)
		(fp_line
			(start -1.905 -0.8636)
			(end 1.905 -0.8636)
			(stroke
				(width 0.1524)
				(type default)
			)
			(layer "F.SilkS")
		)
		(fp_line
			(start -1.905 0.8636)
			(end -1.905 -0.8636)
			(stroke
				(width 0.1524)
				(type default)
			)
			(layer "F.SilkS")
		)
		(fp_line
			(start 1.905 -0.8636)
			(end 1.905 0.8636)
			(stroke
				(width 0.1524)
				(type default)
			)
			(layer "F.SilkS")
		)
		(fp_line
			(start 1.905 0.8636)
			(end -1.905 0.8636)
			(stroke
				(width 0.1524)
				(type default)
			)
			(layer "F.SilkS")
		)
		(fp_poly
			(pts
				(xy 1.524 0.6858) (xy 1.524 -0.6858) (xy 1.524 -0.7366) (xy -1.524 -0.7366) (xy -1.524 -0.6858)
				(xy -1.524 0.6858) (xy -1.524 0.7366) (xy 1.524 0.7366)
			)
			(stroke
				(width 0)
				(type default)
			)
			(fill no)
			(layer "F.CrtYd")
		)
		(pad "1" smd rect
			(at 0.94996 0)
			(size 1.1176 1.3716)
			(layers "F.Cu" "F.Mask" "F.Paste")
			(net "P3V3_BLAD2")
		)
		(pad "2" smd rect
			(at -0.94996 0)
			(size 1.1176 1.3716)
			(layers "F.Cu" "F.Mask" "F.Paste")
			(net "P3V3_10G_4_VCCR")
		)
	)
	(footprint ""
		(layer "F.Cu")
		(at 375.82856 -27.776678 180)
		(property "Reference" "R31"
			(at -33.83788 -17.234408 0)
			(unlocked yes)
			(layer "F.SilkS")
			(effects
				(font
					(size 0.7874 0.5842)
					(thickness 0.1524)
				)
				(justify left)
			)
		)
		(property "Value" ""
			(at 0 0 180)
			(layer "F.Fab")
			(effects
				(font
					(size 1.27 1.27)
				)
			)
		)
		(duplicate_pad_numbers_are_jumpers no)
		(fp_line
			(start 0.7874 0.4064)
			(end -0.7874 0.4064)
			(stroke
				(width 0.1524)
				(type default)
			)
			(layer "F.SilkS")
		)
		(fp_line
			(start 0.7874 -0.4064)
			(end 0.7874 0.4064)
			(stroke
				(width 0.1524)
				(type default)
			)
			(layer "F.SilkS")
		)
		(fp_line
			(start -0.7874 0.4064)
			(end -0.7874 -0.4064)
			(stroke
				(width 0.1524)
				(type default)
			)
			(layer "F.SilkS")
		)
		(fp_line
			(start -0.7874 -0.4064)
			(end 0.7874 -0.4064)
			(stroke
				(width 0.1524)
				(type default)
			)
			(layer "F.SilkS")
		)
		(fp_poly
			(pts
				(xy -0.508 0.2794) (xy -0.508 0.2286) (xy -0.635 0.2286) (xy -0.635 -0.254) (xy -0.5334 -0.254)
				(xy -0.5334 -0.2794) (xy 0.5334 -0.2794) (xy 0.5334 -0.254) (xy 0.635 -0.254) (xy 0.635 0.254) (xy 0.5334 0.254)
				(xy 0.5334 0.2794)
			)
			(stroke
				(width 0)
				(type default)
			)
			(fill no)
			(layer "F.CrtYd")
		)
		(pad "1" smd rect
			(at 0.40005 0 180)
			(size 0.4572 0.508)
			(layers "F.Cu" "F.Mask" "F.Paste")
			(net "P3V3_BLAD2")
		)
		(pad "2" smd rect
			(at -0.40005 0 180)
			(size 0.4572 0.508)
			(layers "F.Cu" "F.Mask" "F.Paste")
			(net "ENET10G_3_RS1")
		)
	)
	(footprint ""
		(layer "F.Cu")
		(at 123.535186 -44.8691 180)
		(property "Reference" "J22"
			(at -1.443228 -18.399252 0)
			(unlocked yes)
			(layer "F.SilkS")
			(effects
				(font
					(size 0.7874 0.5842)
					(thickness 0.1524)
				)
				(justify left)
			)
		)
		(property "Value" ""
			(at 0 0 180)
			(layer "F.Fab")
			(effects
				(font
					(size 1.27 1.27)
				)
			)
		)
		(duplicate_pad_numbers_are_jumpers no)
		(fp_line
			(start 9.655048 10.80008)
			(end 9.655048 6.1976)
			(stroke
				(width 0.1524)
				(type default)
			)
			(layer "F.SilkS")
		)
		(fp_line
			(start 9.655048 2.9718)
			(end 9.655048 -9.9822)
			(stroke
				(width 0.1524)
				(type default)
			)
			(layer "F.SilkS")
		)
		(fp_line
			(start 9.655048 -12.827)
			(end 9.655048 -17.649952)
			(stroke
				(width 0.1524)
				(type default)
			)
			(layer "F.SilkS")
		)
		(fp_line
			(start 9.655048 -17.649952)
			(end -9.655048 -17.649952)
			(stroke
				(width 0.1524)
				(type default)
			)
			(layer "F.SilkS")
		)
		(fp_line
			(start -9.655048 10.80008)
			(end 9.655048 10.80008)
			(stroke
				(width 0.1524)
				(type default)
			)
			(layer "F.SilkS")
		)
		(fp_line
			(start -9.655048 5.969)
			(end -9.655048 10.80008)
			(stroke
				(width 0.1524)
				(type default)
			)
			(layer "F.SilkS")
		)
		(fp_line
			(start -9.655048 0)
			(end -9.655048 3.1496)
			(stroke
				(width 0.1524)
				(type default)
			)
			(layer "F.SilkS")
		)
		(fp_line
			(start -9.655048 -17.649952)
			(end -9.655556 -16.722344)
			(stroke
				(width 0.1524)
				(type default)
			)
			(layer "F.SilkS")
		)
		(fp_line
			(start -9.656826 -14.280642)
			(end -9.663684 -0.70612)
			(stroke
				(width 0.1524)
				(type default)
			)
			(layer "F.SilkS")
		)
		(fp_line
			(start -9.663684 -0.70612)
			(end -9.655048 0)
			(stroke
				(width 0.1524)
				(type default)
			)
			(layer "F.SilkS")
		)
		(fp_poly
			(pts
				(xy -9.1313 -6.1341) (xy -11.2395 -6.7691) (xy -11.2395 -5.5245)
			)
			(stroke
				(width 0)
				(type default)
			)
			(fill yes)
			(layer "F.SilkS")
		)
		(fp_poly
			(pts
				(xy -3.9116 -9.6139) (xy -3.9116 -8.1788) (xy 5.1816 -8.1788) (xy 5.1816 -9.6139)
			)
			(stroke
				(width 0)
				(type default)
			)
			(fill no)
			(layer "B.CrtYd")
		)
		(fp_poly
			(pts
				(xy -3.9116 -16.2052) (xy -3.9116 -14.7701) (xy 5.1562 -14.7701) (xy 5.1562 -16.2052)
			)
			(stroke
				(width 0)
				(type default)
			)
			(fill no)
			(layer "B.CrtYd")
		)
		(fp_poly
			(pts
				(xy -5.1816 -7.0993) (xy -5.1816 -5.6388) (xy 3.9116 -5.6388) (xy 3.9116 -7.0993)
			)
			(stroke
				(width 0)
				(type default)
			)
			(fill no)
			(layer "B.CrtYd")
		)
		(fp_poly
			(pts
				(xy -5.1816 -13.6652) (xy -5.1816 -12.2428) (xy 3.9116 -12.2428) (xy 3.9116 -13.6652)
			)
			(stroke
				(width 0)
				(type default)
			)
			(fill no)
			(layer "B.CrtYd")
		)
		(fp_poly
			(pts
				(arc
					(start 6.931406 4.569968)
					(mid 10.078466 4.569968)
					(end 6.931406 4.569968)
				)
			)
			(stroke
				(width 0)
				(type default)
			)
			(fill no)
			(layer "B.CrtYd")
		)
		(fp_poly
			(pts
				(arc
					(start 6.928104 -11.43)
					(mid 10.081768 -11.43)
					(end 6.928104 -11.43)
				)
			)
			(stroke
				(width 0)
				(type default)
			)
			(fill no)
			(layer "B.CrtYd")
		)
		(fp_poly
			(pts
				(arc
					(start 6.167628 -5.839968)
					(mid 9.322308 -5.839968)
					(end 6.167628 -5.839968)
				)
			)
			(stroke
				(width 0)
				(type default)
			)
			(fill no)
			(layer "B.CrtYd")
		)
		(fp_poly
			(pts
				(arc
					(start -9.320784 -9.139936)
					(mid -6.169152 -9.139936)
					(end -9.320784 -9.139936)
				)
			)
			(stroke
				(width 0)
				(type default)
			)
			(fill no)
			(layer "B.CrtYd")
		)
		(fp_poly
			(pts
				(arc
					(start -10.076434 4.569968)
					(mid -6.933438 4.569968)
					(end -10.076434 4.569968)
				)
			)
			(stroke
				(width 0)
				(type default)
			)
			(fill no)
			(layer "B.CrtYd")
		)
		(fp_poly
			(pts
				(arc
					(start -10.080498 -15.489936)
					(mid -6.929374 -15.489936)
					(end -10.080498 -15.489936)
				)
			)
			(stroke
				(width 0)
				(type default)
			)
			(fill no)
			(layer "B.CrtYd")
		)
		(fp_poly
			(pts
				(arc
					(start 3.838194 0)
					(mid 7.591806 0)
					(end 3.838194 0)
				)
			)
			(stroke
				(width 0)
				(type default)
			)
			(fill no)
			(layer "B.CrtYd")
		)
		(fp_poly
			(pts
				(arc
					(start -7.590028 0)
					(mid -3.839972 0)
					(end -7.590028 0)
				)
			)
			(stroke
				(width 0)
				(type default)
			)
			(fill no)
			(layer "B.CrtYd")
		)
		(fp_poly
			(pts
				(xy -9.655048 0) (xy -9.655048 10.80008) (xy 9.655048 10.80008) (xy 9.655048 -17.649952) (xy -9.655048 -17.649952)
				(xy -9.663684 -0.70612)
			)
			(stroke
				(width 0)
				(type default)
			)
			(fill no)
			(layer "F.CrtYd")
		)
		(fp_text user "A7"
			(at 10.25398 -6.26491 90)
			(unlocked yes)
			(layer "F.SilkS")
			(effects
				(font
					(size 0.7874 0.5842)
					(thickness 0.1524)
				)
				(justify left)
			)
		)
		(fp_text user "A8"
			(at 10.22858 -9.03351 90)
			(unlocked yes)
			(layer "F.SilkS")
			(effects
				(font
					(size 0.7874 0.5842)
					(thickness 0.1524)
				)
				(justify left)
			)
		)
		(fp_text user "B2"
			(at 10.22477 -14.57071 90)
			(unlocked yes)
			(layer "F.SilkS")
			(effects
				(font
					(size 0.7874 0.5842)
					(thickness 0.1524)
				)
				(justify left)
			)
		)
		(fp_text user "B1"
			(at 9.899396 -18.835116 0)
			(unlocked yes)
			(layer "F.SilkS")
			(effects
				(font
					(size 0.7874 0.5842)
					(thickness 0.1524)
				)
				(justify left)
			)
		)
		(fp_text user "B7"
			(at -8.301228 -18.424652 0)
			(unlocked yes)
			(layer "F.SilkS")
			(effects
				(font
					(size 0.7874 0.5842)
					(thickness 0.1524)
				)
				(justify left)
			)
		)
		(fp_text user "A1"
			(at -10.268966 -4.752086 90)
			(unlocked yes)
			(layer "F.SilkS")
			(effects
				(font
					(size 0.7874 0.5842)
					(thickness 0.1524)
				)
				(justify left)
			)
		)
		(fp_text user "A2"
			(at -10.319766 -10.594086 90)
			(unlocked yes)
			(layer "F.SilkS")
			(effects
				(font
					(size 0.7874 0.5842)
					(thickness 0.1524)
				)
				(justify left)
			)
		)
		(fp_text user "B8"
			(at -10.345166 -13.489686 90)
			(unlocked yes)
			(layer "F.SilkS")
			(effects
				(font
					(size 0.7874 0.5842)
					(thickness 0.1524)
				)
				(justify left)
			)
		)
		(fp_text user "A8"
			(at 5.510784 -8.899906 0)
			(unlocked yes)
			(layer "B.SilkS")
			(effects
				(font
					(size 0.7874 0.5842)
					(thickness 0.1524)
				)
				(justify left mirror)
			)
		)
		(fp_text user "B1"
			(at 5.485384 -15.634716 0)
			(unlocked yes)
			(layer "B.SilkS")
			(effects
				(font
					(size 0.7874 0.5842)
					(thickness 0.1524)
				)
				(justify left mirror)
			)
		)
		(fp_text user "B2"
			(at 4.427982 -12.916916 0)
			(unlocked yes)
			(layer "B.SilkS")
			(effects
				(font
					(size 0.7874 0.5842)
					(thickness 0.1524)
				)
				(justify left mirror)
			)
		)
		(fp_text user "A7"
			(at 4.224782 -6.4643 0)
			(unlocked yes)
			(layer "B.SilkS")
			(effects
				(font
					(size 0.7874 0.5842)
					(thickness 0.1524)
				)
				(justify left mirror)
			)
		)
		(fp_text user "B7"
			(at -5.485638 -15.660116 0)
			(unlocked yes)
			(layer "B.SilkS")
			(effects
				(font
					(size 0.7874 0.5842)
					(thickness 0.1524)
				)
				(justify left mirror)
			)
		)
		(fp_text user "A2"
			(at -5.511038 -8.982202 0)
			(unlocked yes)
			(layer "B.SilkS")
			(effects
				(font
					(size 0.7874 0.5842)
					(thickness 0.1524)
				)
				(justify left mirror)
			)
		)
		(fp_text user "A1"
			(at -6.59384 -6.436106 0)
			(unlocked yes)
			(layer "B.SilkS")
			(effects
				(font
					(size 0.7874 0.5842)
					(thickness 0.1524)
				)
				(justify left mirror)
			)
		)
		(fp_text user "B8"
			(at -6.79704 -13.018516 0)
			(unlocked yes)
			(layer "B.SilkS")
			(effects
				(font
					(size 0.7874 0.5842)
					(thickness 0.1524)
				)
				(justify left mirror)
			)
		)
		(pad "" np_thru_hole circle
			(at -5.715 0 180)
			(size 3.2512 3.2512)
			(drill 3.2512)
			(layers "*.Cu" "*.Mask")
			(clearance 0.381)
			(thermal_gap 0.381)
		)
		(pad "" np_thru_hole circle
			(at 5.715 0 180)
			(size 3.2512 3.2512)
			(drill 3.2512)
			(layers "*.Cu" "*.Mask")
			(clearance 0.381)
			(thermal_gap 0.381)
		)
		(pad "A1" thru_hole rect
			(at -4.445 -6.35 180)
			(size 1.2954 1.2954)
			(drill 0.889)
			(layers "*.Cu" "*.Mask")
			(remove_unused_layers no)
			(net "ENET1G_1_MDI0P")
			(clearance 0.0508)
			(thermal_gap 0.0508)
			(padstack
				(mode front_inner_back)
				(layer "Inner"
					(shape circle)
					(size 1.2954 1.2954)
					(clearance 0.0508)
				)
				(layer "B.Cu"
					(shape rect)
					(size 1.2954 1.2954)
					(clearance 0.0508)
				)
			)
		)
		(pad "A2" thru_hole circle
			(at -3.175 -8.89 180)
			(size 1.2954 1.2954)
			(drill 0.889)
			(layers "*.Cu" "*.Mask")
			(remove_unused_layers no)
			(net "ENET1G_1_MDI0N")
			(clearance 0.0508)
			(thermal_gap 0.0508)
		)
		(pad "A3" thru_hole circle
			(at -1.905 -6.35 180)
			(size 1.2954 1.2954)
			(drill 0.889)
			(layers "*.Cu" "*.Mask")
			(remove_unused_layers no)
			(net "ENET1G_1_MDI1P")
			(clearance 0.0508)
			(thermal_gap 0.0508)
		)
		(pad "A4" thru_hole circle
			(at -0.635 -8.89 180)
			(size 1.2954 1.2954)
			(drill 0.889)
			(layers "*.Cu" "*.Mask")
			(remove_unused_layers no)
			(net "ENET1G_1_MDI2P")
			(clearance 0.0508)
			(thermal_gap 0.0508)
		)
		(pad "A5" thru_hole circle
			(at 0.635 -6.35 180)
			(size 1.2954 1.2954)
			(drill 0.889)
			(layers "*.Cu" "*.Mask")
			(remove_unused_layers no)
			(net "ENET1G_1_MDI2N")
			(clearance 0.0508)
			(thermal_gap 0.0508)
		)
		(pad "A6" thru_hole circle
			(at 1.905 -8.89 180)
			(size 1.2954 1.2954)
			(drill 0.889)
			(layers "*.Cu" "*.Mask")
			(remove_unused_layers no)
			(net "ENET1G_1_MDI1N")
			(clearance 0.0508)
			(thermal_gap 0.0508)
		)
		(pad "A7" thru_hole circle
			(at 3.175 -6.35 180)
			(size 1.2954 1.2954)
			(drill 0.889)
			(layers "*.Cu" "*.Mask")
			(remove_unused_layers no)
			(net "ENET1G_1_MDI3P")
			(clearance 0.0508)
			(thermal_gap 0.0508)
		)
		(pad "A8" thru_hole circle
			(at 4.445 -8.89 180)
			(size 1.2954 1.2954)
			(drill 0.889)
			(layers "*.Cu" "*.Mask")
			(remove_unused_layers no)
			(net "ENET1G_1_MDI3N")
			(clearance 0.0508)
			(thermal_gap 0.0508)
		)
		(pad "B1" thru_hole circle
			(at 4.445 -15.489936 180)
			(size 1.2954 1.2954)
			(drill 0.889)
			(layers "*.Cu" "*.Mask")
			(remove_unused_layers no)
			(net "ENET1G_2_MDI0P")
			(clearance 0.0508)
			(thermal_gap 0.0508)
		)
		(pad "B2" thru_hole circle
			(at 3.175 -12.949936 180)
			(size 1.2954 1.2954)
			(drill 0.889)
			(layers "*.Cu" "*.Mask")
			(remove_unused_layers no)
			(net "ENET1G_2_MDI0N")
			(clearance 0.0508)
			(thermal_gap 0.0508)
		)
		(pad "B3" thru_hole circle
			(at 1.905 -15.489936 180)
			(size 1.2954 1.2954)
			(drill 0.889)
			(layers "*.Cu" "*.Mask")
			(remove_unused_layers no)
			(net "ENET1G_2_MDI1P")
			(clearance 0.0508)
			(thermal_gap 0.0508)
		)
		(pad "B4" thru_hole circle
			(at 0.635 -12.949936 180)
			(size 1.2954 1.2954)
			(drill 0.889)
			(layers "*.Cu" "*.Mask")
			(remove_unused_layers no)
			(net "ENET1G_2_MDI2P")
			(clearance 0.0508)
			(thermal_gap 0.0508)
		)
		(pad "B5" thru_hole circle
			(at -0.635 -15.489936 180)
			(size 1.2954 1.2954)
			(drill 0.889)
			(layers "*.Cu" "*.Mask")
			(remove_unused_layers no)
			(net "ENET1G_2_MDI2N")
			(clearance 0.0508)
			(thermal_gap 0.0508)
		)
		(pad "B6" thru_hole circle
			(at -1.905 -12.949936 180)
			(size 1.2954 1.2954)
			(drill 0.889)
			(layers "*.Cu" "*.Mask")
			(remove_unused_layers no)
			(net "ENET1G_2_MDI1N")
			(clearance 0.0508)
			(thermal_gap 0.0508)
		)
		(pad "B7" thru_hole circle
			(at -3.175 -15.489936 180)
			(size 1.2954 1.2954)
			(drill 0.889)
			(layers "*.Cu" "*.Mask")
			(remove_unused_layers no)
			(net "ENET1G_2_MDI3P")
			(clearance 0.0508)
			(thermal_gap 0.0508)
		)
		(pad "B8" thru_hole circle
			(at -4.445 -12.949936 180)
			(size 1.2954 1.2954)
			(drill 0.889)
			(layers "*.Cu" "*.Mask")
			(remove_unused_layers no)
			(net "ENET1G_2_MDI3N")
			(clearance 0.0508)
			(thermal_gap 0.0508)
		)
		(pad "G1" thru_hole circle
			(at -8.504936 -15.489936 180)
			(size 3.048 3.048)
			(drill 2.032)
			(layers "*.Cu" "*.Mask")
			(remove_unused_layers no)
			(net "GND")
			(clearance -0.254)
		)
		(pad "G2" thru_hole circle
			(at -7.744968 -9.139936 180)
			(size 3.048 3.048)
			(drill 2.032)
			(layers "*.Cu" "*.Mask")
			(remove_unused_layers no)
			(net "GND")
			(clearance -0.254)
		)
		(pad "G3" thru_hole circle
			(at -8.504936 4.569968 180)
			(size 3.048 3.048)
			(drill 2.032)
			(layers "*.Cu" "*.Mask")
			(remove_unused_layers no)
			(net "GND")
			(clearance -0.254)
		)
		(pad "G4" thru_hole circle
			(at 8.504936 4.569968 180)
			(size 3.048 3.048)
			(drill 2.032)
			(layers "*.Cu" "*.Mask")
			(remove_unused_layers no)
			(net "GND")
			(clearance -0.254)
		)
		(pad "G5" thru_hole circle
			(at 7.744968 -5.839968 180)
			(size 3.048 3.048)
			(drill 2.032)
			(layers "*.Cu" "*.Mask")
			(remove_unused_layers no)
			(net "GND")
			(clearance -0.254)
		)
		(pad "G6" thru_hole circle
			(at 8.504936 -11.43 180)
			(size 3.048 3.048)
			(drill 2.032)
			(layers "*.Cu" "*.Mask")
			(remove_unused_layers no)
			(net "GND")
			(clearance -0.254)
		)
		(zone
			(layers "F.Cu" "B.Cu" "In1.Cu" "In2.Cu" "In3.Cu" "In4.Cu" "In5.Cu" "In6.Cu")
			(hatch none 0.5)
			(connect_pads
				(clearance 0)
			)
			(min_thickness 0.25)
			(keepout
				(tracks not_allowed)
				(vias allowed)
				(pads allowed)
				(copperpour not_allowed)
				(footprints allowed)
			)
			(placement
				(enabled no)
				(sheetname "")
			)
			(fill
				(thermal_gap 0.5)
				(thermal_bridge_width 0.5)
				(island_removal_mode 0)
			)
			(polygon
				(pts
					(arc
						(start 119.854472 -44.8691)
						(mid 115.7859 -44.8691)
						(end 119.854472 -44.8691)
					)
				)
			)
		)
		(zone
			(layers "F.Cu" "B.Cu" "In1.Cu" "In2.Cu" "In3.Cu" "In4.Cu" "In5.Cu" "In6.Cu")
			(hatch none 0.5)
			(connect_pads
				(clearance 0)
			)
			(min_thickness 0.25)
			(keepout
				(tracks not_allowed)
				(vias allowed)
				(pads allowed)
				(copperpour not_allowed)
				(footprints allowed)
			)
			(placement
				(enabled no)
				(sheetname "")
			)
			(fill
				(thermal_gap 0.5)
				(thermal_bridge_width 0.5)
				(island_removal_mode 0)
			)
			(polygon
				(pts
					(arc
						(start 131.282694 -44.8691)
						(mid 127.217678 -44.8691)
						(end 131.282694 -44.8691)
					)
				)
			)
		)
	)
	(footprint ""
		(layer "F.Cu")
		(at 174.889922 -2.100072 180)
		(property "Reference" "J25"
			(at -4.842002 -1.120394 90)
			(unlocked yes)
			(layer "F.SilkS")
			(effects
				(font
					(size 0.7874 0.5842)
					(thickness 0.1524)
				)
				(justify left)
			)
		)
		(property "Value" ""
			(at 0 0 180)
			(layer "F.Fab")
			(effects
				(font
					(size 1.27 1.27)
				)
			)
		)
		(duplicate_pad_numbers_are_jumpers no)
		(fp_line
			(start 13.999972 18.375122)
			(end 13.999972 -14.675104)
			(stroke
				(width 0.1524)
				(type default)
			)
			(layer "F.SilkS")
		)
		(fp_line
			(start 13.999972 -14.675104)
			(end -3.999992 -14.675104)
			(stroke
				(width 0.1524)
				(type default)
			)
			(layer "F.SilkS")
		)
		(fp_line
			(start 10.999978 15.375128)
			(end 10.999978 -11.67511)
			(stroke
				(width 0.1524)
				(type default)
			)
			(layer "F.SilkS")
		)
		(fp_line
			(start 10.999978 -11.67511)
			(end -0.999998 -11.67511)
			(stroke
				(width 0.1524)
				(type default)
			)
			(layer "F.SilkS")
		)
		(fp_line
			(start -0.999998 15.375128)
			(end 10.999978 15.375128)
			(stroke
				(width 0.1524)
				(type default)
			)
			(layer "F.SilkS")
		)
		(fp_line
			(start -0.999998 -11.67511)
			(end -0.999998 15.375128)
			(stroke
				(width 0.1524)
				(type default)
			)
			(layer "F.SilkS")
		)
		(fp_line
			(start -3.999992 18.375122)
			(end 13.999972 18.375122)
			(stroke
				(width 0.1524)
				(type default)
			)
			(layer "F.SilkS")
		)
		(fp_line
			(start -3.999992 -14.675104)
			(end -3.999992 18.375122)
			(stroke
				(width 0.1524)
				(type default)
			)
			(layer "F.SilkS")
		)
		(fp_poly
			(pts
				(xy -2.261108 0.508) (xy -2.261108 -0.508) (xy -1.245108 0)
			)
			(stroke
				(width 0)
				(type default)
			)
			(fill yes)
			(layer "F.SilkS")
		)
		(fp_line
			(start 13.999972 18.375122)
			(end 13.999972 -14.675104)
			(stroke
				(width 0.1524)
				(type default)
			)
			(layer "B.SilkS")
		)
		(fp_line
			(start 13.999972 -14.675104)
			(end -3.999992 -14.675104)
			(stroke
				(width 0.1524)
				(type default)
			)
			(layer "B.SilkS")
		)
		(fp_line
			(start -3.999992 18.375122)
			(end 13.999972 18.375122)
			(stroke
				(width 0.1524)
				(type default)
			)
			(layer "B.SilkS")
		)
		(fp_line
			(start -3.999992 -14.675104)
			(end -3.999992 18.375122)
			(stroke
				(width 0.1524)
				(type default)
			)
			(layer "B.SilkS")
		)
		(fp_poly
			(pts
				(xy 9.49198 11.707876) (xy 9.49198 11.608054) (xy 10.50798 11.608054) (xy 10.50798 -0.608076) (xy 0.508 -0.608076)
				(xy 0.508 -0.508) (xy -0.508 -0.508) (xy -0.508 11.707876)
			)
			(stroke
				(width 0)
				(type default)
			)
			(fill no)
			(layer "B.CrtYd")
		)
		(fp_poly
			(pts
				(xy -0.999998 15.375128) (xy 10.999978 15.375128) (xy 10.999978 -11.67511) (xy -0.999998 -11.67511)
			)
			(stroke
				(width 0)
				(type default)
			)
			(fill no)
			(layer "F.CrtYd")
		)
		(fp_line
			(start 13.999972 18.375122)
			(end 13.999972 -14.675104)
			(stroke
				(width 0.1)
				(type default)
			)
			(layer "B.Fab")
		)
		(fp_line
			(start 13.999972 -14.675104)
			(end -3.999992 -14.675104)
			(stroke
				(width 0.1)
				(type default)
			)
			(layer "B.Fab")
		)
		(fp_line
			(start -3.999992 18.375122)
			(end 13.999972 18.375122)
			(stroke
				(width 0.1)
				(type default)
			)
			(layer "B.Fab")
		)
		(fp_line
			(start -3.999992 -14.675104)
			(end -3.999992 18.375122)
			(stroke
				(width 0.1)
				(type default)
			)
			(layer "B.Fab")
		)
		(fp_line
			(start 10.999978 15.375128)
			(end 10.999978 -11.67511)
			(stroke
				(width 0.1)
				(type default)
			)
			(layer "F.Fab")
		)
		(fp_line
			(start 10.999978 -11.67511)
			(end -0.999998 -11.67511)
			(stroke
				(width 0.1)
				(type default)
			)
			(layer "F.Fab")
		)
		(fp_line
			(start -0.999998 15.375128)
			(end 10.999978 15.375128)
			(stroke
				(width 0.1)
				(type default)
			)
			(layer "F.Fab")
		)
		(fp_line
			(start -0.999998 -11.67511)
			(end -0.999998 15.375128)
			(stroke
				(width 0.1)
				(type default)
			)
			(layer "F.Fab")
		)
		(fp_poly
			(pts
				(xy -2.261108 0.508) (xy -2.261108 -0.508) (xy -1.245108 0)
			)
			(stroke
				(width 0)
				(type default)
			)
			(fill yes)
			(layer "F.Fab")
		)
		(fp_text user "PRESS-FIT"
			(at 12.25677 0.10287 90)
			(unlocked yes)
			(layer "F.SilkS")
			(effects
				(font
					(size 1.6002 1.1938)
					(thickness 0.1524)
				)
				(justify left)
			)
		)
		(fp_text user "6"
			(at 10.011664 15.904718 0)
			(unlocked yes)
			(layer "F.SilkS")
			(effects
				(font
					(size 0.7874 0.5842)
					(thickness 0.1524)
				)
			)
		)
		(fp_text user "5"
			(at 8.081264 15.930118 0)
			(unlocked yes)
			(layer "F.SilkS")
			(effects
				(font
					(size 0.7874 0.5842)
					(thickness 0.1524)
				)
			)
		)
		(fp_text user "4"
			(at 5.719064 15.980918 0)
			(unlocked yes)
			(layer "F.SilkS")
			(effects
				(font
					(size 0.7874 0.5842)
					(thickness 0.1524)
				)
			)
		)
		(fp_text user "3"
			(at 3.991864 16.031718 0)
			(unlocked yes)
			(layer "F.SilkS")
			(effects
				(font
					(size 0.7874 0.5842)
					(thickness 0.1524)
				)
			)
		)
		(fp_text user "2"
			(at 1.756664 16.057118 0)
			(unlocked yes)
			(layer "F.SilkS")
			(effects
				(font
					(size 0.7874 0.5842)
					(thickness 0.1524)
				)
			)
		)
		(fp_text user "1"
			(at -0.173736 16.107918 0)
			(unlocked yes)
			(layer "F.SilkS")
			(effects
				(font
					(size 0.7874 0.5842)
					(thickness 0.1524)
				)
			)
		)
		(fp_text user "I"
			(at -1.649222 11.210798 180)
			(unlocked yes)
			(layer "F.SilkS")
			(effects
				(font
					(size 0.7874 0.5842)
					(thickness 0.1524)
				)
			)
		)
		(fp_text user "H"
			(at -1.649222 9.81075 180)
			(unlocked yes)
			(layer "F.SilkS")
			(effects
				(font
					(size 0.7874 0.5842)
					(thickness 0.1524)
				)
			)
		)
		(fp_text user "G"
			(at -1.707134 8.3439 0)
			(unlocked yes)
			(layer "F.SilkS")
			(effects
				(font
					(size 0.7874 0.5842)
					(thickness 0.1524)
				)
			)
		)
		(fp_text user "A"
			(at -1.723136 -0.806196 0)
			(unlocked yes)
			(layer "F.SilkS")
			(effects
				(font
					(size 0.7874 0.5842)
					(thickness 0.1524)
				)
			)
		)
		(fp_text user "F"
			(at -1.732534 7.000748 0)
			(unlocked yes)
			(layer "F.SilkS")
			(effects
				(font
					(size 0.7874 0.5842)
					(thickness 0.1524)
				)
			)
		)
		(fp_text user "C"
			(at -1.732534 2.768092 0)
			(unlocked yes)
			(layer "F.SilkS")
			(effects
				(font
					(size 0.7874 0.5842)
					(thickness 0.1524)
				)
			)
		)
		(fp_text user "E"
			(at -1.783334 5.657596 0)
			(unlocked yes)
			(layer "F.SilkS")
			(effects
				(font
					(size 0.7874 0.5842)
					(thickness 0.1524)
				)
			)
		)
		(fp_text user "B"
			(at -1.808734 1.39954 0)
			(unlocked yes)
			(layer "F.SilkS")
			(effects
				(font
					(size 0.7874 0.5842)
					(thickness 0.1524)
				)
			)
		)
		(fp_text user "D"
			(at -1.859534 4.136644 0)
			(unlocked yes)
			(layer "F.SilkS")
			(effects
				(font
					(size 0.7874 0.5842)
					(thickness 0.1524)
				)
			)
		)
		(fp_text user "PRESS-FIT"
			(at 12.75969 -0.0381 270)
			(unlocked yes)
			(layer "B.SilkS")
			(effects
				(font
					(size 1.6002 1.1938)
					(thickness 0.1524)
				)
				(justify left mirror)
			)
		)
		(fp_text user "6"
			(at 9.986264 -1.288796 0)
			(unlocked yes)
			(layer "B.SilkS")
			(effects
				(font
					(size 0.7874 0.5842)
					(thickness 0.1524)
				)
				(justify mirror)
			)
		)
		(fp_text user "5"
			(at 8.030464 -1.263396 0)
			(unlocked yes)
			(layer "B.SilkS")
			(effects
				(font
					(size 0.7874 0.5842)
					(thickness 0.1524)
				)
				(justify mirror)
			)
		)
		(fp_text user "4"
			(at 5.998464 -1.339596 0)
			(unlocked yes)
			(layer "B.SilkS")
			(effects
				(font
					(size 0.7874 0.5842)
					(thickness 0.1524)
				)
				(justify mirror)
			)
		)
		(fp_text user "3"
			(at 3.991864 -1.339596 0)
			(unlocked yes)
			(layer "B.SilkS")
			(effects
				(font
					(size 0.7874 0.5842)
					(thickness 0.1524)
				)
				(justify mirror)
			)
		)
		(fp_text user "2"
			(at 1.959864 -1.314196 0)
			(unlocked yes)
			(layer "B.SilkS")
			(effects
				(font
					(size 0.7874 0.5842)
					(thickness 0.1524)
				)
				(justify mirror)
			)
		)
		(fp_text user "1"
			(at 0.004064 -1.212596 0)
			(unlocked yes)
			(layer "B.SilkS")
			(effects
				(font
					(size 0.7874 0.5842)
					(thickness 0.1524)
				)
				(justify mirror)
			)
		)
		(fp_text user "I"
			(at -1.503934 11.157458 0)
			(unlocked yes)
			(layer "B.SilkS")
			(effects
				(font
					(size 0.7874 0.5842)
					(thickness 0.1524)
				)
				(justify mirror)
			)
		)
		(fp_text user "F"
			(at -1.503934 6.899148 0)
			(unlocked yes)
			(layer "B.SilkS")
			(effects
				(font
					(size 0.7874 0.5842)
					(thickness 0.1524)
				)
				(justify mirror)
			)
		)
		(fp_text user "D"
			(at -1.529334 4.187444 0)
			(unlocked yes)
			(layer "B.SilkS")
			(effects
				(font
					(size 0.7874 0.5842)
					(thickness 0.1524)
				)
				(justify mirror)
			)
		)
		(fp_text user "A"
			(at -1.545336 -0.069596 0)
			(unlocked yes)
			(layer "B.SilkS")
			(effects
				(font
					(size 0.7874 0.5842)
					(thickness 0.1524)
				)
				(justify mirror)
			)
		)
		(fp_text user "H"
			(at -1.554734 9.687306 0)
			(unlocked yes)
			(layer "B.SilkS")
			(effects
				(font
					(size 0.7874 0.5842)
					(thickness 0.1524)
				)
				(justify mirror)
			)
		)
		(fp_text user "B"
			(at -1.554734 1.37414 0)
			(unlocked yes)
			(layer "B.SilkS")
			(effects
				(font
					(size 0.7874 0.5842)
					(thickness 0.1524)
				)
				(justify mirror)
			)
		)
		(fp_text user "G"
			(at -1.580134 8.3947 0)
			(unlocked yes)
			(layer "B.SilkS")
			(effects
				(font
					(size 0.7874 0.5842)
					(thickness 0.1524)
				)
				(justify mirror)
			)
		)
		(fp_text user "E"
			(at -1.580134 5.530596 0)
			(unlocked yes)
			(layer "B.SilkS")
			(effects
				(font
					(size 0.7874 0.5842)
					(thickness 0.1524)
				)
				(justify mirror)
			)
		)
		(fp_text user "C"
			(at -1.605534 2.768092 0)
			(unlocked yes)
			(layer "B.SilkS")
			(effects
				(font
					(size 0.7874 0.5842)
					(thickness 0.1524)
				)
				(justify mirror)
			)
		)
		(fp_text user "PRESS-FIT"
			(at 12.75969 -0.0381 270)
			(unlocked yes)
			(layer "B.Fab")
			(effects
				(font
					(size 1.6002 1.1938)
					(thickness 0.000001)
				)
				(justify left mirror)
			)
		)
		(fp_text user "6"
			(at 9.99998 -1.666748 180)
			(unlocked yes)
			(layer "B.Fab")
			(effects
				(font
					(size 0.7874 0.5842)
					(thickness 0.000001)
				)
				(justify mirror)
			)
		)
		(fp_text user "5"
			(at 7.96798 -1.615948 180)
			(unlocked yes)
			(layer "B.Fab")
			(effects
				(font
					(size 0.7874 0.5842)
					(thickness 0.000001)
				)
				(justify mirror)
			)
		)
		(fp_text user "4"
			(at 5.88518 -1.615948 180)
			(unlocked yes)
			(layer "B.Fab")
			(effects
				(font
					(size 0.7874 0.5842)
					(thickness 0.000001)
				)
				(justify mirror)
			)
		)
		(fp_text user "3"
			(at 3.90398 -1.615948 180)
			(unlocked yes)
			(layer "B.Fab")
			(effects
				(font
					(size 0.7874 0.5842)
					(thickness 0.000001)
				)
				(justify mirror)
			)
		)
		(fp_text user "2"
			(at 1.97358 -1.615948 180)
			(unlocked yes)
			(layer "B.Fab")
			(effects
				(font
					(size 0.7874 0.5842)
					(thickness 0.000001)
				)
				(justify mirror)
			)
		)
		(fp_text user "1"
			(at -0.00762 -1.615948 180)
			(unlocked yes)
			(layer "B.Fab")
			(effects
				(font
					(size 0.7874 0.5842)
					(thickness 0.000001)
				)
				(justify mirror)
			)
		)
		(fp_text user "A"
			(at -1.50622 -0.041148 180)
			(unlocked yes)
			(layer "B.Fab")
			(effects
				(font
					(size 0.7874 0.5842)
					(thickness 0.000001)
				)
				(justify mirror)
			)
		)
		(fp_text user "I"
			(at -1.522222 11.210798 180)
			(unlocked yes)
			(layer "B.Fab")
			(effects
				(font
					(size 0.7874 0.5842)
					(thickness 0.000001)
				)
				(justify mirror)
			)
		)
		(fp_text user "H"
			(at -1.522222 9.81075 180)
			(unlocked yes)
			(layer "B.Fab")
			(effects
				(font
					(size 0.7874 0.5842)
					(thickness 0.000001)
				)
				(justify mirror)
			)
		)
		(fp_text user "G"
			(at -1.522222 8.410956 180)
			(unlocked yes)
			(layer "B.Fab")
			(effects
				(font
					(size 0.7874 0.5842)
					(thickness 0.000001)
				)
				(justify mirror)
			)
		)
		(fp_text user "F"
			(at -1.522222 7.010908 180)
			(unlocked yes)
			(layer "B.Fab")
			(effects
				(font
					(size 0.7874 0.5842)
					(thickness 0.000001)
				)
				(justify mirror)
			)
		)
		(fp_text user "E"
			(at -1.522222 5.61086 180)
			(unlocked yes)
			(layer "B.Fab")
			(effects
				(font
					(size 0.7874 0.5842)
					(thickness 0.000001)
				)
				(justify mirror)
			)
		)
		(fp_text user "D"
			(at -1.522222 4.210812 180)
			(unlocked yes)
			(layer "B.Fab")
			(effects
				(font
					(size 0.7874 0.5842)
					(thickness 0.000001)
				)
				(justify mirror)
			)
		)
		(fp_text user "C"
			(at -1.522222 2.810764 180)
			(unlocked yes)
			(layer "B.Fab")
			(effects
				(font
					(size 0.7874 0.5842)
					(thickness 0.000001)
				)
				(justify mirror)
			)
		)
		(fp_text user "B"
			(at -1.522222 1.410716 180)
			(unlocked yes)
			(layer "B.Fab")
			(effects
				(font
					(size 0.7874 0.5842)
					(thickness 0.000001)
				)
				(justify mirror)
			)
		)
		(fp_text user "PRESS-FIT"
			(at 12.758674 14.569186 270)
			(unlocked yes)
			(layer "F.Fab")
			(effects
				(font
					(size 1.6002 1.1938)
					(thickness 0.000001)
				)
				(justify left)
			)
		)
		(fp_text user "6"
			(at 10.12698 16.013938 180)
			(unlocked yes)
			(layer "F.Fab")
			(effects
				(font
					(size 0.7874 0.5842)
					(thickness 0.000001)
				)
			)
		)
		(fp_text user "5"
			(at 8.09498 16.064738 180)
			(unlocked yes)
			(layer "F.Fab")
			(effects
				(font
					(size 0.7874 0.5842)
					(thickness 0.000001)
				)
			)
		)
		(fp_text user "4"
			(at 6.01218 16.064738 180)
			(unlocked yes)
			(layer "F.Fab")
			(effects
				(font
					(size 0.7874 0.5842)
					(thickness 0.000001)
				)
			)
		)
		(fp_text user "3"
			(at 4.03098 16.064738 180)
			(unlocked yes)
			(layer "F.Fab")
			(effects
				(font
					(size 0.7874 0.5842)
					(thickness 0.000001)
				)
			)
		)
		(fp_text user "2"
			(at 2.10058 16.064738 180)
			(unlocked yes)
			(layer "F.Fab")
			(effects
				(font
					(size 0.7874 0.5842)
					(thickness 0.000001)
				)
			)
		)
		(fp_text user "1"
			(at 0.11938 16.064738 180)
			(unlocked yes)
			(layer "F.Fab")
			(effects
				(font
					(size 0.7874 0.5842)
					(thickness 0.000001)
				)
			)
		)
		(fp_text user "I"
			(at -1.649222 11.210798 180)
			(unlocked yes)
			(layer "F.Fab")
			(effects
				(font
					(size 0.7874 0.5842)
					(thickness 0.000001)
				)
			)
		)
		(fp_text user "H"
			(at -1.649222 9.81075 180)
			(unlocked yes)
			(layer "F.Fab")
			(effects
				(font
					(size 0.7874 0.5842)
					(thickness 0.000001)
				)
			)
		)
		(fp_text user "G"
			(at -1.649222 8.410956 180)
			(unlocked yes)
			(layer "F.Fab")
			(effects
				(font
					(size 0.7874 0.5842)
					(thickness 0.000001)
				)
			)
		)
		(fp_text user "F"
			(at -1.649222 7.010908 180)
			(unlocked yes)
			(layer "F.Fab")
			(effects
				(font
					(size 0.7874 0.5842)
					(thickness 0.000001)
				)
			)
		)
		(fp_text user "E"
			(at -1.649222 5.61086 180)
			(unlocked yes)
			(layer "F.Fab")
			(effects
				(font
					(size 0.7874 0.5842)
					(thickness 0.000001)
				)
			)
		)
		(fp_text user "D"
			(at -1.649222 4.210812 180)
			(unlocked yes)
			(layer "F.Fab")
			(effects
				(font
					(size 0.7874 0.5842)
					(thickness 0.000001)
				)
			)
		)
		(fp_text user "C"
			(at -1.649222 2.810764 180)
			(unlocked yes)
			(layer "F.Fab")
			(effects
				(font
					(size 0.7874 0.5842)
					(thickness 0.000001)
				)
			)
		)
		(fp_text user "B"
			(at -1.649222 1.410716 180)
			(unlocked yes)
			(layer "F.Fab")
			(effects
				(font
					(size 0.7874 0.5842)
					(thickness 0.000001)
				)
			)
		)
		(fp_text user "A"
			(at -1.68402 -0.803148 180)
			(unlocked yes)
			(layer "F.Fab")
			(effects
				(font
					(size 0.7874 0.5842)
					(thickness 0.000001)
				)
			)
		)
		(pad "A1" thru_hole rect
			(at 0 0)
			(size 0.9144 0.9144)
			(drill 0.508)
			(layers "*.Cu" "*.Mask")
			(remove_unused_layers no)
			(net "SAS_BLAD1_TX1_P")
			(clearance 0.0508)
			(thermal_gap 0.0508)
			(padstack
				(mode front_inner_back)
				(layer "Inner"
					(shape circle)
					(size 0.9144 0.9144)
					(clearance 0.0508)
				)
				(layer "B.Cu"
					(shape rect)
					(size 0.9144 0.9144)
					(clearance 0.0508)
				)
			)
		)
		(pad "A2" thru_hole circle
			(at 1.999996 -0.100076)
			(size 0.9144 0.9144)
			(drill 0.508)
			(layers "*.Cu" "*.Mask")
			(remove_unused_layers no)
			(net "GND")
			(clearance 0.0508)
			(thermal_gap 0.0508)
		)
		(pad "A3" thru_hole circle
			(at 3.999992 0)
			(size 0.9144 0.9144)
			(drill 0.508)
			(layers "*.Cu" "*.Mask")
			(remove_unused_layers no)
			(net "AIRMAX_RSVD3")
			(clearance 0.0508)
			(thermal_gap 0.0508)
		)
		(pad "A4" thru_hole circle
			(at 5.999988 -0.100076)
			(size 0.9144 0.9144)
			(drill 0.508)
			(layers "*.Cu" "*.Mask")
			(remove_unused_layers no)
			(net "GND")
			(clearance 0.0508)
			(thermal_gap 0.0508)
		)
		(pad "A5" thru_hole circle
			(at 7.999984 0)
			(size 0.9144 0.9144)
			(drill 0.508)
			(layers "*.Cu" "*.Mask")
			(remove_unused_layers no)
			(net "SAS_BLAD1_TX6_P")
			(clearance 0.0508)
			(thermal_gap 0.0508)
		)
		(pad "A6" thru_hole circle
			(at 9.99998 -0.100076)
			(size 0.9144 0.9144)
			(drill 0.508)
			(layers "*.Cu" "*.Mask")
			(remove_unused_layers no)
			(net "GND")
			(clearance 0.0508)
			(thermal_gap 0.0508)
		)
		(pad "B1" thru_hole circle
			(at 0 1.400048)
			(size 0.9144 0.9144)
			(drill 0.508)
			(layers "*.Cu" "*.Mask")
			(remove_unused_layers no)
			(net "SAS_BLAD1_TX1_N")
			(clearance 0.0508)
			(thermal_gap 0.0508)
		)
		(pad "B2" thru_hole circle
			(at 1.999996 1.299972)
			(size 0.9144 0.9144)
			(drill 0.508)
			(layers "*.Cu" "*.Mask")
			(remove_unused_layers no)
			(net "SAS_BLAD1_RX3_P")
			(clearance 0.0508)
			(thermal_gap 0.0508)
		)
		(pad "B3" thru_hole circle
			(at 3.999992 1.400048)
			(size 0.9144 0.9144)
			(drill 0.508)
			(layers "*.Cu" "*.Mask")
			(remove_unused_layers no)
			(net "AIRMAX_RSVD4")
			(clearance 0.0508)
			(thermal_gap 0.0508)
		)
		(pad "B4" thru_hole circle
			(at 5.999988 1.299972)
			(size 0.9144 0.9144)
			(drill 0.508)
			(layers "*.Cu" "*.Mask")
			(remove_unused_layers no)
			(net "AIRMAX_RSVD1")
			(clearance 0.0508)
			(thermal_gap 0.0508)
		)
		(pad "B5" thru_hole circle
			(at 7.999984 1.400048)
			(size 0.9144 0.9144)
			(drill 0.508)
			(layers "*.Cu" "*.Mask")
			(remove_unused_layers no)
			(net "SAS_BLAD1_TX6_N")
			(clearance 0.0508)
			(thermal_gap 0.0508)
		)
		(pad "B6" thru_hole circle
			(at 9.99998 1.299972)
			(size 0.9144 0.9144)
			(drill 0.508)
			(layers "*.Cu" "*.Mask")
			(remove_unused_layers no)
			(net "SAS_BLAD1_RX8_P")
			(clearance 0.0508)
			(thermal_gap 0.0508)
		)
		(pad "C1" thru_hole circle
			(at 0 2.800096)
			(size 0.9144 0.9144)
			(drill 0.508)
			(layers "*.Cu" "*.Mask")
			(remove_unused_layers no)
			(net "GND")
			(clearance 0.0508)
			(thermal_gap 0.0508)
		)
		(pad "C2" thru_hole circle
			(at 1.999996 2.70002)
			(size 0.9144 0.9144)
			(drill 0.508)
			(layers "*.Cu" "*.Mask")
			(remove_unused_layers no)
			(net "SAS_BLAD1_RX3_N")
			(clearance 0.0508)
			(thermal_gap 0.0508)
		)
		(pad "C3" thru_hole circle
			(at 3.999992 2.800096)
			(size 0.9144 0.9144)
			(drill 0.508)
			(layers "*.Cu" "*.Mask")
			(remove_unused_layers no)
			(net "GND")
			(clearance 0.0508)
			(thermal_gap 0.0508)
		)
		(pad "C4" thru_hole circle
			(at 5.999988 2.70002)
			(size 0.9144 0.9144)
			(drill 0.508)
			(layers "*.Cu" "*.Mask")
			(remove_unused_layers no)
			(net "AIRMAX_RSVD2")
			(clearance 0.0508)
			(thermal_gap 0.0508)
		)
		(pad "C5" thru_hole circle
			(at 7.999984 2.800096)
			(size 0.9144 0.9144)
			(drill 0.508)
			(layers "*.Cu" "*.Mask")
			(remove_unused_layers no)
			(net "GND")
			(clearance 0.0508)
			(thermal_gap 0.0508)
		)
		(pad "C6" thru_hole circle
			(at 9.99998 2.70002)
			(size 0.9144 0.9144)
			(drill 0.508)
			(layers "*.Cu" "*.Mask")
			(remove_unused_layers no)
			(net "SAS_BLAD1_RX8_N")
			(clearance 0.0508)
			(thermal_gap 0.0508)
		)
		(pad "D1" thru_hole circle
			(at 0 4.19989)
			(size 0.9144 0.9144)
			(drill 0.508)
			(layers "*.Cu" "*.Mask")
			(remove_unused_layers no)
			(net "SAS_BLAD1_RX1_P")
			(clearance 0.0508)
			(thermal_gap 0.0508)
		)
		(pad "D2" thru_hole circle
			(at 1.999996 4.100068)
			(size 0.9144 0.9144)
			(drill 0.508)
			(layers "*.Cu" "*.Mask")
			(remove_unused_layers no)
			(net "GND")
			(clearance 0.0508)
			(thermal_gap 0.0508)
		)
		(pad "D3" thru_hole circle
			(at 3.999992 4.19989)
			(size 0.9144 0.9144)
			(drill 0.508)
			(layers "*.Cu" "*.Mask")
			(remove_unused_layers no)
			(net "SAS_BLAD1_RX4_P")
			(clearance 0.0508)
			(thermal_gap 0.0508)
		)
		(pad "D4" thru_hole circle
			(at 5.999988 4.100068)
			(size 0.9144 0.9144)
			(drill 0.508)
			(layers "*.Cu" "*.Mask")
			(remove_unused_layers no)
			(net "GND")
			(clearance 0.0508)
			(thermal_gap 0.0508)
		)
		(pad "D5" thru_hole circle
			(at 7.999984 4.19989)
			(size 0.9144 0.9144)
			(drill 0.508)
			(layers "*.Cu" "*.Mask")
			(remove_unused_layers no)
			(net "SAS_BLAD1_RX6_P")
			(clearance 0.0508)
			(thermal_gap 0.0508)
		)
		(pad "D6" thru_hole circle
			(at 9.99998 4.100068)
			(size 0.9144 0.9144)
			(drill 0.508)
			(layers "*.Cu" "*.Mask")
			(remove_unused_layers no)
			(net "GND")
			(clearance 0.0508)
			(thermal_gap 0.0508)
		)
		(pad "E1" thru_hole circle
			(at 0 5.599938)
			(size 0.9144 0.9144)
			(drill 0.508)
			(layers "*.Cu" "*.Mask")
			(remove_unused_layers no)
			(net "SAS_BLAD1_RX1_N")
			(clearance 0.0508)
			(thermal_gap 0.0508)
		)
		(pad "E2" thru_hole circle
			(at 1.999996 5.500116)
			(size 0.9144 0.9144)
			(drill 0.508)
			(layers "*.Cu" "*.Mask")
			(remove_unused_layers no)
			(net "SAS_BLAD1_TX3_P")
			(clearance 0.0508)
			(thermal_gap 0.0508)
		)
		(pad "E3" thru_hole circle
			(at 3.999992 5.599938)
			(size 0.9144 0.9144)
			(drill 0.508)
			(layers "*.Cu" "*.Mask")
			(remove_unused_layers no)
			(net "SAS_BLAD1_RX4_N")
			(clearance 0.0508)
			(thermal_gap 0.0508)
		)
		(pad "E4" thru_hole circle
			(at 5.999988 5.500116)
			(size 0.9144 0.9144)
			(drill 0.508)
			(layers "*.Cu" "*.Mask")
			(remove_unused_layers no)
			(net "SAS_BLAD1_TX5_P")
			(clearance 0.0508)
			(thermal_gap 0.0508)
		)
		(pad "E5" thru_hole circle
			(at 7.999984 5.599938)
			(size 0.9144 0.9144)
			(drill 0.508)
			(layers "*.Cu" "*.Mask")
			(remove_unused_layers no)
			(net "SAS_BLAD1_RX6_N")
			(clearance 0.0508)
			(thermal_gap 0.0508)
		)
		(pad "E6" thru_hole circle
			(at 9.99998 5.500116)
			(size 0.9144 0.9144)
			(drill 0.508)
			(layers "*.Cu" "*.Mask")
			(remove_unused_layers no)
			(net "SAS_BLAD1_TX8_P")
			(clearance 0.0508)
			(thermal_gap 0.0508)
		)
		(pad "F1" thru_hole circle
			(at 0 6.999986)
			(size 0.9144 0.9144)
			(drill 0.508)
			(layers "*.Cu" "*.Mask")
			(remove_unused_layers no)
			(net "GND")
			(clearance 0.0508)
			(thermal_gap 0.0508)
		)
		(pad "F2" thru_hole circle
			(at 1.999996 6.89991)
			(size 0.9144 0.9144)
			(drill 0.508)
			(layers "*.Cu" "*.Mask")
			(remove_unused_layers no)
			(net "SAS_BLAD1_TX3_N")
			(clearance 0.0508)
			(thermal_gap 0.0508)
		)
		(pad "F3" thru_hole circle
			(at 3.999992 6.999986)
			(size 0.9144 0.9144)
			(drill 0.508)
			(layers "*.Cu" "*.Mask")
			(remove_unused_layers no)
			(net "GND")
			(clearance 0.0508)
			(thermal_gap 0.0508)
		)
		(pad "F4" thru_hole circle
			(at 5.999988 6.89991)
			(size 0.9144 0.9144)
			(drill 0.508)
			(layers "*.Cu" "*.Mask")
			(remove_unused_layers no)
			(net "SAS_BLAD1_TX5_N")
			(clearance 0.0508)
			(thermal_gap 0.0508)
		)
		(pad "F5" thru_hole circle
			(at 7.999984 6.999986)
			(size 0.9144 0.9144)
			(drill 0.508)
			(layers "*.Cu" "*.Mask")
			(remove_unused_layers no)
			(net "GND")
			(clearance 0.0508)
			(thermal_gap 0.0508)
		)
		(pad "F6" thru_hole circle
			(at 9.99998 6.89991)
			(size 0.9144 0.9144)
			(drill 0.508)
			(layers "*.Cu" "*.Mask")
			(remove_unused_layers no)
			(net "SAS_BLAD1_TX8_N")
			(clearance 0.0508)
			(thermal_gap 0.0508)
		)
		(pad "G1" thru_hole circle
			(at 0 8.400034)
			(size 0.9144 0.9144)
			(drill 0.508)
			(layers "*.Cu" "*.Mask")
			(remove_unused_layers no)
			(net "SAS_BLAD1_TX2_P")
			(clearance 0.0508)
			(thermal_gap 0.0508)
		)
		(pad "G2" thru_hole circle
			(at 1.999996 8.299958)
			(size 0.9144 0.9144)
			(drill 0.508)
			(layers "*.Cu" "*.Mask")
			(remove_unused_layers no)
			(net "GND")
			(clearance 0.0508)
			(thermal_gap 0.0508)
		)
		(pad "G3" thru_hole circle
			(at 3.999992 8.400034)
			(size 0.9144 0.9144)
			(drill 0.508)
			(layers "*.Cu" "*.Mask")
			(remove_unused_layers no)
			(net "SAS_BLAD1_TX4_P")
			(clearance 0.0508)
			(thermal_gap 0.0508)
		)
		(pad "G4" thru_hole circle
			(at 5.999988 8.299958)
			(size 0.9144 0.9144)
			(drill 0.508)
			(layers "*.Cu" "*.Mask")
			(remove_unused_layers no)
			(net "GND")
			(clearance 0.0508)
			(thermal_gap 0.0508)
		)
		(pad "G5" thru_hole circle
			(at 7.999984 8.400034)
			(size 0.9144 0.9144)
			(drill 0.508)
			(layers "*.Cu" "*.Mask")
			(remove_unused_layers no)
			(net "SAS_BLAD1_TX7_P")
			(clearance 0.0508)
			(thermal_gap 0.0508)
		)
		(pad "G6" thru_hole circle
			(at 9.99998 8.299958)
			(size 0.9144 0.9144)
			(drill 0.508)
			(layers "*.Cu" "*.Mask")
			(remove_unused_layers no)
			(net "GND")
			(clearance 0.0508)
			(thermal_gap 0.0508)
		)
		(pad "H1" thru_hole circle
			(at 0 9.800082)
			(size 0.9144 0.9144)
			(drill 0.508)
			(layers "*.Cu" "*.Mask")
			(remove_unused_layers no)
			(net "SAS_BLAD1_TX2_N")
			(clearance 0.0508)
			(thermal_gap 0.0508)
		)
		(pad "H2" thru_hole circle
			(at 1.999996 9.700006)
			(size 0.9144 0.9144)
			(drill 0.508)
			(layers "*.Cu" "*.Mask")
			(remove_unused_layers no)
			(net "SAS_BLAD1_RX2_P")
			(clearance 0.0508)
			(thermal_gap 0.0508)
		)
		(pad "H3" thru_hole circle
			(at 3.999992 9.800082)
			(size 0.9144 0.9144)
			(drill 0.508)
			(layers "*.Cu" "*.Mask")
			(remove_unused_layers no)
			(net "SAS_BLAD1_TX4_N")
			(clearance 0.0508)
			(thermal_gap 0.0508)
		)
		(pad "H4" thru_hole circle
			(at 5.999988 9.700006)
			(size 0.9144 0.9144)
			(drill 0.508)
			(layers "*.Cu" "*.Mask")
			(remove_unused_layers no)
			(net "SAS_BLAD1_RX5_P")
			(clearance 0.0508)
			(thermal_gap 0.0508)
		)
		(pad "H5" thru_hole circle
			(at 7.999984 9.800082)
			(size 0.9144 0.9144)
			(drill 0.508)
			(layers "*.Cu" "*.Mask")
			(remove_unused_layers no)
			(net "SAS_BLAD1_TX7_N")
			(clearance 0.0508)
			(thermal_gap 0.0508)
		)
		(pad "H6" thru_hole circle
			(at 9.99998 9.700006)
			(size 0.9144 0.9144)
			(drill 0.508)
			(layers "*.Cu" "*.Mask")
			(remove_unused_layers no)
			(net "SAS_BLAD1_RX7_P")
			(clearance 0.0508)
			(thermal_gap 0.0508)
		)
		(pad "I1" thru_hole circle
			(at 0 11.199876)
			(size 0.9144 0.9144)
			(drill 0.508)
			(layers "*.Cu" "*.Mask")
			(remove_unused_layers no)
			(net "GND")
			(clearance 0.0508)
			(thermal_gap 0.0508)
		)
		(pad "I2" thru_hole circle
			(at 1.999996 11.100054)
			(size 0.9144 0.9144)
			(drill 0.508)
			(layers "*.Cu" "*.Mask")
			(remove_unused_layers no)
			(net "SAS_BLAD1_RX2_N")
			(clearance 0.0508)
			(thermal_gap 0.0508)
		)
		(pad "I3" thru_hole circle
			(at 3.999992 11.199876)
			(size 0.9144 0.9144)
			(drill 0.508)
			(layers "*.Cu" "*.Mask")
			(remove_unused_layers no)
			(net "GND")
			(clearance 0.0508)
			(thermal_gap 0.0508)
		)
		(pad "I4" thru_hole circle
			(at 5.999988 11.100054)
			(size 0.9144 0.9144)
			(drill 0.508)
			(layers "*.Cu" "*.Mask")
			(remove_unused_layers no)
			(net "SAS_BLAD1_RX5_N")
			(clearance 0.0508)
			(thermal_gap 0.0508)
		)
		(pad "I5" thru_hole circle
			(at 7.999984 11.199876)
			(size 0.9144 0.9144)
			(drill 0.508)
			(layers "*.Cu" "*.Mask")
			(remove_unused_layers no)
			(net "GND")
			(clearance 0.0508)
			(thermal_gap 0.0508)
		)
		(pad "I6" thru_hole circle
			(at 9.99998 11.100054)
			(size 0.9144 0.9144)
			(drill 0.508)
			(layers "*.Cu" "*.Mask")
			(remove_unused_layers no)
			(net "SAS_BLAD1_RX7_N")
			(clearance 0.0508)
			(thermal_gap 0.0508)
		)
		(zone
			(layer "B.Cu")
			(hatch none 0.5)
			(connect_pads
				(clearance 0)
			)
			(min_thickness 0.25)
			(keepout
				(tracks allowed)
				(vias not_allowed)
				(pads allowed)
				(copperpour not_allowed)
				(footprints allowed)
			)
			(placement
				(enabled no)
				(sheetname "")
			)
			(fill
				(thermal_gap 0.5)
				(thermal_bridge_width 0.5)
				(island_removal_mode 0)
			)
			(polygon
				(pts
					(xy 165.397942 -13.807948) (xy 165.397942 -13.708126) (xy 164.381942 -13.708126) (xy 164.381942 -1.491996)
					(xy 174.381922 -1.491996) (xy 174.381922 -1.592072) (xy 175.397922 -1.592072) (xy 175.397922 -13.807948)
				)
			)
		)
	)
	(footprint ""
		(layer "F.Cu")
		(at 326.644 -2.6416 90)
		(property "Reference" "C27"
			(at -1.6002 -4.384548 90)
			(unlocked yes)
			(layer "F.SilkS")
			(effects
				(font
					(size 0.7874 0.5842)
					(thickness 0.1524)
				)
				(justify left)
			)
		)
		(property "Value" ""
			(at 0 0 90)
			(layer "F.Fab")
			(effects
				(font
					(size 1.27 1.27)
				)
			)
		)
		(duplicate_pad_numbers_are_jumpers no)
		(fp_line
			(start 0.7874 -0.4064)
			(end 0.7874 0.4064)
			(stroke
				(width 0.1524)
				(type default)
			)
			(layer "F.SilkS")
		)
		(fp_line
			(start -0.7874 -0.4064)
			(end 0.7874 -0.4064)
			(stroke
				(width 0.1524)
				(type default)
			)
			(layer "F.SilkS")
		)
		(fp_line
			(start 0 0.381)
			(end 0 -0.381)
			(stroke
				(width 0.1524)
				(type default)
			)
			(layer "F.SilkS")
		)
		(fp_line
			(start 0.7874 0.4064)
			(end -0.7874 0.4064)
			(stroke
				(width 0.1524)
				(type default)
			)
			(layer "F.SilkS")
		)
		(fp_line
			(start -0.7874 0.4064)
			(end -0.7874 -0.4064)
			(stroke
				(width 0.1524)
				(type default)
			)
			(layer "F.SilkS")
		)
		(fp_poly
			(pts
				(xy -0.5334 0.254) (xy -0.635 0.254) (xy -0.635 0.2286) (xy -0.635 -0.254) (xy -0.5334 -0.254) (xy -0.5334 -0.2794)
				(xy 0.5334 -0.2794) (xy 0.5334 -0.254) (xy 0.635 -0.254) (xy 0.635 0.254) (xy 0.5334 0.254) (xy 0.5334 0.2794)
				(xy -0.508 0.2794) (xy -0.5334 0.2794)
			)
			(stroke
				(width 0)
				(type default)
			)
			(fill no)
			(layer "F.CrtYd")
		)
		(pad "1" smd rect
			(at 0.40005 0 90)
			(size 0.4572 0.508)
			(layers "F.Cu" "F.Mask" "F.Paste")
			(net "P3V3_10G_4_VCCT")
		)
		(pad "2" smd rect
			(at -0.40005 0 90)
			(size 0.4572 0.508)
			(layers "F.Cu" "F.Mask" "F.Paste")
			(net "GND")
		)
	)
	(footprint ""
		(layer "F.Cu")
		(at 340.261448 -22.239732 180)
		(property "Reference" "R72"
			(at 58.070496 4.329684 0)
			(unlocked yes)
			(layer "F.SilkS")
			(effects
				(font
					(size 0.7874 0.5842)
					(thickness 0.1524)
				)
				(justify left)
			)
		)
		(property "Value" ""
			(at 0 0 180)
			(layer "F.Fab")
			(effects
				(font
					(size 1.27 1.27)
				)
			)
		)
		(duplicate_pad_numbers_are_jumpers no)
		(fp_line
			(start 0.7874 0.4064)
			(end -0.7874 0.4064)
			(stroke
				(width 0.1524)
				(type default)
			)
			(layer "F.SilkS")
		)
		(fp_line
			(start 0.7874 -0.4064)
			(end 0.7874 0.4064)
			(stroke
				(width 0.1524)
				(type default)
			)
			(layer "F.SilkS")
		)
		(fp_line
			(start -0.7874 0.4064)
			(end -0.7874 -0.4064)
			(stroke
				(width 0.1524)
				(type default)
			)
			(layer "F.SilkS")
		)
		(fp_line
			(start -0.7874 -0.4064)
			(end 0.7874 -0.4064)
			(stroke
				(width 0.1524)
				(type default)
			)
			(layer "F.SilkS")
		)
		(fp_poly
			(pts
				(xy -0.508 0.2794) (xy -0.508 0.2286) (xy -0.635 0.2286) (xy -0.635 -0.254) (xy -0.5334 -0.254)
				(xy -0.5334 -0.2794) (xy 0.5334 -0.2794) (xy 0.5334 -0.254) (xy 0.635 -0.254) (xy 0.635 0.254) (xy 0.5334 0.254)
				(xy 0.5334 0.2794)
			)
			(stroke
				(width 0)
				(type default)
			)
			(fill no)
			(layer "F.CrtYd")
		)
		(pad "1" smd rect
			(at 0.40005 0 180)
			(size 0.4572 0.508)
			(layers "F.Cu" "F.Mask" "F.Paste")
			(net "ENET10G_4_LOS")
		)
		(pad "2" smd rect
			(at -0.40005 0 180)
			(size 0.4572 0.508)
			(layers "F.Cu" "F.Mask" "F.Paste")
			(net "SFP4_PRESENT_N")
		)
	)
	(footprint ""
		(layer "F.Cu")
		(at 309.200296 -23.520146 -90)
		(property "Reference" "C10"
			(at -2.235708 5.167122 90)
			(unlocked yes)
			(layer "F.SilkS")
			(effects
				(font
					(size 0.7874 0.5842)
					(thickness 0.1524)
				)
			)
		)
		(property "Value" ""
			(at 0 0 270)
			(layer "F.Fab")
			(effects
				(font
					(size 1.27 1.27)
				)
			)
		)
		(duplicate_pad_numbers_are_jumpers no)
		(fp_line
			(start -1.2954 0.5842)
			(end -1.2954 -0.5842)
			(stroke
				(width 0.1524)
				(type default)
			)
			(layer "F.SilkS")
		)
		(fp_line
			(start 1.2954 0.5842)
			(end -1.2954 0.5842)
			(stroke
				(width 0.1524)
				(type default)
			)
			(layer "F.SilkS")
		)
		(fp_line
			(start -1.2954 -0.5842)
			(end 1.2954 -0.5842)
			(stroke
				(width 0.1524)
				(type default)
			)
			(layer "F.SilkS")
		)
		(fp_line
			(start 0 -0.5842)
			(end 0 0.5842)
			(stroke
				(width 0.1524)
				(type default)
			)
			(layer "F.SilkS")
		)
		(fp_line
			(start 1.2954 -0.5842)
			(end 1.2954 0.5842)
			(stroke
				(width 0.1524)
				(type default)
			)
			(layer "F.SilkS")
		)
		(fp_poly
			(pts
				(xy 0.8636 -0.4572) (xy 0.8636 -0.3556) (xy 1.143 -0.3556) (xy 1.143 0.3556) (xy 0.8636 0.3556)
				(xy 0.8636 0.4572) (xy -0.8636 0.4572) (xy -0.8636 0.3556) (xy -1.143 0.3556) (xy -1.143 -0.3556)
				(xy -0.8636 -0.3556) (xy -0.8636 -0.4572)
			)
			(stroke
				(width 0)
				(type default)
			)
			(fill no)
			(layer "F.CrtYd")
		)
		(fp_line
			(start -0.884936 0.504952)
			(end -0.884936 -0.504952)
			(stroke
				(width 0.1)
				(type default)
			)
			(layer "F.Fab")
		)
		(fp_line
			(start 0.884936 0.504952)
			(end -0.884936 0.504952)
			(stroke
				(width 0.1)
				(type default)
			)
			(layer "F.Fab")
		)
		(fp_line
			(start -0.884936 -0.504952)
			(end 0.884936 -0.504952)
			(stroke
				(width 0.1)
				(type default)
			)
			(layer "F.Fab")
		)
		(fp_line
			(start 0.884936 -0.504952)
			(end 0.884936 0.504952)
			(stroke
				(width 0.1)
				(type default)
			)
			(layer "F.Fab")
		)
		(pad "1" smd rect
			(at 0.7366 0)
			(size 0.7112 0.8128)
			(layers "F.Cu" "F.Mask" "F.Paste")
			(net "P12V")
		)
		(pad "2" smd rect
			(at -0.7366 0)
			(size 0.7112 0.8128)
			(layers "F.Cu" "F.Mask" "F.Paste")
			(net "GND")
		)
	)
	(footprint ""
		(layer "F.Cu")
		(at 347.639132 -21.657818 -90)
		(property "Reference" "R65"
			(at -3.3528 57.161684 90)
			(unlocked yes)
			(layer "F.SilkS")
			(effects
				(font
					(size 0.7874 0.5842)
					(thickness 0.1524)
				)
				(justify left)
			)
		)
		(property "Value" ""
			(at 0 0 270)
			(layer "F.Fab")
			(effects
				(font
					(size 1.27 1.27)
				)
			)
		)
		(duplicate_pad_numbers_are_jumpers no)
		(fp_line
			(start -0.7874 0.4064)
			(end -0.7874 -0.4064)
			(stroke
				(width 0.1524)
				(type default)
			)
			(layer "F.SilkS")
		)
		(fp_line
			(start 0.7874 0.4064)
			(end -0.7874 0.4064)
			(stroke
				(width 0.1524)
				(type default)
			)
			(layer "F.SilkS")
		)
		(fp_line
			(start -0.7874 -0.4064)
			(end 0.7874 -0.4064)
			(stroke
				(width 0.1524)
				(type default)
			)
			(layer "F.SilkS")
		)
		(fp_line
			(start 0.7874 -0.4064)
			(end 0.7874 0.4064)
			(stroke
				(width 0.1524)
				(type default)
			)
			(layer "F.SilkS")
		)
		(fp_poly
			(pts
				(xy -0.508 0.2794) (xy -0.508 0.2286) (xy -0.635 0.2286) (xy -0.635 -0.254) (xy -0.5334 -0.254)
				(xy -0.5334 -0.2794) (xy 0.5334 -0.2794) (xy 0.5334 -0.254) (xy 0.635 -0.254) (xy 0.635 0.254) (xy 0.5334 0.254)
				(xy 0.5334 0.2794)
			)
			(stroke
				(width 0)
				(type default)
			)
			(fill no)
			(layer "F.CrtYd")
		)
		(pad "1" smd rect
			(at 0.40005 0 270)
			(size 0.4572 0.508)
			(layers "F.Cu" "F.Mask" "F.Paste")
			(net "SKU_PIN_BLAD2_1")
		)
		(pad "2" smd rect
			(at -0.40005 0 270)
			(size 0.4572 0.508)
			(layers "F.Cu" "F.Mask" "F.Paste")
			(net "P3V3_BLAD2")
		)
	)
	(footprint ""
		(layer "F.Cu")
		(at 338.127848 -24.038306)
		(property "Reference" "R26"
			(at -58.3438 -4.587748 0)
			(unlocked yes)
			(layer "F.SilkS")
			(effects
				(font
					(size 0.7874 0.5842)
					(thickness 0.1524)
				)
				(justify left)
			)
		)
		(property "Value" ""
			(at 0 0 0)
			(layer "F.Fab")
			(effects
				(font
					(size 1.27 1.27)
				)
			)
		)
		(duplicate_pad_numbers_are_jumpers no)
		(fp_line
			(start -0.7874 -0.4064)
			(end 0.7874 -0.4064)
			(stroke
				(width 0.1524)
				(type default)
			)
			(layer "F.SilkS")
		)
		(fp_line
			(start -0.7874 0.4064)
			(end -0.7874 -0.4064)
			(stroke
				(width 0.1524)
				(type default)
			)
			(layer "F.SilkS")
		)
		(fp_line
			(start 0.7874 -0.4064)
			(end 0.7874 0.4064)
			(stroke
				(width 0.1524)
				(type default)
			)
			(layer "F.SilkS")
		)
		(fp_line
			(start 0.7874 0.4064)
			(end -0.7874 0.4064)
			(stroke
				(width 0.1524)
				(type default)
			)
			(layer "F.SilkS")
		)
		(fp_poly
			(pts
				(xy -0.508 0.2794) (xy -0.508 0.2286) (xy -0.635 0.2286) (xy -0.635 -0.254) (xy -0.5334 -0.254)
				(xy -0.5334 -0.2794) (xy 0.5334 -0.2794) (xy 0.5334 -0.254) (xy 0.635 -0.254) (xy 0.635 0.254) (xy 0.5334 0.254)
				(xy 0.5334 0.2794)
			)
			(stroke
				(width 0)
				(type default)
			)
			(fill no)
			(layer "F.CrtYd")
		)
		(pad "1" smd rect
			(at 0.40005 0)
			(size 0.4572 0.508)
			(layers "F.Cu" "F.Mask" "F.Paste")
			(net "P3V3_BLAD2")
		)
		(pad "2" smd rect
			(at -0.40005 0)
			(size 0.4572 0.508)
			(layers "F.Cu" "F.Mask" "F.Paste")
			(net "ENET10G_4_MOD_DEF0")
		)
	)
	(footprint ""
		(layer "F.Cu")
		(at 29.029152 -26.405332 180)
		(property "Reference" "JP3"
			(at -0.488696 2.229866 0)
			(unlocked yes)
			(layer "F.SilkS")
			(effects
				(font
					(size 0.7874 0.5842)
					(thickness 0.1524)
				)
				(justify left)
			)
		)
		(property "Value" ""
			(at 0 0 180)
			(layer "F.Fab")
			(effects
				(font
					(size 1.27 1.27)
				)
			)
		)
		(duplicate_pad_numbers_are_jumpers no)
		(fp_line
			(start 2.54 1.27)
			(end -2.54 1.27)
			(stroke
				(width 0.1524)
				(type default)
			)
			(layer "F.SilkS")
		)
		(fp_line
			(start 2.54 -1.27)
			(end 2.54 1.27)
			(stroke
				(width 0.1524)
				(type default)
			)
			(layer "F.SilkS")
		)
		(fp_line
			(start -2.54 1.27)
			(end -2.54 -1.27)
			(stroke
				(width 0.1524)
				(type default)
			)
			(layer "F.SilkS")
		)
		(fp_line
			(start -2.54 -1.27)
			(end 2.54 -1.27)
			(stroke
				(width 0.1524)
				(type default)
			)
			(layer "F.SilkS")
		)
		(fp_poly
			(pts
				(xy -2.828798 0.794004) (xy -4.176014 1.314704) (xy -3.313938 2.177034)
			)
			(stroke
				(width 0)
				(type default)
			)
			(fill yes)
			(layer "F.SilkS")
		)
		(fp_poly
			(pts
				(xy -2.1082 -0.8382) (xy -2.1082 0.8382) (xy 2.1082 0.8382) (xy 2.1082 -0.8382)
			)
			(stroke
				(width 0)
				(type default)
			)
			(fill no)
			(layer "B.CrtYd")
		)
		(fp_rect
			(start -2.54 1.27)
			(end 2.54 -1.27)
			(stroke
				(width 0)
				(type default)
			)
			(fill no)
			(layer "F.CrtYd")
		)
		(fp_line
			(start 2.54 1.27)
			(end -2.54 1.27)
			(stroke
				(width 0.1)
				(type default)
			)
			(layer "F.Fab")
		)
		(fp_line
			(start 2.54 -1.27)
			(end 2.54 1.27)
			(stroke
				(width 0.1)
				(type default)
			)
			(layer "F.Fab")
		)
		(fp_line
			(start -2.54 1.27)
			(end -2.54 -1.27)
			(stroke
				(width 0.1)
				(type default)
			)
			(layer "F.Fab")
		)
		(fp_line
			(start -2.54 -1.27)
			(end 2.54 -1.27)
			(stroke
				(width 0.1)
				(type default)
			)
			(layer "F.Fab")
		)
		(fp_text user "2"
			(at 3.372104 -0.081534 0)
			(unlocked yes)
			(layer "F.SilkS")
			(effects
				(font
					(size 0.7874 0.5842)
					(thickness 0.1524)
				)
				(justify left)
			)
		)
		(fp_text user "1"
			(at -2.673096 -0.056134 0)
			(unlocked yes)
			(layer "F.SilkS")
			(effects
				(font
					(size 0.7874 0.5842)
					(thickness 0.1524)
				)
				(justify left)
			)
		)
		(fp_text user "2"
			(at 2.356104 -0.081534 0)
			(unlocked yes)
			(layer "B.SilkS")
			(effects
				(font
					(size 0.7874 0.5842)
					(thickness 0.1524)
				)
				(justify left mirror)
			)
		)
		(fp_text user "1"
			(at -2.977896 -0.056134 0)
			(unlocked yes)
			(layer "B.SilkS")
			(effects
				(font
					(size 0.7874 0.5842)
					(thickness 0.1524)
				)
				(justify left mirror)
			)
		)
		(pad "1" thru_hole rect
			(at -1.27 0 180)
			(size 1.6764 1.6764)
			(drill 1.1684)
			(layers "*.Cu" "*.Mask")
			(remove_unused_layers no)
			(net "NODE2_EN")
			(clearance 0)
			(padstack
				(mode front_inner_back)
				(layer "Inner"
					(shape circle)
					(size 1.6764 1.6764)
					(clearance 0)
				)
				(layer "B.Cu"
					(shape rect)
					(size 1.6764 1.6764)
					(clearance 0)
				)
			)
		)
		(pad "2" thru_hole circle
			(at 1.27 0 180)
			(size 1.6764 1.6764)
			(drill 1.1684)
			(layers "*.Cu" "*.Mask")
			(remove_unused_layers no)
			(net "N39386877")
			(clearance 0)
		)
	)
	(footprint ""
		(layer "F.Cu")
		(at 313.07024 -27.523694)
		(property "Reference" "R28"
			(at -6.604 -1.285748 0)
			(unlocked yes)
			(layer "F.SilkS")
			(effects
				(font
					(size 0.7874 0.5842)
					(thickness 0.1524)
				)
				(justify left)
			)
		)
		(property "Value" ""
			(at 0 0 0)
			(layer "F.Fab")
			(effects
				(font
					(size 1.27 1.27)
				)
			)
		)
		(duplicate_pad_numbers_are_jumpers no)
		(fp_line
			(start -0.7874 -0.4064)
			(end 0.7874 -0.4064)
			(stroke
				(width 0.1524)
				(type default)
			)
			(layer "F.SilkS")
		)
		(fp_line
			(start -0.7874 0.4064)
			(end -0.7874 -0.4064)
			(stroke
				(width 0.1524)
				(type default)
			)
			(layer "F.SilkS")
		)
		(fp_line
			(start 0.7874 -0.4064)
			(end 0.7874 0.4064)
			(stroke
				(width 0.1524)
				(type default)
			)
			(layer "F.SilkS")
		)
		(fp_line
			(start 0.7874 0.4064)
			(end -0.7874 0.4064)
			(stroke
				(width 0.1524)
				(type default)
			)
			(layer "F.SilkS")
		)
		(fp_poly
			(pts
				(xy -0.508 0.2794) (xy -0.508 0.2286) (xy -0.635 0.2286) (xy -0.635 -0.254) (xy -0.5334 -0.254)
				(xy -0.5334 -0.2794) (xy 0.5334 -0.2794) (xy 0.5334 -0.254) (xy 0.635 -0.254) (xy 0.635 0.254) (xy 0.5334 0.254)
				(xy 0.5334 0.2794)
			)
			(stroke
				(width 0)
				(type default)
			)
			(fill no)
			(layer "F.CrtYd")
		)
		(pad "1" smd rect
			(at 0.40005 0)
			(size 0.4572 0.508)
			(layers "F.Cu" "F.Mask" "F.Paste")
			(net "P3V3_BLAD2")
		)
		(pad "2" smd rect
			(at -0.40005 0)
			(size 0.4572 0.508)
			(layers "F.Cu" "F.Mask" "F.Paste")
			(net "ENET10G_4_RS0")
		)
	)
	(footprint ""
		(layer "F.Cu")
		(at 306.324 -33.655 90)
		(property "Reference" "L8"
			(at -0.9906 -2.79273 90)
			(unlocked yes)
			(layer "F.SilkS")
			(effects
				(font
					(size 0.7874 0.5842)
					(thickness 0.1524)
				)
				(justify left)
			)
		)
		(property "Value" ""
			(at 0 0 90)
			(layer "F.Fab")
			(effects
				(font
					(size 1.27 1.27)
				)
			)
		)
		(duplicate_pad_numbers_are_jumpers no)
		(fp_line
			(start -1.905 -0.8636)
			(end 1.905 -0.8636)
			(stroke
				(width 0.1524)
				(type default)
			)
			(layer "F.SilkS")
		)
		(fp_line
			(start 1.905 0.8382)
			(end 1.905 -0.8382)
			(stroke
				(width 0.1524)
				(type default)
			)
			(layer "F.SilkS")
		)
		(fp_line
			(start 0.127 0.8382)
			(end 0.127 -0.8382)
			(stroke
				(width 0.1524)
				(type default)
			)
			(layer "F.SilkS")
		)
		(fp_line
			(start -0.127 0.8382)
			(end -0.127 -0.8382)
			(stroke
				(width 0.1524)
				(type default)
			)
			(layer "F.SilkS")
		)
		(fp_line
			(start -1.905 0.8382)
			(end -1.905 -0.8382)
			(stroke
				(width 0.1524)
				(type default)
			)
			(layer "F.SilkS")
		)
		(fp_line
			(start 1.905 0.8636)
			(end -1.905 0.8636)
			(stroke
				(width 0.1524)
				(type default)
			)
			(layer "F.SilkS")
		)
		(fp_rect
			(start -1.524 0.7112)
			(end 1.524 -0.7366)
			(stroke
				(width 0)
				(type default)
			)
			(fill no)
			(layer "F.CrtYd")
		)
		(pad "1" smd rect
			(at 0.94996 0 90)
			(size 1.1176 1.3716)
			(layers "F.Cu" "F.Mask" "F.Paste")
			(net "P3V3_10G_4_VCCR_L")
		)
		(pad "2" smd rect
			(at -0.94996 0 90)
			(size 1.1176 1.3716)
			(layers "F.Cu" "F.Mask" "F.Paste")
			(net "P3V3_10G_4_VCCR")
		)
	)
	(footprint ""
		(layer "F.Cu")
		(at 4.499864 -28.999942 180)
		(property "Reference" "H5"
			(at -0.245872 10.900664 0)
			(unlocked yes)
			(layer "F.SilkS")
			(effects
				(font
					(size 0.7874 0.5842)
					(thickness 0.1524)
				)
				(justify left)
			)
		)
		(property "Value" ""
			(at 0 0 180)
			(layer "F.Fab")
			(effects
				(font
					(size 1.27 1.27)
				)
			)
		)
		(duplicate_pad_numbers_are_jumpers no)
		(fp_poly
			(pts
				(arc
					(start 3.999992 5.999988)
					(mid 0 9.99998)
					(end -3.999992 5.999988)
				)
				(arc
					(start -3.999992 0)
					(mid 0 -3.999992)
					(end 3.999992 0)
				)
			)
			(stroke
				(width 0)
				(type default)
			)
			(fill no)
			(layer "B.CrtYd")
		)
		(fp_poly
			(pts
				(arc
					(start 3.999992 5.999988)
					(mid 0 9.99998)
					(end -3.999992 5.999988)
				)
				(arc
					(start -3.999992 0)
					(mid 0 -3.999992)
					(end 3.999992 0)
				)
			)
			(stroke
				(width 0)
				(type default)
			)
			(fill no)
			(layer "F.CrtYd")
		)
		(pad "" np_thru_hole circle
			(at 0 0 180)
			(size 3.5052 3.5052)
			(drill 3.5052)
			(layers "*.Cu" "*.Mask")
			(clearance 0.381)
			(thermal_gap 0.381)
		)
		(zone
			(layers "F.Cu" "B.Cu" "In1.Cu" "In2.Cu" "In3.Cu" "In4.Cu" "In5.Cu" "In6.Cu")
			(hatch none 0.5)
			(connect_pads
				(clearance 0)
			)
			(min_thickness 0.25)
			(keepout
				(tracks not_allowed)
				(vias allowed)
				(pads allowed)
				(copperpour not_allowed)
				(footprints allowed)
			)
			(placement
				(enabled no)
				(sheetname "")
			)
			(fill
				(thermal_gap 0.5)
				(thermal_bridge_width 0.5)
				(island_removal_mode 0)
			)
			(polygon
				(pts
					(arc
						(start 2.088134 -32.452564)
						(mid 4.499864 -38.507852)
						(end 6.911594 -32.452564)
					)
					(arc
						(start 6.911594 -32.452564)
						(mid 6.797965 -32.289703)
						(end 6.757924 -32.095186)
					)
					(arc
						(start 6.757924 -28.999942)
						(mid 4.499864 -26.741882)
						(end 2.241804 -28.999942)
					)
					(arc
						(start 2.241804 -32.095186)
						(mid 2.201818 -32.289726)
						(end 2.088134 -32.452564)
					)
				)
			)
		)
	)
	(footprint ""
		(layer "F.Cu")
		(at 395.889988 -2.100072 180)
		(property "Reference" "J8"
			(at -4.872736 -0.63246 90)
			(unlocked yes)
			(layer "F.SilkS")
			(effects
				(font
					(size 0.7874 0.5842)
					(thickness 0.1524)
				)
				(justify left)
			)
		)
		(property "Value" ""
			(at 0 0 180)
			(layer "F.Fab")
			(effects
				(font
					(size 1.27 1.27)
				)
			)
		)
		(duplicate_pad_numbers_are_jumpers no)
		(fp_line
			(start 13.999972 18.375122)
			(end 13.999972 -14.675104)
			(stroke
				(width 0.1524)
				(type default)
			)
			(layer "F.SilkS")
		)
		(fp_line
			(start 13.999972 -14.675104)
			(end -3.999992 -14.675104)
			(stroke
				(width 0.1524)
				(type default)
			)
			(layer "F.SilkS")
		)
		(fp_line
			(start 10.999978 15.375128)
			(end 10.999978 -11.67511)
			(stroke
				(width 0.1524)
				(type default)
			)
			(layer "F.SilkS")
		)
		(fp_line
			(start 10.999978 -11.67511)
			(end -0.999998 -11.67511)
			(stroke
				(width 0.1524)
				(type default)
			)
			(layer "F.SilkS")
		)
		(fp_line
			(start -0.999998 15.375128)
			(end 10.999978 15.375128)
			(stroke
				(width 0.1524)
				(type default)
			)
			(layer "F.SilkS")
		)
		(fp_line
			(start -0.999998 -11.67511)
			(end -0.999998 15.375128)
			(stroke
				(width 0.1524)
				(type default)
			)
			(layer "F.SilkS")
		)
		(fp_line
			(start -3.999992 18.375122)
			(end 13.999972 18.375122)
			(stroke
				(width 0.1524)
				(type default)
			)
			(layer "F.SilkS")
		)
		(fp_line
			(start -3.999992 -14.675104)
			(end -3.999992 18.375122)
			(stroke
				(width 0.1524)
				(type default)
			)
			(layer "F.SilkS")
		)
		(fp_poly
			(pts
				(xy -2.261108 0.508) (xy -2.261108 -0.508) (xy -1.245108 0)
			)
			(stroke
				(width 0)
				(type default)
			)
			(fill yes)
			(layer "F.SilkS")
		)
		(fp_line
			(start 13.999972 18.375122)
			(end 13.999972 -14.675104)
			(stroke
				(width 0.1524)
				(type default)
			)
			(layer "B.SilkS")
		)
		(fp_line
			(start 13.999972 -14.675104)
			(end -3.999992 -14.675104)
			(stroke
				(width 0.1524)
				(type default)
			)
			(layer "B.SilkS")
		)
		(fp_line
			(start -3.999992 18.375122)
			(end 13.999972 18.375122)
			(stroke
				(width 0.1524)
				(type default)
			)
			(layer "B.SilkS")
		)
		(fp_line
			(start -3.999992 -14.675104)
			(end -3.999992 18.375122)
			(stroke
				(width 0.1524)
				(type default)
			)
			(layer "B.SilkS")
		)
		(fp_poly
			(pts
				(xy 9.49198 11.707876) (xy 9.49198 11.608054) (xy 10.50798 11.608054) (xy 10.50798 -0.608076) (xy 0.508 -0.608076)
				(xy 0.508 -0.508) (xy -0.508 -0.508) (xy -0.508 11.707876)
			)
			(stroke
				(width 0)
				(type default)
			)
			(fill no)
			(layer "B.CrtYd")
		)
		(fp_poly
			(pts
				(xy -0.999998 15.375128) (xy 10.999978 15.375128) (xy 10.999978 -11.67511) (xy -0.999998 -11.67511)
			)
			(stroke
				(width 0)
				(type default)
			)
			(fill no)
			(layer "F.CrtYd")
		)
		(fp_line
			(start 13.999972 18.375122)
			(end 13.999972 -14.675104)
			(stroke
				(width 0.1)
				(type default)
			)
			(layer "B.Fab")
		)
		(fp_line
			(start 13.999972 -14.675104)
			(end -3.999992 -14.675104)
			(stroke
				(width 0.1)
				(type default)
			)
			(layer "B.Fab")
		)
		(fp_line
			(start -3.999992 18.375122)
			(end 13.999972 18.375122)
			(stroke
				(width 0.1)
				(type default)
			)
			(layer "B.Fab")
		)
		(fp_line
			(start -3.999992 -14.675104)
			(end -3.999992 18.375122)
			(stroke
				(width 0.1)
				(type default)
			)
			(layer "B.Fab")
		)
		(fp_line
			(start 10.999978 15.375128)
			(end 10.999978 -11.67511)
			(stroke
				(width 0.1)
				(type default)
			)
			(layer "F.Fab")
		)
		(fp_line
			(start 10.999978 -11.67511)
			(end -0.999998 -11.67511)
			(stroke
				(width 0.1)
				(type default)
			)
			(layer "F.Fab")
		)
		(fp_line
			(start -0.999998 15.375128)
			(end 10.999978 15.375128)
			(stroke
				(width 0.1)
				(type default)
			)
			(layer "F.Fab")
		)
		(fp_line
			(start -0.999998 -11.67511)
			(end -0.999998 15.375128)
			(stroke
				(width 0.1)
				(type default)
			)
			(layer "F.Fab")
		)
		(fp_poly
			(pts
				(xy -2.261108 0.508) (xy -2.261108 -0.508) (xy -1.245108 0)
			)
			(stroke
				(width 0)
				(type default)
			)
			(fill yes)
			(layer "F.Fab")
		)
		(fp_text user "PRESS-FIT"
			(at 12.449302 -0.20193 90)
			(unlocked yes)
			(layer "F.SilkS")
			(effects
				(font
					(size 1.6002 1.1938)
					(thickness 0.1524)
				)
				(justify left)
			)
		)
		(fp_text user "6"
			(at 10.102596 16.006318 0)
			(unlocked yes)
			(layer "F.SilkS")
			(effects
				(font
					(size 0.7874 0.5842)
					(thickness 0.1524)
				)
			)
		)
		(fp_text user "5"
			(at 8.019796 15.980918 0)
			(unlocked yes)
			(layer "F.SilkS")
			(effects
				(font
					(size 0.7874 0.5842)
					(thickness 0.1524)
				)
			)
		)
		(fp_text user "4"
			(at 5.657596 16.057118 0)
			(unlocked yes)
			(layer "F.SilkS")
			(effects
				(font
					(size 0.7874 0.5842)
					(thickness 0.1524)
				)
			)
		)
		(fp_text user "3"
			(at 3.854196 16.082518 0)
			(unlocked yes)
			(layer "F.SilkS")
			(effects
				(font
					(size 0.7874 0.5842)
					(thickness 0.1524)
				)
			)
		)
		(fp_text user "2"
			(at 1.949196 16.133318 0)
			(unlocked yes)
			(layer "F.SilkS")
			(effects
				(font
					(size 0.7874 0.5842)
					(thickness 0.1524)
				)
			)
		)
		(fp_text user "1"
			(at 0.018796 16.184118 0)
			(unlocked yes)
			(layer "F.SilkS")
			(effects
				(font
					(size 0.7874 0.5842)
					(thickness 0.1524)
				)
			)
		)
		(fp_text user "A"
			(at -1.657604 -0.780796 0)
			(unlocked yes)
			(layer "F.SilkS")
			(effects
				(font
					(size 0.7874 0.5842)
					(thickness 0.1524)
				)
			)
		)
		(fp_text user "H"
			(at -1.667002 9.712706 0)
			(unlocked yes)
			(layer "F.SilkS")
			(effects
				(font
					(size 0.7874 0.5842)
					(thickness 0.1524)
				)
			)
		)
		(fp_text user "G"
			(at -1.667002 8.3947 0)
			(unlocked yes)
			(layer "F.SilkS")
			(effects
				(font
					(size 0.7874 0.5842)
					(thickness 0.1524)
				)
			)
		)
		(fp_text user "F"
			(at -1.692402 6.924548 0)
			(unlocked yes)
			(layer "F.SilkS")
			(effects
				(font
					(size 0.7874 0.5842)
					(thickness 0.1524)
				)
			)
		)
		(fp_text user "I"
			(at -1.717802 11.259058 0)
			(unlocked yes)
			(layer "F.SilkS")
			(effects
				(font
					(size 0.7874 0.5842)
					(thickness 0.1524)
				)
			)
		)
		(fp_text user "E"
			(at -1.717802 5.530596 0)
			(unlocked yes)
			(layer "F.SilkS")
			(effects
				(font
					(size 0.7874 0.5842)
					(thickness 0.1524)
				)
			)
		)
		(fp_text user "C"
			(at -1.717802 2.768092 0)
			(unlocked yes)
			(layer "F.SilkS")
			(effects
				(font
					(size 0.7874 0.5842)
					(thickness 0.1524)
				)
			)
		)
		(fp_text user "B"
			(at -1.768602 1.32334 0)
			(unlocked yes)
			(layer "F.SilkS")
			(effects
				(font
					(size 0.7874 0.5842)
					(thickness 0.1524)
				)
			)
		)
		(fp_text user "D"
			(at -1.844802 4.212844 0)
			(unlocked yes)
			(layer "F.SilkS")
			(effects
				(font
					(size 0.7874 0.5842)
					(thickness 0.1524)
				)
			)
		)
		(fp_text user "PRESS-FIT"
			(at 12.75969 -0.0381 270)
			(unlocked yes)
			(layer "B.SilkS")
			(effects
				(font
					(size 1.6002 1.1938)
					(thickness 0.1524)
				)
				(justify left mirror)
			)
		)
		(fp_text user "6"
			(at 10.000996 -1.237996 0)
			(unlocked yes)
			(layer "B.SilkS")
			(effects
				(font
					(size 0.7874 0.5842)
					(thickness 0.1524)
				)
				(justify mirror)
			)
		)
		(fp_text user "5"
			(at 8.019796 -1.263396 0)
			(unlocked yes)
			(layer "B.SilkS")
			(effects
				(font
					(size 0.7874 0.5842)
					(thickness 0.1524)
				)
				(justify mirror)
			)
		)
		(fp_text user "4"
			(at 5.936996 -1.263396 0)
			(unlocked yes)
			(layer "B.SilkS")
			(effects
				(font
					(size 0.7874 0.5842)
					(thickness 0.1524)
				)
				(justify mirror)
			)
		)
		(fp_text user "3"
			(at 3.523996 -1.288796 0)
			(unlocked yes)
			(layer "B.SilkS")
			(effects
				(font
					(size 0.7874 0.5842)
					(thickness 0.1524)
				)
				(justify mirror)
			)
		)
		(fp_text user "2"
			(at 2.025396 -1.237996 0)
			(unlocked yes)
			(layer "B.SilkS")
			(effects
				(font
					(size 0.7874 0.5842)
					(thickness 0.1524)
				)
				(justify mirror)
			)
		)
		(fp_text user "1"
			(at -0.057404 -1.314196 0)
			(unlocked yes)
			(layer "B.SilkS")
			(effects
				(font
					(size 0.7874 0.5842)
					(thickness 0.1524)
				)
				(justify mirror)
			)
		)
		(fp_text user "F"
			(at -1.463802 6.975348 0)
			(unlocked yes)
			(layer "B.SilkS")
			(effects
				(font
					(size 0.7874 0.5842)
					(thickness 0.1524)
				)
				(justify mirror)
			)
		)
		(fp_text user "E"
			(at -1.463802 5.632196 0)
			(unlocked yes)
			(layer "B.SilkS")
			(effects
				(font
					(size 0.7874 0.5842)
					(thickness 0.1524)
				)
				(justify mirror)
			)
		)
		(fp_text user "D"
			(at -1.463802 4.187444 0)
			(unlocked yes)
			(layer "B.SilkS")
			(effects
				(font
					(size 0.7874 0.5842)
					(thickness 0.1524)
				)
				(justify mirror)
			)
		)
		(fp_text user "B"
			(at -1.463802 1.37414 0)
			(unlocked yes)
			(layer "B.SilkS")
			(effects
				(font
					(size 0.7874 0.5842)
					(thickness 0.1524)
				)
				(justify mirror)
			)
		)
		(fp_text user "H"
			(at -1.489202 9.687306 0)
			(unlocked yes)
			(layer "B.SilkS")
			(effects
				(font
					(size 0.7874 0.5842)
					(thickness 0.1524)
				)
				(justify mirror)
			)
		)
		(fp_text user "C"
			(at -1.489202 2.869692 0)
			(unlocked yes)
			(layer "B.SilkS")
			(effects
				(font
					(size 0.7874 0.5842)
					(thickness 0.1524)
				)
				(justify mirror)
			)
		)
		(fp_text user "A"
			(at -1.505204 -0.069596 0)
			(unlocked yes)
			(layer "B.SilkS")
			(effects
				(font
					(size 0.7874 0.5842)
					(thickness 0.1524)
				)
				(justify mirror)
			)
		)
		(fp_text user "I"
			(at -1.540002 11.055858 0)
			(unlocked yes)
			(layer "B.SilkS")
			(effects
				(font
					(size 0.7874 0.5842)
					(thickness 0.1524)
				)
				(justify mirror)
			)
		)
		(fp_text user "G"
			(at -1.540002 8.3439 0)
			(unlocked yes)
			(layer "B.SilkS")
			(effects
				(font
					(size 0.7874 0.5842)
					(thickness 0.1524)
				)
				(justify mirror)
			)
		)
		(fp_text user "PRESS-FIT"
			(at 12.75969 -0.0381 270)
			(unlocked yes)
			(layer "B.Fab")
			(effects
				(font
					(size 1.6002 1.1938)
					(thickness 0.000001)
				)
				(justify left mirror)
			)
		)
		(fp_text user "6"
			(at 9.99998 -1.666748 180)
			(unlocked yes)
			(layer "B.Fab")
			(effects
				(font
					(size 0.7874 0.5842)
					(thickness 0.000001)
				)
				(justify mirror)
			)
		)
		(fp_text user "5"
			(at 7.96798 -1.615948 180)
			(unlocked yes)
			(layer "B.Fab")
			(effects
				(font
					(size 0.7874 0.5842)
					(thickness 0.000001)
				)
				(justify mirror)
			)
		)
		(fp_text user "4"
			(at 5.88518 -1.615948 180)
			(unlocked yes)
			(layer "B.Fab")
			(effects
				(font
					(size 0.7874 0.5842)
					(thickness 0.000001)
				)
				(justify mirror)
			)
		)
		(fp_text user "3"
			(at 3.90398 -1.615948 180)
			(unlocked yes)
			(layer "B.Fab")
			(effects
				(font
					(size 0.7874 0.5842)
					(thickness 0.000001)
				)
				(justify mirror)
			)
		)
		(fp_text user "2"
			(at 1.97358 -1.615948 180)
			(unlocked yes)
			(layer "B.Fab")
			(effects
				(font
					(size 0.7874 0.5842)
					(thickness 0.000001)
				)
				(justify mirror)
			)
		)
		(fp_text user "1"
			(at -0.00762 -1.615948 180)
			(unlocked yes)
			(layer "B.Fab")
			(effects
				(font
					(size 0.7874 0.5842)
					(thickness 0.000001)
				)
				(justify mirror)
			)
		)
		(fp_text user "A"
			(at -1.50622 -0.041148 180)
			(unlocked yes)
			(layer "B.Fab")
			(effects
				(font
					(size 0.7874 0.5842)
					(thickness 0.000001)
				)
				(justify mirror)
			)
		)
		(fp_text user "I"
			(at -1.522222 11.210798 180)
			(unlocked yes)
			(layer "B.Fab")
			(effects
				(font
					(size 0.7874 0.5842)
					(thickness 0.000001)
				)
				(justify mirror)
			)
		)
		(fp_text user "H"
			(at -1.522222 9.81075 180)
			(unlocked yes)
			(layer "B.Fab")
			(effects
				(font
					(size 0.7874 0.5842)
					(thickness 0.000001)
				)
				(justify mirror)
			)
		)
		(fp_text user "G"
			(at -1.522222 8.410956 180)
			(unlocked yes)
			(layer "B.Fab")
			(effects
				(font
					(size 0.7874 0.5842)
					(thickness 0.000001)
				)
				(justify mirror)
			)
		)
		(fp_text user "F"
			(at -1.522222 7.010908 180)
			(unlocked yes)
			(layer "B.Fab")
			(effects
				(font
					(size 0.7874 0.5842)
					(thickness 0.000001)
				)
				(justify mirror)
			)
		)
		(fp_text user "E"
			(at -1.522222 5.61086 180)
			(unlocked yes)
			(layer "B.Fab")
			(effects
				(font
					(size 0.7874 0.5842)
					(thickness 0.000001)
				)
				(justify mirror)
			)
		)
		(fp_text user "D"
			(at -1.522222 4.210812 180)
			(unlocked yes)
			(layer "B.Fab")
			(effects
				(font
					(size 0.7874 0.5842)
					(thickness 0.000001)
				)
				(justify mirror)
			)
		)
		(fp_text user "C"
			(at -1.522222 2.810764 180)
			(unlocked yes)
			(layer "B.Fab")
			(effects
				(font
					(size 0.7874 0.5842)
					(thickness 0.000001)
				)
				(justify mirror)
			)
		)
		(fp_text user "B"
			(at -1.522222 1.410716 180)
			(unlocked yes)
			(layer "B.Fab")
			(effects
				(font
					(size 0.7874 0.5842)
					(thickness 0.000001)
				)
				(justify mirror)
			)
		)
		(fp_text user "PRESS-FIT"
			(at 12.758674 14.569186 270)
			(unlocked yes)
			(layer "F.Fab")
			(effects
				(font
					(size 1.6002 1.1938)
					(thickness 0.000001)
				)
				(justify left)
			)
		)
		(fp_text user "6"
			(at 10.12698 16.013938 180)
			(unlocked yes)
			(layer "F.Fab")
			(effects
				(font
					(size 0.7874 0.5842)
					(thickness 0.000001)
				)
			)
		)
		(fp_text user "5"
			(at 8.09498 16.064738 180)
			(unlocked yes)
			(layer "F.Fab")
			(effects
				(font
					(size 0.7874 0.5842)
					(thickness 0.000001)
				)
			)
		)
		(fp_text user "4"
			(at 6.01218 16.064738 180)
			(unlocked yes)
			(layer "F.Fab")
			(effects
				(font
					(size 0.7874 0.5842)
					(thickness 0.000001)
				)
			)
		)
		(fp_text user "3"
			(at 4.03098 16.064738 180)
			(unlocked yes)
			(layer "F.Fab")
			(effects
				(font
					(size 0.7874 0.5842)
					(thickness 0.000001)
				)
			)
		)
		(fp_text user "2"
			(at 2.10058 16.064738 180)
			(unlocked yes)
			(layer "F.Fab")
			(effects
				(font
					(size 0.7874 0.5842)
					(thickness 0.000001)
				)
			)
		)
		(fp_text user "1"
			(at 0.11938 16.064738 180)
			(unlocked yes)
			(layer "F.Fab")
			(effects
				(font
					(size 0.7874 0.5842)
					(thickness 0.000001)
				)
			)
		)
		(fp_text user "I"
			(at -1.649222 11.210798 180)
			(unlocked yes)
			(layer "F.Fab")
			(effects
				(font
					(size 0.7874 0.5842)
					(thickness 0.000001)
				)
			)
		)
		(fp_text user "H"
			(at -1.649222 9.81075 180)
			(unlocked yes)
			(layer "F.Fab")
			(effects
				(font
					(size 0.7874 0.5842)
					(thickness 0.000001)
				)
			)
		)
		(fp_text user "G"
			(at -1.649222 8.410956 180)
			(unlocked yes)
			(layer "F.Fab")
			(effects
				(font
					(size 0.7874 0.5842)
					(thickness 0.000001)
				)
			)
		)
		(fp_text user "F"
			(at -1.649222 7.010908 180)
			(unlocked yes)
			(layer "F.Fab")
			(effects
				(font
					(size 0.7874 0.5842)
					(thickness 0.000001)
				)
			)
		)
		(fp_text user "E"
			(at -1.649222 5.61086 180)
			(unlocked yes)
			(layer "F.Fab")
			(effects
				(font
					(size 0.7874 0.5842)
					(thickness 0.000001)
				)
			)
		)
		(fp_text user "D"
			(at -1.649222 4.210812 180)
			(unlocked yes)
			(layer "F.Fab")
			(effects
				(font
					(size 0.7874 0.5842)
					(thickness 0.000001)
				)
			)
		)
		(fp_text user "C"
			(at -1.649222 2.810764 180)
			(unlocked yes)
			(layer "F.Fab")
			(effects
				(font
					(size 0.7874 0.5842)
					(thickness 0.000001)
				)
			)
		)
		(fp_text user "B"
			(at -1.649222 1.410716 180)
			(unlocked yes)
			(layer "F.Fab")
			(effects
				(font
					(size 0.7874 0.5842)
					(thickness 0.000001)
				)
			)
		)
		(fp_text user "A"
			(at -1.68402 -0.803148 180)
			(unlocked yes)
			(layer "F.Fab")
			(effects
				(font
					(size 0.7874 0.5842)
					(thickness 0.000001)
				)
			)
		)
		(pad "A1" thru_hole rect
			(at 0 0)
			(size 0.9144 0.9144)
			(drill 0.508)
			(layers "*.Cu" "*.Mask")
			(remove_unused_layers no)
			(net "SAS_BLAD2_TX1_P")
			(clearance 0.0508)
			(thermal_gap 0.0508)
			(padstack
				(mode front_inner_back)
				(layer "Inner"
					(shape circle)
					(size 0.9144 0.9144)
					(clearance 0.0508)
				)
				(layer "B.Cu"
					(shape rect)
					(size 0.9144 0.9144)
					(clearance 0.0508)
				)
			)
		)
		(pad "A2" thru_hole circle
			(at 1.999996 -0.100076)
			(size 0.9144 0.9144)
			(drill 0.508)
			(layers "*.Cu" "*.Mask")
			(remove_unused_layers no)
			(net "GND")
			(clearance 0.0508)
			(thermal_gap 0.0508)
		)
		(pad "A3" thru_hole circle
			(at 3.999992 0)
			(size 0.9144 0.9144)
			(drill 0.508)
			(layers "*.Cu" "*.Mask")
			(remove_unused_layers no)
			(net "AIRMAX_RSVD7")
			(clearance 0.0508)
			(thermal_gap 0.0508)
		)
		(pad "A4" thru_hole circle
			(at 5.999988 -0.100076)
			(size 0.9144 0.9144)
			(drill 0.508)
			(layers "*.Cu" "*.Mask")
			(remove_unused_layers no)
			(net "GND")
			(clearance 0.0508)
			(thermal_gap 0.0508)
		)
		(pad "A5" thru_hole circle
			(at 7.999984 0)
			(size 0.9144 0.9144)
			(drill 0.508)
			(layers "*.Cu" "*.Mask")
			(remove_unused_layers no)
			(net "SAS_BLAD2_TX6_P")
			(clearance 0.0508)
			(thermal_gap 0.0508)
		)
		(pad "A6" thru_hole circle
			(at 9.99998 -0.100076)
			(size 0.9144 0.9144)
			(drill 0.508)
			(layers "*.Cu" "*.Mask")
			(remove_unused_layers no)
			(net "GND")
			(clearance 0.0508)
			(thermal_gap 0.0508)
		)
		(pad "B1" thru_hole circle
			(at 0 1.400048)
			(size 0.9144 0.9144)
			(drill 0.508)
			(layers "*.Cu" "*.Mask")
			(remove_unused_layers no)
			(net "SAS_BLAD2_TX1_N")
			(clearance 0.0508)
			(thermal_gap 0.0508)
		)
		(pad "B2" thru_hole circle
			(at 1.999996 1.299972)
			(size 0.9144 0.9144)
			(drill 0.508)
			(layers "*.Cu" "*.Mask")
			(remove_unused_layers no)
			(net "SAS_BLAD2_RX3_P")
			(clearance 0.0508)
			(thermal_gap 0.0508)
		)
		(pad "B3" thru_hole circle
			(at 3.999992 1.400048)
			(size 0.9144 0.9144)
			(drill 0.508)
			(layers "*.Cu" "*.Mask")
			(remove_unused_layers no)
			(net "AIRMAX_RSVD8")
			(clearance 0.0508)
			(thermal_gap 0.0508)
		)
		(pad "B4" thru_hole circle
			(at 5.999988 1.299972)
			(size 0.9144 0.9144)
			(drill 0.508)
			(layers "*.Cu" "*.Mask")
			(remove_unused_layers no)
			(net "AIRMAX_RSVD5")
			(clearance 0.0508)
			(thermal_gap 0.0508)
		)
		(pad "B5" thru_hole circle
			(at 7.999984 1.400048)
			(size 0.9144 0.9144)
			(drill 0.508)
			(layers "*.Cu" "*.Mask")
			(remove_unused_layers no)
			(net "SAS_BLAD2_TX6_N")
			(clearance 0.0508)
			(thermal_gap 0.0508)
		)
		(pad "B6" thru_hole circle
			(at 9.99998 1.299972)
			(size 0.9144 0.9144)
			(drill 0.508)
			(layers "*.Cu" "*.Mask")
			(remove_unused_layers no)
			(net "SAS_BLAD2_RX8_P")
			(clearance 0.0508)
			(thermal_gap 0.0508)
		)
		(pad "C1" thru_hole circle
			(at 0 2.800096)
			(size 0.9144 0.9144)
			(drill 0.508)
			(layers "*.Cu" "*.Mask")
			(remove_unused_layers no)
			(net "GND")
			(clearance 0.0508)
			(thermal_gap 0.0508)
		)
		(pad "C2" thru_hole circle
			(at 1.999996 2.70002)
			(size 0.9144 0.9144)
			(drill 0.508)
			(layers "*.Cu" "*.Mask")
			(remove_unused_layers no)
			(net "SAS_BLAD2_RX3_N")
			(clearance 0.0508)
			(thermal_gap 0.0508)
		)
		(pad "C3" thru_hole circle
			(at 3.999992 2.800096)
			(size 0.9144 0.9144)
			(drill 0.508)
			(layers "*.Cu" "*.Mask")
			(remove_unused_layers no)
			(net "GND")
			(clearance 0.0508)
			(thermal_gap 0.0508)
		)
		(pad "C4" thru_hole circle
			(at 5.999988 2.70002)
			(size 0.9144 0.9144)
			(drill 0.508)
			(layers "*.Cu" "*.Mask")
			(remove_unused_layers no)
			(net "AIRMAX_RSVD6")
			(clearance 0.0508)
			(thermal_gap 0.0508)
		)
		(pad "C5" thru_hole circle
			(at 7.999984 2.800096)
			(size 0.9144 0.9144)
			(drill 0.508)
			(layers "*.Cu" "*.Mask")
			(remove_unused_layers no)
			(net "GND")
			(clearance 0.0508)
			(thermal_gap 0.0508)
		)
		(pad "C6" thru_hole circle
			(at 9.99998 2.70002)
			(size 0.9144 0.9144)
			(drill 0.508)
			(layers "*.Cu" "*.Mask")
			(remove_unused_layers no)
			(net "SAS_BLAD2_RX8_N")
			(clearance 0.0508)
			(thermal_gap 0.0508)
		)
		(pad "D1" thru_hole circle
			(at 0 4.19989)
			(size 0.9144 0.9144)
			(drill 0.508)
			(layers "*.Cu" "*.Mask")
			(remove_unused_layers no)
			(net "SAS_BLAD2_RX1_P")
			(clearance 0.0508)
			(thermal_gap 0.0508)
		)
		(pad "D2" thru_hole circle
			(at 1.999996 4.100068)
			(size 0.9144 0.9144)
			(drill 0.508)
			(layers "*.Cu" "*.Mask")
			(remove_unused_layers no)
			(net "GND")
			(clearance 0.0508)
			(thermal_gap 0.0508)
		)
		(pad "D3" thru_hole circle
			(at 3.999992 4.19989)
			(size 0.9144 0.9144)
			(drill 0.508)
			(layers "*.Cu" "*.Mask")
			(remove_unused_layers no)
			(net "SAS_BLAD2_RX4_P")
			(clearance 0.0508)
			(thermal_gap 0.0508)
		)
		(pad "D4" thru_hole circle
			(at 5.999988 4.100068)
			(size 0.9144 0.9144)
			(drill 0.508)
			(layers "*.Cu" "*.Mask")
			(remove_unused_layers no)
			(net "GND")
			(clearance 0.0508)
			(thermal_gap 0.0508)
		)
		(pad "D5" thru_hole circle
			(at 7.999984 4.19989)
			(size 0.9144 0.9144)
			(drill 0.508)
			(layers "*.Cu" "*.Mask")
			(remove_unused_layers no)
			(net "SAS_BLAD2_RX6_P")
			(clearance 0.0508)
			(thermal_gap 0.0508)
		)
		(pad "D6" thru_hole circle
			(at 9.99998 4.100068)
			(size 0.9144 0.9144)
			(drill 0.508)
			(layers "*.Cu" "*.Mask")
			(remove_unused_layers no)
			(net "GND")
			(clearance 0.0508)
			(thermal_gap 0.0508)
		)
		(pad "E1" thru_hole circle
			(at 0 5.599938)
			(size 0.9144 0.9144)
			(drill 0.508)
			(layers "*.Cu" "*.Mask")
			(remove_unused_layers no)
			(net "SAS_BLAD2_RX1_N")
			(clearance 0.0508)
			(thermal_gap 0.0508)
		)
		(pad "E2" thru_hole circle
			(at 1.999996 5.500116)
			(size 0.9144 0.9144)
			(drill 0.508)
			(layers "*.Cu" "*.Mask")
			(remove_unused_layers no)
			(net "SAS_BLAD2_TX3_P")
			(clearance 0.0508)
			(thermal_gap 0.0508)
		)
		(pad "E3" thru_hole circle
			(at 3.999992 5.599938)
			(size 0.9144 0.9144)
			(drill 0.508)
			(layers "*.Cu" "*.Mask")
			(remove_unused_layers no)
			(net "SAS_BLAD2_RX4_N")
			(clearance 0.0508)
			(thermal_gap 0.0508)
		)
		(pad "E4" thru_hole circle
			(at 5.999988 5.500116)
			(size 0.9144 0.9144)
			(drill 0.508)
			(layers "*.Cu" "*.Mask")
			(remove_unused_layers no)
			(net "SAS_BLAD2_TX5_P")
			(clearance 0.0508)
			(thermal_gap 0.0508)
		)
		(pad "E5" thru_hole circle
			(at 7.999984 5.599938)
			(size 0.9144 0.9144)
			(drill 0.508)
			(layers "*.Cu" "*.Mask")
			(remove_unused_layers no)
			(net "SAS_BLAD2_RX6_N")
			(clearance 0.0508)
			(thermal_gap 0.0508)
		)
		(pad "E6" thru_hole circle
			(at 9.99998 5.500116)
			(size 0.9144 0.9144)
			(drill 0.508)
			(layers "*.Cu" "*.Mask")
			(remove_unused_layers no)
			(net "SAS_BLAD2_TX8_P")
			(clearance 0.0508)
			(thermal_gap 0.0508)
		)
		(pad "F1" thru_hole circle
			(at 0 6.999986)
			(size 0.9144 0.9144)
			(drill 0.508)
			(layers "*.Cu" "*.Mask")
			(remove_unused_layers no)
			(net "GND")
			(clearance 0.0508)
			(thermal_gap 0.0508)
		)
		(pad "F2" thru_hole circle
			(at 1.999996 6.89991)
			(size 0.9144 0.9144)
			(drill 0.508)
			(layers "*.Cu" "*.Mask")
			(remove_unused_layers no)
			(net "SAS_BLAD2_TX3_N")
			(clearance 0.0508)
			(thermal_gap 0.0508)
		)
		(pad "F3" thru_hole circle
			(at 3.999992 6.999986)
			(size 0.9144 0.9144)
			(drill 0.508)
			(layers "*.Cu" "*.Mask")
			(remove_unused_layers no)
			(net "GND")
			(clearance 0.0508)
			(thermal_gap 0.0508)
		)
		(pad "F4" thru_hole circle
			(at 5.999988 6.89991)
			(size 0.9144 0.9144)
			(drill 0.508)
			(layers "*.Cu" "*.Mask")
			(remove_unused_layers no)
			(net "SAS_BLAD2_TX5_N")
			(clearance 0.0508)
			(thermal_gap 0.0508)
		)
		(pad "F5" thru_hole circle
			(at 7.999984 6.999986)
			(size 0.9144 0.9144)
			(drill 0.508)
			(layers "*.Cu" "*.Mask")
			(remove_unused_layers no)
			(net "GND")
			(clearance 0.0508)
			(thermal_gap 0.0508)
		)
		(pad "F6" thru_hole circle
			(at 9.99998 6.89991)
			(size 0.9144 0.9144)
			(drill 0.508)
			(layers "*.Cu" "*.Mask")
			(remove_unused_layers no)
			(net "SAS_BLAD2_TX8_N")
			(clearance 0.0508)
			(thermal_gap 0.0508)
		)
		(pad "G1" thru_hole circle
			(at 0 8.400034)
			(size 0.9144 0.9144)
			(drill 0.508)
			(layers "*.Cu" "*.Mask")
			(remove_unused_layers no)
			(net "SAS_BLAD2_TX2_P")
			(clearance 0.0508)
			(thermal_gap 0.0508)
		)
		(pad "G2" thru_hole circle
			(at 1.999996 8.299958)
			(size 0.9144 0.9144)
			(drill 0.508)
			(layers "*.Cu" "*.Mask")
			(remove_unused_layers no)
			(net "GND")
			(clearance 0.0508)
			(thermal_gap 0.0508)
		)
		(pad "G3" thru_hole circle
			(at 3.999992 8.400034)
			(size 0.9144 0.9144)
			(drill 0.508)
			(layers "*.Cu" "*.Mask")
			(remove_unused_layers no)
			(net "SAS_BLAD2_TX4_P")
			(clearance 0.0508)
			(thermal_gap 0.0508)
		)
		(pad "G4" thru_hole circle
			(at 5.999988 8.299958)
			(size 0.9144 0.9144)
			(drill 0.508)
			(layers "*.Cu" "*.Mask")
			(remove_unused_layers no)
			(net "GND")
			(clearance 0.0508)
			(thermal_gap 0.0508)
		)
		(pad "G5" thru_hole circle
			(at 7.999984 8.400034)
			(size 0.9144 0.9144)
			(drill 0.508)
			(layers "*.Cu" "*.Mask")
			(remove_unused_layers no)
			(net "SAS_BLAD2_TX7_P")
			(clearance 0.0508)
			(thermal_gap 0.0508)
		)
		(pad "G6" thru_hole circle
			(at 9.99998 8.299958)
			(size 0.9144 0.9144)
			(drill 0.508)
			(layers "*.Cu" "*.Mask")
			(remove_unused_layers no)
			(net "GND")
			(clearance 0.0508)
			(thermal_gap 0.0508)
		)
		(pad "H1" thru_hole circle
			(at 0 9.800082)
			(size 0.9144 0.9144)
			(drill 0.508)
			(layers "*.Cu" "*.Mask")
			(remove_unused_layers no)
			(net "SAS_BLAD2_TX2_N")
			(clearance 0.0508)
			(thermal_gap 0.0508)
		)
		(pad "H2" thru_hole circle
			(at 1.999996 9.700006)
			(size 0.9144 0.9144)
			(drill 0.508)
			(layers "*.Cu" "*.Mask")
			(remove_unused_layers no)
			(net "SAS_BLAD2_RX2_P")
			(clearance 0.0508)
			(thermal_gap 0.0508)
		)
		(pad "H3" thru_hole circle
			(at 3.999992 9.800082)
			(size 0.9144 0.9144)
			(drill 0.508)
			(layers "*.Cu" "*.Mask")
			(remove_unused_layers no)
			(net "SAS_BLAD2_TX4_N")
			(clearance 0.0508)
			(thermal_gap 0.0508)
		)
		(pad "H4" thru_hole circle
			(at 5.999988 9.700006)
			(size 0.9144 0.9144)
			(drill 0.508)
			(layers "*.Cu" "*.Mask")
			(remove_unused_layers no)
			(net "SAS_BLAD2_RX5_P")
			(clearance 0.0508)
			(thermal_gap 0.0508)
		)
		(pad "H5" thru_hole circle
			(at 7.999984 9.800082)
			(size 0.9144 0.9144)
			(drill 0.508)
			(layers "*.Cu" "*.Mask")
			(remove_unused_layers no)
			(net "SAS_BLAD2_TX7_N")
			(clearance 0.0508)
			(thermal_gap 0.0508)
		)
		(pad "H6" thru_hole circle
			(at 9.99998 9.700006)
			(size 0.9144 0.9144)
			(drill 0.508)
			(layers "*.Cu" "*.Mask")
			(remove_unused_layers no)
			(net "SAS_BLAD2_RX7_P")
			(clearance 0.0508)
			(thermal_gap 0.0508)
		)
		(pad "I1" thru_hole circle
			(at 0 11.199876)
			(size 0.9144 0.9144)
			(drill 0.508)
			(layers "*.Cu" "*.Mask")
			(remove_unused_layers no)
			(net "GND")
			(clearance 0.0508)
			(thermal_gap 0.0508)
		)
		(pad "I2" thru_hole circle
			(at 1.999996 11.100054)
			(size 0.9144 0.9144)
			(drill 0.508)
			(layers "*.Cu" "*.Mask")
			(remove_unused_layers no)
			(net "SAS_BLAD2_RX2_N")
			(clearance 0.0508)
			(thermal_gap 0.0508)
		)
		(pad "I3" thru_hole circle
			(at 3.999992 11.199876)
			(size 0.9144 0.9144)
			(drill 0.508)
			(layers "*.Cu" "*.Mask")
			(remove_unused_layers no)
			(net "GND")
			(clearance 0.0508)
			(thermal_gap 0.0508)
		)
		(pad "I4" thru_hole circle
			(at 5.999988 11.100054)
			(size 0.9144 0.9144)
			(drill 0.508)
			(layers "*.Cu" "*.Mask")
			(remove_unused_layers no)
			(net "SAS_BLAD2_RX5_N")
			(clearance 0.0508)
			(thermal_gap 0.0508)
		)
		(pad "I5" thru_hole circle
			(at 7.999984 11.199876)
			(size 0.9144 0.9144)
			(drill 0.508)
			(layers "*.Cu" "*.Mask")
			(remove_unused_layers no)
			(net "GND")
			(clearance 0.0508)
			(thermal_gap 0.0508)
		)
		(pad "I6" thru_hole circle
			(at 9.99998 11.100054)
			(size 0.9144 0.9144)
			(drill 0.508)
			(layers "*.Cu" "*.Mask")
			(remove_unused_layers no)
			(net "SAS_BLAD2_RX7_N")
			(clearance 0.0508)
			(thermal_gap 0.0508)
		)
		(zone
			(layer "B.Cu")
			(hatch none 0.5)
			(connect_pads
				(clearance 0)
			)
			(min_thickness 0.25)
			(keepout
				(tracks allowed)
				(vias not_allowed)
				(pads allowed)
				(copperpour not_allowed)
				(footprints allowed)
			)
			(placement
				(enabled no)
				(sheetname "")
			)
			(fill
				(thermal_gap 0.5)
				(thermal_bridge_width 0.5)
				(island_removal_mode 0)
			)
			(polygon
				(pts
					(xy 386.398008 -13.807948) (xy 386.398008 -13.708126) (xy 385.382008 -13.708126) (xy 385.382008 -1.491996)
					(xy 395.381988 -1.491996) (xy 395.381988 -1.592072) (xy 396.397988 -1.592072) (xy 396.397988 -13.807948)
				)
			)
		)
	)
	(footprint ""
		(layer "F.Cu")
		(at 89.41816 -29.122878 180)
		(property "Reference" "R47"
			(at 7.13232 -1.080008 0)
			(unlocked yes)
			(layer "F.SilkS")
			(effects
				(font
					(size 0.7874 0.5842)
					(thickness 0.1524)
				)
				(justify left)
			)
		)
		(property "Value" ""
			(at 0 0 180)
			(layer "F.Fab")
			(effects
				(font
					(size 1.27 1.27)
				)
			)
		)
		(duplicate_pad_numbers_are_jumpers no)
		(fp_line
			(start 0.7874 0.4064)
			(end -0.7874 0.4064)
			(stroke
				(width 0.1524)
				(type default)
			)
			(layer "F.SilkS")
		)
		(fp_line
			(start 0.7874 -0.4064)
			(end 0.7874 0.4064)
			(stroke
				(width 0.1524)
				(type default)
			)
			(layer "F.SilkS")
		)
		(fp_line
			(start -0.7874 0.4064)
			(end -0.7874 -0.4064)
			(stroke
				(width 0.1524)
				(type default)
			)
			(layer "F.SilkS")
		)
		(fp_line
			(start -0.7874 -0.4064)
			(end 0.7874 -0.4064)
			(stroke
				(width 0.1524)
				(type default)
			)
			(layer "F.SilkS")
		)
		(fp_poly
			(pts
				(xy -0.508 0.2794) (xy -0.508 0.2286) (xy -0.635 0.2286) (xy -0.635 -0.254) (xy -0.5334 -0.254)
				(xy -0.5334 -0.2794) (xy 0.5334 -0.2794) (xy 0.5334 -0.254) (xy 0.635 -0.254) (xy 0.635 0.254) (xy 0.5334 0.254)
				(xy 0.5334 0.2794)
			)
			(stroke
				(width 0)
				(type default)
			)
			(fill no)
			(layer "F.CrtYd")
		)
		(pad "1" smd rect
			(at 0.40005 0 180)
			(size 0.4572 0.508)
			(layers "F.Cu" "F.Mask" "F.Paste")
			(net "GND")
		)
		(pad "2" smd rect
			(at -0.40005 0 180)
			(size 0.4572 0.508)
			(layers "F.Cu" "F.Mask" "F.Paste")
			(net "ENET10G_2_TX_DIS")
		)
	)
	(footprint ""
		(layer "F.Cu")
		(at 121.31802 -21.552662 90)
		(property "Reference" "R34"
			(at -6.2738 -59.604148 90)
			(unlocked yes)
			(layer "F.SilkS")
			(effects
				(font
					(size 0.7874 0.5842)
					(thickness 0.1524)
				)
				(justify left)
			)
		)
		(property "Value" ""
			(at 0 0 90)
			(layer "F.Fab")
			(effects
				(font
					(size 1.27 1.27)
				)
			)
		)
		(duplicate_pad_numbers_are_jumpers no)
		(fp_line
			(start 0.7874 -0.4064)
			(end 0.7874 0.4064)
			(stroke
				(width 0.1524)
				(type default)
			)
			(layer "F.SilkS")
		)
		(fp_line
			(start -0.7874 -0.4064)
			(end 0.7874 -0.4064)
			(stroke
				(width 0.1524)
				(type default)
			)
			(layer "F.SilkS")
		)
		(fp_line
			(start 0.7874 0.4064)
			(end -0.7874 0.4064)
			(stroke
				(width 0.1524)
				(type default)
			)
			(layer "F.SilkS")
		)
		(fp_line
			(start -0.7874 0.4064)
			(end -0.7874 -0.4064)
			(stroke
				(width 0.1524)
				(type default)
			)
			(layer "F.SilkS")
		)
		(fp_poly
			(pts
				(xy -0.508 0.2794) (xy -0.508 0.2286) (xy -0.635 0.2286) (xy -0.635 -0.254) (xy -0.5334 -0.254)
				(xy -0.5334 -0.2794) (xy 0.5334 -0.2794) (xy 0.5334 -0.254) (xy 0.635 -0.254) (xy 0.635 0.254) (xy 0.5334 0.254)
				(xy 0.5334 0.2794)
			)
			(stroke
				(width 0)
				(type default)
			)
			(fill no)
			(layer "F.CrtYd")
		)
		(pad "1" smd rect
			(at 0.40005 0 90)
			(size 0.4572 0.508)
			(layers "F.Cu" "F.Mask" "F.Paste")
			(net "GND")
		)
		(pad "2" smd rect
			(at -0.40005 0 90)
			(size 0.4572 0.508)
			(layers "F.Cu" "F.Mask" "F.Paste")
			(net "BLADE1_MATED_N")
		)
	)
	(footprint ""
		(layer "F.Cu")
		(at 313.07024 -28.966922)
		(property "Reference" "R20"
			(at -6.5786 -0.955548 0)
			(unlocked yes)
			(layer "F.SilkS")
			(effects
				(font
					(size 0.7874 0.5842)
					(thickness 0.1524)
				)
				(justify left)
			)
		)
		(property "Value" ""
			(at 0 0 0)
			(layer "F.Fab")
			(effects
				(font
					(size 1.27 1.27)
				)
			)
		)
		(duplicate_pad_numbers_are_jumpers no)
		(fp_line
			(start -0.7874 -0.4064)
			(end 0.7874 -0.4064)
			(stroke
				(width 0.1524)
				(type default)
			)
			(layer "F.SilkS")
		)
		(fp_line
			(start -0.7874 0.4064)
			(end -0.7874 -0.4064)
			(stroke
				(width 0.1524)
				(type default)
			)
			(layer "F.SilkS")
		)
		(fp_line
			(start 0.7874 -0.4064)
			(end 0.7874 0.4064)
			(stroke
				(width 0.1524)
				(type default)
			)
			(layer "F.SilkS")
		)
		(fp_line
			(start 0.7874 0.4064)
			(end -0.7874 0.4064)
			(stroke
				(width 0.1524)
				(type default)
			)
			(layer "F.SilkS")
		)
		(fp_poly
			(pts
				(xy -0.508 0.2794) (xy -0.508 0.2286) (xy -0.635 0.2286) (xy -0.635 -0.254) (xy -0.5334 -0.254)
				(xy -0.5334 -0.2794) (xy 0.5334 -0.2794) (xy 0.5334 -0.254) (xy 0.635 -0.254) (xy 0.635 0.254) (xy 0.5334 0.254)
				(xy 0.5334 0.2794)
			)
			(stroke
				(width 0)
				(type default)
			)
			(fill no)
			(layer "F.CrtYd")
		)
		(pad "1" smd rect
			(at 0.40005 0)
			(size 0.4572 0.508)
			(layers "F.Cu" "F.Mask" "F.Paste")
			(net "P3V3_BLAD2")
		)
		(pad "2" smd rect
			(at -0.40005 0)
			(size 0.4572 0.508)
			(layers "F.Cu" "F.Mask" "F.Paste")
			(net "ENET10G_4_TX_DIS")
		)
	)
	(footprint ""
		(layer "F.Cu")
		(at 425.809918 -29.100018)
		(property "Reference" "GNDPAD1"
			(at 0.659384 9.954768 90)
			(unlocked yes)
			(layer "F.SilkS")
			(effects
				(font
					(size 0.7874 0.5842)
					(thickness 0.1524)
				)
				(justify left)
			)
		)
		(property "Value" ""
			(at 0 0 0)
			(layer "F.Fab")
			(effects
				(font
					(size 1.27 1.27)
				)
			)
		)
		(duplicate_pad_numbers_are_jumpers no)
		(fp_poly
			(pts
				(xy -1.3589 2.4511) (xy 1.3589 2.4511) (xy 1.3589 -2.4511) (xy -1.3589 -2.4511)
			)
			(stroke
				(width 0)
				(type default)
			)
			(fill no)
			(layer "F.CrtYd")
		)
		(pad "1" smd rect
			(at 0 0)
			(size 2.6162 4.8006)
			(layers "F.Cu" "F.Mask" "F.Paste")
			(net "GND")
		)
	)
	(footprint ""
		(layer "F.Cu")
		(at 375.82856 -23.636478 180)
		(property "Reference" "R17"
			(at -33.86328 -16.650208 0)
			(unlocked yes)
			(layer "F.SilkS")
			(effects
				(font
					(size 0.7874 0.5842)
					(thickness 0.1524)
				)
				(justify left)
			)
		)
		(property "Value" ""
			(at 0 0 180)
			(layer "F.Fab")
			(effects
				(font
					(size 1.27 1.27)
				)
			)
		)
		(duplicate_pad_numbers_are_jumpers no)
		(fp_line
			(start 0.7874 0.4064)
			(end -0.7874 0.4064)
			(stroke
				(width 0.1524)
				(type default)
			)
			(layer "F.SilkS")
		)
		(fp_line
			(start 0.7874 -0.4064)
			(end 0.7874 0.4064)
			(stroke
				(width 0.1524)
				(type default)
			)
			(layer "F.SilkS")
		)
		(fp_line
			(start -0.7874 0.4064)
			(end -0.7874 -0.4064)
			(stroke
				(width 0.1524)
				(type default)
			)
			(layer "F.SilkS")
		)
		(fp_line
			(start -0.7874 -0.4064)
			(end 0.7874 -0.4064)
			(stroke
				(width 0.1524)
				(type default)
			)
			(layer "F.SilkS")
		)
		(fp_poly
			(pts
				(xy -0.508 0.2794) (xy -0.508 0.2286) (xy -0.635 0.2286) (xy -0.635 -0.254) (xy -0.5334 -0.254)
				(xy -0.5334 -0.2794) (xy 0.5334 -0.2794) (xy 0.5334 -0.254) (xy 0.635 -0.254) (xy 0.635 0.254) (xy 0.5334 0.254)
				(xy 0.5334 0.2794)
			)
			(stroke
				(width 0)
				(type default)
			)
			(fill no)
			(layer "F.CrtYd")
		)
		(pad "1" smd rect
			(at 0.40005 0 180)
			(size 0.4572 0.508)
			(layers "F.Cu" "F.Mask" "F.Paste")
			(net "P3V3_BLAD2")
		)
		(pad "2" smd rect
			(at -0.40005 0 180)
			(size 0.4572 0.508)
			(layers "F.Cu" "F.Mask" "F.Paste")
			(net "ENET10G_3_TX_FAULT")
		)
	)
	(footprint ""
		(layer "F.Cu")
		(at 142.9512 -3.048 90)
		(property "Reference" "C21"
			(at -2.1844 -8.092948 90)
			(unlocked yes)
			(layer "F.SilkS")
			(effects
				(font
					(size 0.7874 0.5842)
					(thickness 0.1524)
				)
				(justify left)
			)
		)
		(property "Value" ""
			(at 0 0 90)
			(layer "F.Fab")
			(effects
				(font
					(size 1.27 1.27)
				)
			)
		)
		(duplicate_pad_numbers_are_jumpers no)
		(fp_line
			(start 0.7874 -0.4064)
			(end 0.7874 0.4064)
			(stroke
				(width 0.1524)
				(type default)
			)
			(layer "F.SilkS")
		)
		(fp_line
			(start -0.7874 -0.4064)
			(end 0.7874 -0.4064)
			(stroke
				(width 0.1524)
				(type default)
			)
			(layer "F.SilkS")
		)
		(fp_line
			(start 0 0.381)
			(end 0 -0.381)
			(stroke
				(width 0.1524)
				(type default)
			)
			(layer "F.SilkS")
		)
		(fp_line
			(start 0.7874 0.4064)
			(end -0.7874 0.4064)
			(stroke
				(width 0.1524)
				(type default)
			)
			(layer "F.SilkS")
		)
		(fp_line
			(start -0.7874 0.4064)
			(end -0.7874 -0.4064)
			(stroke
				(width 0.1524)
				(type default)
			)
			(layer "F.SilkS")
		)
		(fp_poly
			(pts
				(xy -0.5334 0.254) (xy -0.635 0.254) (xy -0.635 0.2286) (xy -0.635 -0.254) (xy -0.5334 -0.254) (xy -0.5334 -0.2794)
				(xy 0.5334 -0.2794) (xy 0.5334 -0.254) (xy 0.635 -0.254) (xy 0.635 0.254) (xy 0.5334 0.254) (xy 0.5334 0.2794)
				(xy -0.508 0.2794) (xy -0.5334 0.2794)
			)
			(stroke
				(width 0)
				(type default)
			)
			(fill no)
			(layer "F.CrtYd")
		)
		(pad "1" smd rect
			(at 0.40005 0 90)
			(size 0.4572 0.508)
			(layers "F.Cu" "F.Mask" "F.Paste")
			(net "P3V3_10G_1_VCCR")
		)
		(pad "2" smd rect
			(at -0.40005 0 90)
			(size 0.4572 0.508)
			(layers "F.Cu" "F.Mask" "F.Paste")
			(net "GND")
		)
	)
	(footprint ""
		(layer "F.Cu")
		(at 191.494918 -28.4099 180)
		(property "Reference" "U1"
			(at -9.3091 -9.331452 0)
			(unlocked yes)
			(layer "F.SilkS")
			(effects
				(font
					(size 0.7874 0.5842)
					(thickness 0.1524)
				)
				(justify left)
			)
		)
		(property "Value" ""
			(at 0 0 180)
			(layer "F.Fab")
			(effects
				(font
					(size 1.27 1.27)
				)
			)
		)
		(duplicate_pad_numbers_are_jumpers no)
		(fp_line
			(start 6.949948 8.32993)
			(end 6.949948 5.7912)
			(stroke
				(width 0.1524)
				(type default)
			)
			(layer "F.SilkS")
		)
		(fp_line
			(start 6.949948 4.572)
			(end 6.949948 0)
			(stroke
				(width 0.1524)
				(type default)
			)
			(layer "F.SilkS")
		)
		(fp_line
			(start 6.949948 -3.670046)
			(end 0 -3.670046)
			(stroke
				(width 0.1524)
				(type default)
			)
			(layer "F.SilkS")
		)
		(fp_line
			(start 0 -3.670046)
			(end -6.949948 -3.670046)
			(stroke
				(width 0.1524)
				(type default)
			)
			(layer "F.SilkS")
		)
		(fp_line
			(start -6.949948 8.32993)
			(end 6.949948 8.32993)
			(stroke
				(width 0.1524)
				(type default)
			)
			(layer "F.SilkS")
		)
		(fp_line
			(start -6.949948 5.7912)
			(end -6.949948 8.32993)
			(stroke
				(width 0.1524)
				(type default)
			)
			(layer "F.SilkS")
		)
		(fp_line
			(start -6.949948 0)
			(end -6.949948 4.5466)
			(stroke
				(width 0.1524)
				(type default)
			)
			(layer "F.SilkS")
		)
		(fp_line
			(start -6.949948 -3.670046)
			(end -6.949948 0)
			(stroke
				(width 0.1524)
				(type default)
			)
			(layer "F.SilkS")
		)
		(fp_poly
			(pts
				(xy -6.9596 0) (xy -8.7376 1.016) (xy -8.7376 -1.016)
			)
			(stroke
				(width 0)
				(type default)
			)
			(fill yes)
			(layer "F.SilkS")
		)
		(fp_poly
			(pts
				(arc
					(start 4.933188 5.180076)
					(mid 7.066788 5.180076)
					(end 4.933188 5.180076)
				)
			)
			(stroke
				(width 0)
				(type default)
			)
			(fill no)
			(layer "B.CrtYd")
		)
		(fp_poly
			(pts
				(arc
					(start -7.06755 5.180076)
					(mid -4.932426 5.180076)
					(end -7.06755 5.180076)
				)
			)
			(stroke
				(width 0)
				(type default)
			)
			(fill no)
			(layer "B.CrtYd")
		)
		(fp_poly
			(pts
				(xy -6.949948 8.32993) (xy 6.949948 8.32993) (xy 6.949948 -3.670046) (xy -6.949948 -3.670046)
			)
			(stroke
				(width 0)
				(type default)
			)
			(fill no)
			(layer "F.CrtYd")
		)
		(fp_line
			(start 6.949948 8.32993)
			(end 6.949948 -3.670046)
			(stroke
				(width 0.1)
				(type default)
			)
			(layer "F.Fab")
		)
		(fp_line
			(start 6.949948 -3.670046)
			(end -6.949948 -3.670046)
			(stroke
				(width 0.1)
				(type default)
			)
			(layer "F.Fab")
		)
		(fp_line
			(start -6.700012 0)
			(end -6.949948 0)
			(stroke
				(width 0.1)
				(type default)
			)
			(layer "F.Fab")
		)
		(fp_line
			(start -6.949948 8.32993)
			(end 6.949948 8.32993)
			(stroke
				(width 0.1)
				(type default)
			)
			(layer "F.Fab")
		)
		(fp_line
			(start -6.949948 0)
			(end -6.949948 8.32993)
			(stroke
				(width 0.1)
				(type default)
			)
			(layer "F.Fab")
		)
		(fp_line
			(start -6.949948 -3.670046)
			(end -6.949948 0)
			(stroke
				(width 0.1)
				(type default)
			)
			(layer "F.Fab")
		)
		(fp_poly
			(pts
				(xy -6.9596 0) (xy -8.7376 1.016) (xy -8.7376 -1.016)
			)
			(stroke
				(width 0)
				(type default)
			)
			(fill yes)
			(layer "F.Fab")
		)
		(fp_text user "A13"
			(at 9.481566 0.837184 90)
			(unlocked yes)
			(layer "F.SilkS")
			(effects
				(font
					(size 0.7874 0.5842)
					(thickness 0.1524)
				)
				(justify left)
			)
		)
		(fp_text user "B13"
			(at 9.42594 -3.176016 90)
			(unlocked yes)
			(layer "F.SilkS")
			(effects
				(font
					(size 0.7874 0.5842)
					(thickness 0.1524)
				)
				(justify left)
			)
		)
		(fp_text user "A1"
			(at -11.85418 1.438148 0)
			(unlocked yes)
			(layer "F.SilkS")
			(effects
				(font
					(size 0.7874 0.5842)
					(thickness 0.1524)
				)
				(justify left)
			)
		)
		(fp_text user "B1"
			(at -11.85418 -3.367278 0)
			(unlocked yes)
			(layer "F.SilkS")
			(effects
				(font
					(size 0.7874 0.5842)
					(thickness 0.1524)
				)
				(justify left)
			)
		)
		(fp_text user "A13"
			(at 7.360666 -0.091948 180)
			(unlocked yes)
			(layer "F.Fab")
			(effects
				(font
					(size 0.7874 0.5842)
					(thickness 0.000001)
				)
				(justify left)
			)
		)
		(fp_text user "B13"
			(at 7.360666 -2.601722 180)
			(unlocked yes)
			(layer "F.Fab")
			(effects
				(font
					(size 0.7874 0.5842)
					(thickness 0.000001)
				)
				(justify left)
			)
		)
		(fp_text user "A1"
			(at -8.609584 1.330452 180)
			(unlocked yes)
			(layer "F.Fab")
			(effects
				(font
					(size 0.7874 0.5842)
					(thickness 0.000001)
				)
				(justify left)
			)
		)
		(fp_text user "B1"
			(at -8.685784 -2.601722 180)
			(unlocked yes)
			(layer "F.Fab")
			(effects
				(font
					(size 0.7874 0.5842)
					(thickness 0.000001)
				)
				(justify left)
			)
		)
		(pad "" np_thru_hole circle
			(at -5.999988 5.180076 180)
			(size 1.6002 1.6002)
			(drill 1.6002)
			(layers "*.Cu" "*.Mask")
			(clearance 0.381)
			(thermal_gap 0.381)
		)
		(pad "" np_thru_hole circle
			(at 5.999988 5.180076 180)
			(size 1.6002 1.6002)
			(drill 1.6002)
			(layers "*.Cu" "*.Mask")
			(clearance 0.381)
			(thermal_gap 0.381)
		)
		(pad "A1" smd rect
			(at -4.59994 0 180)
			(size 0.381 1.8542)
			(layers "F.Cu" "F.Mask" "F.Paste")
			(net "GND")
		)
		(pad "A2" smd rect
			(at -3.800094 0 180)
			(size 0.381 1.8542)
			(layers "F.Cu" "F.Mask" "F.Paste")
			(net "SAS_BLAD1_RX1_P")
		)
		(pad "A3" smd rect
			(at -2.999994 0 180)
			(size 0.381 1.8542)
			(layers "F.Cu" "F.Mask" "F.Paste")
			(net "SAS_BLAD1_RX1_N")
		)
		(pad "A4" smd rect
			(at -2.199894 0 180)
			(size 0.381 1.8542)
			(layers "F.Cu" "F.Mask" "F.Paste")
			(net "GND")
		)
		(pad "A5" smd rect
			(at -1.400048 0 180)
			(size 0.381 1.8542)
			(layers "F.Cu" "F.Mask" "F.Paste")
			(net "SAS_BLAD1_RX2_P")
		)
		(pad "A6" smd rect
			(at -0.599948 0 180)
			(size 0.381 1.8542)
			(layers "F.Cu" "F.Mask" "F.Paste")
			(net "SAS_BLAD1_RX2_N")
		)
		(pad "A7" smd rect
			(at 0.199898 0 180)
			(size 0.381 1.8542)
			(layers "F.Cu" "F.Mask" "F.Paste")
			(net "GND")
		)
		(pad "A8" smd rect
			(at 0.999998 0 180)
			(size 0.381 1.8542)
			(layers "F.Cu" "F.Mask" "F.Paste")
			(net "SAS_BLAD1_RX3_P")
		)
		(pad "A9" smd rect
			(at 1.800098 0 180)
			(size 0.381 1.8542)
			(layers "F.Cu" "F.Mask" "F.Paste")
			(net "SAS_BLAD1_RX3_N")
		)
		(pad "A10" smd rect
			(at 2.599944 0 180)
			(size 0.381 1.8542)
			(layers "F.Cu" "F.Mask" "F.Paste")
			(net "GND")
		)
		(pad "A11" smd rect
			(at 3.400044 0 180)
			(size 0.381 1.8542)
			(layers "F.Cu" "F.Mask" "F.Paste")
			(net "SAS_BLAD1_RX4_P")
		)
		(pad "A12" smd rect
			(at 4.19989 0 180)
			(size 0.381 1.8542)
			(layers "F.Cu" "F.Mask" "F.Paste")
			(net "SAS_BLAD1_RX4_N")
		)
		(pad "A13" smd rect
			(at 4.99999 0 180)
			(size 0.381 1.8542)
			(layers "F.Cu" "F.Mask" "F.Paste")
			(net "GND")
		)
		(pad "B1" smd rect
			(at -4.99999 -2.510028 180)
			(size 0.381 1.8542)
			(layers "F.Cu" "F.Mask" "F.Paste")
			(net "GND")
		)
		(pad "B2" smd rect
			(at -4.19989 -2.510028 180)
			(size 0.381 1.8542)
			(layers "F.Cu" "F.Mask" "F.Paste")
			(net "SAS_BLAD1_TX1_P")
		)
		(pad "B3" smd rect
			(at -3.400044 -2.510028 180)
			(size 0.381 1.8542)
			(layers "F.Cu" "F.Mask" "F.Paste")
			(net "SAS_BLAD1_TX1_N")
		)
		(pad "B4" smd rect
			(at -2.599944 -2.510028 180)
			(size 0.381 1.8542)
			(layers "F.Cu" "F.Mask" "F.Paste")
			(net "GND")
		)
		(pad "B5" smd rect
			(at -1.800098 -2.510028 180)
			(size 0.381 1.8542)
			(layers "F.Cu" "F.Mask" "F.Paste")
			(net "SAS_BLAD1_TX2_P")
		)
		(pad "B6" smd rect
			(at -0.999998 -2.510028 180)
			(size 0.381 1.8542)
			(layers "F.Cu" "F.Mask" "F.Paste")
			(net "SAS_BLAD1_TX2_N")
		)
		(pad "B7" smd rect
			(at -0.199898 -2.510028 180)
			(size 0.381 1.8542)
			(layers "F.Cu" "F.Mask" "F.Paste")
			(net "GND")
		)
		(pad "B8" smd rect
			(at 0.599948 -2.510028 180)
			(size 0.381 1.8542)
			(layers "F.Cu" "F.Mask" "F.Paste")
			(net "SAS_BLAD1_TX3_P")
		)
		(pad "B9" smd rect
			(at 1.400048 -2.510028 180)
			(size 0.381 1.8542)
			(layers "F.Cu" "F.Mask" "F.Paste")
			(net "SAS_BLAD1_TX3_N")
		)
		(pad "B10" smd rect
			(at 2.199894 -2.510028 180)
			(size 0.381 1.8542)
			(layers "F.Cu" "F.Mask" "F.Paste")
			(net "GND")
		)
		(pad "B11" smd rect
			(at 2.999994 -2.510028 180)
			(size 0.381 1.8542)
			(layers "F.Cu" "F.Mask" "F.Paste")
			(net "SAS_BLAD1_TX4_P")
		)
		(pad "B12" smd rect
			(at 3.800094 -2.510028 180)
			(size 0.381 1.8542)
			(layers "F.Cu" "F.Mask" "F.Paste")
			(net "SAS_BLAD1_TX4_N")
		)
		(pad "B13" smd rect
			(at 4.59994 -2.510028 180)
			(size 0.381 1.8542)
			(layers "F.Cu" "F.Mask" "F.Paste")
			(net "GND")
		)
		(zone
			(layer "F.Cu")
			(hatch none 0.5)
			(connect_pads
				(clearance 0)
			)
			(min_thickness 0.25)
			(keepout
				(tracks not_allowed)
				(vias allowed)
				(pads allowed)
				(copperpour not_allowed)
				(footprints allowed)
			)
			(placement
				(enabled no)
				(sheetname "")
			)
			(fill
				(thermal_gap 0.5)
				(thermal_bridge_width 0.5)
				(island_removal_mode 0)
			)
			(polygon
				(pts
					(xy 186.414918 -36.73983) (xy 184.574942 -36.73983) (xy 184.574942 -35.279838) (xy 186.414918 -35.279838)
				)
			)
		)
		(zone
			(layer "F.Cu")
			(hatch none 0.5)
			(connect_pads
				(clearance 0)
			)
			(min_thickness 0.25)
			(keepout
				(tracks not_allowed)
				(vias allowed)
				(pads allowed)
				(copperpour not_allowed)
				(footprints allowed)
			)
			(placement
				(enabled no)
				(sheetname "")
			)
			(fill
				(thermal_gap 0.5)
				(thermal_bridge_width 0.5)
				(island_removal_mode 0)
			)
			(polygon
				(pts
					(xy 198.414894 -36.73983) (xy 196.574918 -36.73983) (xy 196.574918 -35.279838) (xy 198.414894 -35.279838)
				)
			)
		)
		(zone
			(layers "F.Cu" "B.Cu" "In1.Cu" "In2.Cu" "In3.Cu" "In4.Cu" "In5.Cu" "In6.Cu")
			(hatch none 0.5)
			(connect_pads
				(clearance 0)
			)
			(min_thickness 0.25)
			(keepout
				(tracks not_allowed)
				(vias allowed)
				(pads allowed)
				(copperpour not_allowed)
				(footprints allowed)
			)
			(placement
				(enabled no)
				(sheetname "")
			)
			(fill
				(thermal_gap 0.5)
				(thermal_bridge_width 0.5)
				(island_removal_mode 0)
			)
			(polygon
				(pts
					(arc
						(start 186.713876 -33.589976)
						(mid 184.275984 -33.589976)
						(end 186.713876 -33.589976)
					)
				)
			)
		)
		(zone
			(layers "F.Cu" "B.Cu" "In1.Cu" "In2.Cu" "In3.Cu" "In4.Cu" "In5.Cu" "In6.Cu")
			(hatch none 0.5)
			(connect_pads
				(clearance 0)
			)
			(min_thickness 0.25)
			(keepout
				(tracks not_allowed)
				(vias allowed)
				(pads allowed)
				(copperpour not_allowed)
				(footprints allowed)
			)
			(placement
				(enabled no)
				(sheetname "")
			)
			(fill
				(thermal_gap 0.5)
				(thermal_bridge_width 0.5)
				(island_removal_mode 0)
			)
			(polygon
				(pts
					(arc
						(start 198.714614 -33.589976)
						(mid 196.275198 -33.589976)
						(end 198.714614 -33.589976)
					)
				)
			)
		)
	)
	(footprint ""
		(layer "F.Cu")
		(at 310.308752 -28.966922 180)
		(property "Reference" "R55"
			(at 6.801104 0.984504 0)
			(unlocked yes)
			(layer "F.SilkS")
			(effects
				(font
					(size 0.7874 0.5842)
					(thickness 0.1524)
				)
				(justify left)
			)
		)
		(property "Value" ""
			(at 0 0 180)
			(layer "F.Fab")
			(effects
				(font
					(size 1.27 1.27)
				)
			)
		)
		(duplicate_pad_numbers_are_jumpers no)
		(fp_line
			(start 0.7874 0.4064)
			(end -0.7874 0.4064)
			(stroke
				(width 0.1524)
				(type default)
			)
			(layer "F.SilkS")
		)
		(fp_line
			(start 0.7874 -0.4064)
			(end 0.7874 0.4064)
			(stroke
				(width 0.1524)
				(type default)
			)
			(layer "F.SilkS")
		)
		(fp_line
			(start -0.7874 0.4064)
			(end -0.7874 -0.4064)
			(stroke
				(width 0.1524)
				(type default)
			)
			(layer "F.SilkS")
		)
		(fp_line
			(start -0.7874 -0.4064)
			(end 0.7874 -0.4064)
			(stroke
				(width 0.1524)
				(type default)
			)
			(layer "F.SilkS")
		)
		(fp_poly
			(pts
				(xy -0.508 0.2794) (xy -0.508 0.2286) (xy -0.635 0.2286) (xy -0.635 -0.254) (xy -0.5334 -0.254)
				(xy -0.5334 -0.2794) (xy 0.5334 -0.2794) (xy 0.5334 -0.254) (xy 0.635 -0.254) (xy 0.635 0.254) (xy 0.5334 0.254)
				(xy 0.5334 0.2794)
			)
			(stroke
				(width 0)
				(type default)
			)
			(fill no)
			(layer "F.CrtYd")
		)
		(pad "1" smd rect
			(at 0.40005 0 180)
			(size 0.4572 0.508)
			(layers "F.Cu" "F.Mask" "F.Paste")
			(net "GND")
		)
		(pad "2" smd rect
			(at -0.40005 0 180)
			(size 0.4572 0.508)
			(layers "F.Cu" "F.Mask" "F.Paste")
			(net "ENET10G_4_TX_DIS")
		)
	)
	(footprint ""
		(layer "F.Cu")
		(at 117.31244 -21.08581)
		(property "Reference" "R46"
			(at -61.341 4.988052 0)
			(unlocked yes)
			(layer "F.SilkS")
			(effects
				(font
					(size 0.7874 0.5842)
					(thickness 0.1524)
				)
				(justify left)
			)
		)
		(property "Value" ""
			(at 0 0 0)
			(layer "F.Fab")
			(effects
				(font
					(size 1.27 1.27)
				)
			)
		)
		(duplicate_pad_numbers_are_jumpers no)
		(fp_line
			(start -0.7874 -0.4064)
			(end 0.7874 -0.4064)
			(stroke
				(width 0.1524)
				(type default)
			)
			(layer "F.SilkS")
		)
		(fp_line
			(start -0.7874 0.4064)
			(end -0.7874 -0.4064)
			(stroke
				(width 0.1524)
				(type default)
			)
			(layer "F.SilkS")
		)
		(fp_line
			(start 0.7874 -0.4064)
			(end 0.7874 0.4064)
			(stroke
				(width 0.1524)
				(type default)
			)
			(layer "F.SilkS")
		)
		(fp_line
			(start 0.7874 0.4064)
			(end -0.7874 0.4064)
			(stroke
				(width 0.1524)
				(type default)
			)
			(layer "F.SilkS")
		)
		(fp_poly
			(pts
				(xy -0.508 0.2794) (xy -0.508 0.2286) (xy -0.635 0.2286) (xy -0.635 -0.254) (xy -0.5334 -0.254)
				(xy -0.5334 -0.2794) (xy 0.5334 -0.2794) (xy 0.5334 -0.254) (xy 0.635 -0.254) (xy 0.635 0.254) (xy 0.5334 0.254)
				(xy 0.5334 0.2794)
			)
			(stroke
				(width 0)
				(type default)
			)
			(fill no)
			(layer "F.CrtYd")
		)
		(pad "1" smd rect
			(at 0.40005 0)
			(size 0.4572 0.508)
			(layers "F.Cu" "F.Mask" "F.Paste")
			(net "GND")
		)
		(pad "2" smd rect
			(at -0.40005 0)
			(size 0.4572 0.508)
			(layers "F.Cu" "F.Mask" "F.Paste")
			(net "ENET10G_2_TX_FAULT")
		)
	)
	(footprint ""
		(layer "F.Cu")
		(at 104.570022 -14.389862 180)
		(property "Reference" "U6"
			(at -5.134356 -8.113776 0)
			(unlocked yes)
			(layer "F.SilkS")
			(effects
				(font
					(size 0.7874 0.5842)
					(thickness 0.1524)
				)
				(justify left)
			)
		)
		(property "Value" ""
			(at 0 0 180)
			(layer "F.Fab")
			(effects
				(font
					(size 1.27 1.27)
				)
			)
		)
		(duplicate_pad_numbers_are_jumpers no)
		(fp_line
			(start 5.500116 3.700018)
			(end 4.191 3.700018)
			(stroke
				(width 0.1524)
				(type default)
			)
			(layer "F.SilkS")
		)
		(fp_line
			(start 5.500116 0.889)
			(end 5.500116 3.700018)
			(stroke
				(width 0.1524)
				(type default)
			)
			(layer "F.SilkS")
		)
		(fp_line
			(start 5.500116 -3.700018)
			(end 5.500116 -0.889)
			(stroke
				(width 0.1524)
				(type default)
			)
			(layer "F.SilkS")
		)
		(fp_line
			(start 3.7846 -3.700018)
			(end 5.500116 -3.700018)
			(stroke
				(width 0.1524)
				(type default)
			)
			(layer "F.SilkS")
		)
		(fp_line
			(start -3.7846 3.700018)
			(end -5.500116 3.700018)
			(stroke
				(width 0.1524)
				(type default)
			)
			(layer "F.SilkS")
		)
		(fp_line
			(start -5.500116 0.635)
			(end -5.500116 3.700018)
			(stroke
				(width 0.1524)
				(type default)
			)
			(layer "F.SilkS")
		)
		(fp_line
			(start -5.500116 -3.700018)
			(end -4.191 -3.700018)
			(stroke
				(width 0.1524)
				(type default)
			)
			(layer "F.SilkS")
		)
		(fp_line
			(start -5.500116 -3.700018)
			(end -5.500116 -0.635)
			(stroke
				(width 0.1524)
				(type default)
			)
			(layer "F.SilkS")
		)
		(fp_poly
			(pts
				(xy -3.387344 5.3848) (xy -3.946144 6.8072) (xy -2.853944 6.8072)
			)
			(stroke
				(width 0)
				(type default)
			)
			(fill yes)
			(layer "F.SilkS")
		)
		(fp_poly
			(pts
				(arc
					(start -4.064 -0.3302)
					(mid -4.8006 -1.0668)
					(end -5.5372 -0.3302)
				)
				(arc
					(start -5.5372 0.3048)
					(mid -5.314015 0.843615)
					(end -4.7752 1.0668)
				)
				(arc
					(start -4.7752 1.0668)
					(mid -4.272306 0.858494)
					(end -4.064 0.3556)
				)
			)
			(stroke
				(width 0)
				(type default)
			)
			(fill no)
			(layer "B.CrtYd")
		)
		(fp_poly
			(pts
				(arc
					(start 3.7338 0)
					(mid 5.8674 0)
					(end 3.7338 0)
				)
			)
			(stroke
				(width 0)
				(type default)
			)
			(fill no)
			(layer "B.CrtYd")
		)
		(fp_rect
			(start -5.5118 5.1308)
			(end 5.5118 -5.1308)
			(stroke
				(width 0)
				(type default)
			)
			(fill no)
			(layer "F.CrtYd")
		)
		(fp_text user "10"
			(at 5.776214 5.877306 0)
			(unlocked yes)
			(layer "F.SilkS")
			(effects
				(font
					(size 0.7874 0.5842)
					(thickness 0.1524)
				)
				(justify left)
			)
		)
		(fp_text user "11"
			(at 3.19659 -6.426454 90)
			(unlocked yes)
			(layer "F.SilkS")
			(effects
				(font
					(size 0.7874 0.5842)
					(thickness 0.1524)
				)
				(justify left)
			)
		)
		(fp_text user "20"
			(at -3.99161 -8.483854 90)
			(unlocked yes)
			(layer "F.SilkS")
			(effects
				(font
					(size 0.7874 0.5842)
					(thickness 0.1524)
				)
				(justify left)
			)
		)
		(fp_text user "1"
			(at -4.148582 5.851906 0)
			(unlocked yes)
			(layer "F.SilkS")
			(effects
				(font
					(size 0.7874 0.5842)
					(thickness 0.1524)
				)
				(justify left)
			)
		)
		(pad "" np_thru_hole oval
			(at -4.800092 0 180)
			(size 0.9652 1.6002)
			(drill oval 0.9652 1.6002)
			(layers "*.Cu" "*.Mask")
			(clearance 0.381)
			(thermal_gap 0.381)
		)
		(pad "" np_thru_hole circle
			(at 4.800092 0 180)
			(size 1.6002 1.6002)
			(drill 1.6002)
			(layers "*.Cu" "*.Mask")
			(clearance 0.381)
			(thermal_gap 0.381)
		)
		(pad "1" smd oval
			(at -3.400044 4.100068 180)
			(size 0.508 2.032)
			(layers "F.Cu" "F.Mask" "F.Paste")
			(net "GND")
		)
		(pad "2" smd oval
			(at -2.599944 4.100068 180)
			(size 0.508 2.032)
			(layers "F.Cu" "F.Mask" "F.Paste")
			(net "ENET10G_2_TX_FAULT")
		)
		(pad "3" smd oval
			(at -1.800098 4.100068 180)
			(size 0.508 2.032)
			(layers "F.Cu" "F.Mask" "F.Paste")
			(net "ENET10G_2_TX_DIS")
		)
		(pad "4" smd oval
			(at -0.999998 4.100068 180)
			(size 0.508 2.032)
			(layers "F.Cu" "F.Mask" "F.Paste")
			(net "ENET10G_2_SDA")
		)
		(pad "5" smd oval
			(at -0.199898 4.100068 180)
			(size 0.508 2.032)
			(layers "F.Cu" "F.Mask" "F.Paste")
			(net "ENET10G_2_SCL")
		)
		(pad "6" smd oval
			(at 0.599948 4.100068 180)
			(size 0.508 2.032)
			(layers "F.Cu" "F.Mask" "F.Paste")
			(net "ENET10G_2_MOD_DEF0")
		)
		(pad "7" smd oval
			(at 1.400048 4.100068 180)
			(size 0.508 2.032)
			(layers "F.Cu" "F.Mask" "F.Paste")
			(net "ENET10G_2_RS0")
		)
		(pad "8" smd oval
			(at 2.199894 4.100068 180)
			(size 0.508 2.032)
			(layers "F.Cu" "F.Mask" "F.Paste")
			(net "ENET10G_2_LOS")
		)
		(pad "9" smd oval
			(at 2.999994 4.100068 180)
			(size 0.508 2.032)
			(layers "F.Cu" "F.Mask" "F.Paste")
			(net "ENET10G_2_RS1")
		)
		(pad "10" smd oval
			(at 3.800094 4.100068 180)
			(size 0.508 2.032)
			(layers "F.Cu" "F.Mask" "F.Paste")
			(net "GND")
		)
		(pad "11" smd oval
			(at 3.400044 -4.100068 180)
			(size 0.508 2.032)
			(layers "F.Cu" "F.Mask" "F.Paste")
			(net "GND")
		)
		(pad "12" smd oval
			(at 2.599944 -4.100068 180)
			(size 0.508 2.032)
			(layers "F.Cu" "F.Mask" "F.Paste")
			(net "ENET10G_2_RDN")
		)
		(pad "13" smd oval
			(at 1.800098 -4.100068 180)
			(size 0.508 2.032)
			(layers "F.Cu" "F.Mask" "F.Paste")
			(net "ENET10G_2_RDP")
		)
		(pad "14" smd oval
			(at 0.999998 -4.100068 180)
			(size 0.508 2.032)
			(layers "F.Cu" "F.Mask" "F.Paste")
			(net "GND")
		)
		(pad "15" smd oval
			(at 0.199898 -4.100068 180)
			(size 0.508 2.032)
			(layers "F.Cu" "F.Mask" "F.Paste")
			(net "P3V3_10G_2_VCCR")
		)
		(pad "16" smd oval
			(at -0.599948 -4.100068 180)
			(size 0.508 2.032)
			(layers "F.Cu" "F.Mask" "F.Paste")
			(net "P3V3_10G_2_VCCT")
		)
		(pad "17" smd oval
			(at -1.400048 -4.100068 180)
			(size 0.508 2.032)
			(layers "F.Cu" "F.Mask" "F.Paste")
			(net "GND")
		)
		(pad "18" smd oval
			(at -2.199894 -4.100068 180)
			(size 0.508 2.032)
			(layers "F.Cu" "F.Mask" "F.Paste")
			(net "ENET10G_2_TDP")
		)
		(pad "19" smd oval
			(at -2.999994 -4.100068 180)
			(size 0.508 2.032)
			(layers "F.Cu" "F.Mask" "F.Paste")
			(net "ENET10G_2_TDN")
		)
		(pad "20" smd oval
			(at -3.800094 -4.100068 180)
			(size 0.508 2.032)
			(layers "F.Cu" "F.Mask" "F.Paste")
			(net "GND")
		)
		(zone
			(layers "F.Cu" "B.Cu" "In1.Cu" "In2.Cu" "In3.Cu" "In4.Cu" "In5.Cu" "In6.Cu")
			(hatch none 0.5)
			(connect_pads
				(clearance 0)
			)
			(min_thickness 0.25)
			(keepout
				(tracks not_allowed)
				(vias allowed)
				(pads allowed)
				(copperpour not_allowed)
				(footprints allowed)
			)
			(placement
				(enabled no)
				(sheetname "")
			)
			(fill
				(thermal_gap 0.5)
				(thermal_bridge_width 0.5)
				(island_removal_mode 0)
			)
			(polygon
				(pts
					(arc
						(start 109.345222 -15.609062)
						(mid 109.9918 -15.34124)
						(end 110.259622 -14.694662)
					)
					(arc
						(start 110.259622 -14.059662)
						(mid 109.370622 -13.170662)
						(end 108.481622 -14.059662)
					)
					(arc
						(start 108.481622 -14.745462)
						(mid 108.734565 -15.356119)
						(end 109.345222 -15.609062)
					)
				)
			)
		)
		(zone
			(layers "F.Cu" "B.Cu" "In1.Cu" "In2.Cu" "In3.Cu" "In4.Cu" "In5.Cu" "In6.Cu")
			(hatch none 0.5)
			(connect_pads
				(clearance 0)
			)
			(min_thickness 0.25)
			(keepout
				(tracks not_allowed)
				(vias allowed)
				(pads allowed)
				(copperpour not_allowed)
				(footprints allowed)
			)
			(placement
				(enabled no)
				(sheetname "")
			)
			(fill
				(thermal_gap 0.5)
				(thermal_bridge_width 0.5)
				(island_removal_mode 0)
			)
			(polygon
				(pts
					(arc
						(start 100.988622 -14.389862)
						(mid 98.550222 -14.389862)
						(end 100.988622 -14.389862)
					)
				)
			)
		)
	)
	(footprint ""
		(layer "F.Cu")
		(at 323.2404 -2.6416 90)
		(property "Reference" "C31"
			(at -1.6002 -3.038348 90)
			(unlocked yes)
			(layer "F.SilkS")
			(effects
				(font
					(size 0.7874 0.5842)
					(thickness 0.1524)
				)
				(justify left)
			)
		)
		(property "Value" ""
			(at 0 0 90)
			(layer "F.Fab")
			(effects
				(font
					(size 1.27 1.27)
				)
			)
		)
		(duplicate_pad_numbers_are_jumpers no)
		(fp_line
			(start 0.7874 -0.4064)
			(end 0.7874 0.4064)
			(stroke
				(width 0.1524)
				(type default)
			)
			(layer "F.SilkS")
		)
		(fp_line
			(start -0.7874 -0.4064)
			(end 0.7874 -0.4064)
			(stroke
				(width 0.1524)
				(type default)
			)
			(layer "F.SilkS")
		)
		(fp_line
			(start 0 0.381)
			(end 0 -0.381)
			(stroke
				(width 0.1524)
				(type default)
			)
			(layer "F.SilkS")
		)
		(fp_line
			(start 0.7874 0.4064)
			(end -0.7874 0.4064)
			(stroke
				(width 0.1524)
				(type default)
			)
			(layer "F.SilkS")
		)
		(fp_line
			(start -0.7874 0.4064)
			(end -0.7874 -0.4064)
			(stroke
				(width 0.1524)
				(type default)
			)
			(layer "F.SilkS")
		)
		(fp_poly
			(pts
				(xy -0.5334 0.254) (xy -0.635 0.254) (xy -0.635 0.2286) (xy -0.635 -0.254) (xy -0.5334 -0.254) (xy -0.5334 -0.2794)
				(xy 0.5334 -0.2794) (xy 0.5334 -0.254) (xy 0.635 -0.254) (xy 0.635 0.254) (xy 0.5334 0.254) (xy 0.5334 0.2794)
				(xy -0.508 0.2794) (xy -0.5334 0.2794)
			)
			(stroke
				(width 0)
				(type default)
			)
			(fill no)
			(layer "F.CrtYd")
		)
		(pad "1" smd rect
			(at 0.40005 0 90)
			(size 0.4572 0.508)
			(layers "F.Cu" "F.Mask" "F.Paste")
			(net "P3V3_10G_4_VCCR")
		)
		(pad "2" smd rect
			(at -0.40005 0 90)
			(size 0.4572 0.508)
			(layers "F.Cu" "F.Mask" "F.Paste")
			(net "GND")
		)
	)
	(footprint ""
		(layer "F.Cu")
		(at 154.89936 -26.709878 180)
		(property "Reference" "R15"
			(at -33.73628 -17.945608 0)
			(unlocked yes)
			(layer "F.SilkS")
			(effects
				(font
					(size 0.7874 0.5842)
					(thickness 0.1524)
				)
				(justify left)
			)
		)
		(property "Value" ""
			(at 0 0 180)
			(layer "F.Fab")
			(effects
				(font
					(size 1.27 1.27)
				)
			)
		)
		(duplicate_pad_numbers_are_jumpers no)
		(fp_line
			(start 0.7874 0.4064)
			(end -0.7874 0.4064)
			(stroke
				(width 0.1524)
				(type default)
			)
			(layer "F.SilkS")
		)
		(fp_line
			(start 0.7874 -0.4064)
			(end 0.7874 0.4064)
			(stroke
				(width 0.1524)
				(type default)
			)
			(layer "F.SilkS")
		)
		(fp_line
			(start -0.7874 0.4064)
			(end -0.7874 -0.4064)
			(stroke
				(width 0.1524)
				(type default)
			)
			(layer "F.SilkS")
		)
		(fp_line
			(start -0.7874 -0.4064)
			(end 0.7874 -0.4064)
			(stroke
				(width 0.1524)
				(type default)
			)
			(layer "F.SilkS")
		)
		(fp_poly
			(pts
				(xy -0.508 0.2794) (xy -0.508 0.2286) (xy -0.635 0.2286) (xy -0.635 -0.254) (xy -0.5334 -0.254)
				(xy -0.5334 -0.2794) (xy 0.5334 -0.2794) (xy 0.5334 -0.254) (xy 0.635 -0.254) (xy 0.635 0.254) (xy 0.5334 0.254)
				(xy 0.5334 0.2794)
			)
			(stroke
				(width 0)
				(type default)
			)
			(fill no)
			(layer "F.CrtYd")
		)
		(pad "1" smd rect
			(at 0.40005 0 180)
			(size 0.4572 0.508)
			(layers "F.Cu" "F.Mask" "F.Paste")
			(net "P3V3_BLAD1")
		)
		(pad "2" smd rect
			(at -0.40005 0 180)
			(size 0.4572 0.508)
			(layers "F.Cu" "F.Mask" "F.Paste")
			(net "ENET10G_1_RS1")
		)
	)
	(footprint ""
		(layer "F.Cu")
		(at 310.749696 -23.520146 -90)
		(property "Reference" "C9"
			(at -1.854708 5.446522 90)
			(unlocked yes)
			(layer "F.SilkS")
			(effects
				(font
					(size 0.7874 0.5842)
					(thickness 0.1524)
				)
			)
		)
		(property "Value" ""
			(at 0 0 270)
			(layer "F.Fab")
			(effects
				(font
					(size 1.27 1.27)
				)
			)
		)
		(duplicate_pad_numbers_are_jumpers no)
		(fp_line
			(start -1.2954 0.5842)
			(end -1.2954 -0.5842)
			(stroke
				(width 0.1524)
				(type default)
			)
			(layer "F.SilkS")
		)
		(fp_line
			(start 1.2954 0.5842)
			(end -1.2954 0.5842)
			(stroke
				(width 0.1524)
				(type default)
			)
			(layer "F.SilkS")
		)
		(fp_line
			(start -1.2954 -0.5842)
			(end 1.2954 -0.5842)
			(stroke
				(width 0.1524)
				(type default)
			)
			(layer "F.SilkS")
		)
		(fp_line
			(start 0 -0.5842)
			(end 0 0.5842)
			(stroke
				(width 0.1524)
				(type default)
			)
			(layer "F.SilkS")
		)
		(fp_line
			(start 1.2954 -0.5842)
			(end 1.2954 0.5842)
			(stroke
				(width 0.1524)
				(type default)
			)
			(layer "F.SilkS")
		)
		(fp_poly
			(pts
				(xy 0.8636 -0.4572) (xy 0.8636 -0.3556) (xy 1.143 -0.3556) (xy 1.143 0.3556) (xy 0.8636 0.3556)
				(xy 0.8636 0.4572) (xy -0.8636 0.4572) (xy -0.8636 0.3556) (xy -1.143 0.3556) (xy -1.143 -0.3556)
				(xy -0.8636 -0.3556) (xy -0.8636 -0.4572)
			)
			(stroke
				(width 0)
				(type default)
			)
			(fill no)
			(layer "F.CrtYd")
		)
		(fp_line
			(start -0.884936 0.504952)
			(end -0.884936 -0.504952)
			(stroke
				(width 0.1)
				(type default)
			)
			(layer "F.Fab")
		)
		(fp_line
			(start 0.884936 0.504952)
			(end -0.884936 0.504952)
			(stroke
				(width 0.1)
				(type default)
			)
			(layer "F.Fab")
		)
		(fp_line
			(start -0.884936 -0.504952)
			(end 0.884936 -0.504952)
			(stroke
				(width 0.1)
				(type default)
			)
			(layer "F.Fab")
		)
		(fp_line
			(start 0.884936 -0.504952)
			(end 0.884936 0.504952)
			(stroke
				(width 0.1)
				(type default)
			)
			(layer "F.Fab")
		)
		(pad "1" smd rect
			(at 0.7366 0)
			(size 0.7112 0.8128)
			(layers "F.Cu" "F.Mask" "F.Paste")
			(net "P12V")
		)
		(pad "2" smd rect
			(at -0.7366 0)
			(size 0.7112 0.8128)
			(layers "F.Cu" "F.Mask" "F.Paste")
			(net "GND")
		)
	)
	(footprint ""
		(layer "F.Cu")
		(at 342.965278 -21.78304 90)
		(property "Reference" "R36"
			(at 3.227578 -56.835548 90)
			(unlocked yes)
			(layer "F.SilkS")
			(effects
				(font
					(size 0.7874 0.5842)
					(thickness 0.1524)
				)
				(justify left)
			)
		)
		(property "Value" ""
			(at 0 0 90)
			(layer "F.Fab")
			(effects
				(font
					(size 1.27 1.27)
				)
			)
		)
		(duplicate_pad_numbers_are_jumpers no)
		(fp_line
			(start 0.7874 -0.4064)
			(end 0.7874 0.4064)
			(stroke
				(width 0.1524)
				(type default)
			)
			(layer "F.SilkS")
		)
		(fp_line
			(start -0.7874 -0.4064)
			(end 0.7874 -0.4064)
			(stroke
				(width 0.1524)
				(type default)
			)
			(layer "F.SilkS")
		)
		(fp_line
			(start 0.7874 0.4064)
			(end -0.7874 0.4064)
			(stroke
				(width 0.1524)
				(type default)
			)
			(layer "F.SilkS")
		)
		(fp_line
			(start -0.7874 0.4064)
			(end -0.7874 -0.4064)
			(stroke
				(width 0.1524)
				(type default)
			)
			(layer "F.SilkS")
		)
		(fp_poly
			(pts
				(xy -0.508 0.2794) (xy -0.508 0.2286) (xy -0.635 0.2286) (xy -0.635 -0.254) (xy -0.5334 -0.254)
				(xy -0.5334 -0.2794) (xy 0.5334 -0.2794) (xy 0.5334 -0.254) (xy 0.635 -0.254) (xy 0.635 0.254) (xy 0.5334 0.254)
				(xy 0.5334 0.2794)
			)
			(stroke
				(width 0)
				(type default)
			)
			(fill no)
			(layer "F.CrtYd")
		)
		(pad "1" smd rect
			(at 0.40005 0 90)
			(size 0.4572 0.508)
			(layers "F.Cu" "F.Mask" "F.Paste")
			(net "GND")
		)
		(pad "2" smd rect
			(at -0.40005 0 90)
			(size 0.4572 0.508)
			(layers "F.Cu" "F.Mask" "F.Paste")
			(net "BLADE2_MATED_N")
		)
	)
	(footprint ""
		(layer "F.Cu")
		(at 92.16644 -27.574494)
		(property "Reference" "R12"
			(at -7.112 0.593852 0)
			(unlocked yes)
			(layer "F.SilkS")
			(effects
				(font
					(size 0.7874 0.5842)
					(thickness 0.1524)
				)
				(justify left)
			)
		)
		(property "Value" ""
			(at 0 0 0)
			(layer "F.Fab")
			(effects
				(font
					(size 1.27 1.27)
				)
			)
		)
		(duplicate_pad_numbers_are_jumpers no)
		(fp_line
			(start -0.7874 -0.4064)
			(end 0.7874 -0.4064)
			(stroke
				(width 0.1524)
				(type default)
			)
			(layer "F.SilkS")
		)
		(fp_line
			(start -0.7874 0.4064)
			(end -0.7874 -0.4064)
			(stroke
				(width 0.1524)
				(type default)
			)
			(layer "F.SilkS")
		)
		(fp_line
			(start 0.7874 -0.4064)
			(end 0.7874 0.4064)
			(stroke
				(width 0.1524)
				(type default)
			)
			(layer "F.SilkS")
		)
		(fp_line
			(start 0.7874 0.4064)
			(end -0.7874 0.4064)
			(stroke
				(width 0.1524)
				(type default)
			)
			(layer "F.SilkS")
		)
		(fp_poly
			(pts
				(xy -0.508 0.2794) (xy -0.508 0.2286) (xy -0.635 0.2286) (xy -0.635 -0.254) (xy -0.5334 -0.254)
				(xy -0.5334 -0.2794) (xy 0.5334 -0.2794) (xy 0.5334 -0.254) (xy 0.635 -0.254) (xy 0.635 0.254) (xy 0.5334 0.254)
				(xy 0.5334 0.2794)
			)
			(stroke
				(width 0)
				(type default)
			)
			(fill no)
			(layer "F.CrtYd")
		)
		(pad "1" smd rect
			(at 0.40005 0)
			(size 0.4572 0.508)
			(layers "F.Cu" "F.Mask" "F.Paste")
			(net "P3V3_BLAD1")
		)
		(pad "2" smd rect
			(at -0.40005 0)
			(size 0.4572 0.508)
			(layers "F.Cu" "F.Mask" "F.Paste")
			(net "ENET10G_2_RS0")
		)
	)
	(footprint ""
		(layer "F.Cu")
		(at 367.538 -3.1242 90)
		(property "Reference" "C26"
			(at -2.3368 2.194052 90)
			(unlocked yes)
			(layer "F.SilkS")
			(effects
				(font
					(size 0.7874 0.5842)
					(thickness 0.1524)
				)
				(justify left)
			)
		)
		(property "Value" ""
			(at 0 0 90)
			(layer "F.Fab")
			(effects
				(font
					(size 1.27 1.27)
				)
			)
		)
		(duplicate_pad_numbers_are_jumpers no)
		(fp_line
			(start 0.7874 -0.4064)
			(end 0.7874 0.4064)
			(stroke
				(width 0.1524)
				(type default)
			)
			(layer "F.SilkS")
		)
		(fp_line
			(start -0.7874 -0.4064)
			(end 0.7874 -0.4064)
			(stroke
				(width 0.1524)
				(type default)
			)
			(layer "F.SilkS")
		)
		(fp_line
			(start 0 0.381)
			(end 0 -0.381)
			(stroke
				(width 0.1524)
				(type default)
			)
			(layer "F.SilkS")
		)
		(fp_line
			(start 0.7874 0.4064)
			(end -0.7874 0.4064)
			(stroke
				(width 0.1524)
				(type default)
			)
			(layer "F.SilkS")
		)
		(fp_line
			(start -0.7874 0.4064)
			(end -0.7874 -0.4064)
			(stroke
				(width 0.1524)
				(type default)
			)
			(layer "F.SilkS")
		)
		(fp_poly
			(pts
				(xy -0.5334 0.254) (xy -0.635 0.254) (xy -0.635 0.2286) (xy -0.635 -0.254) (xy -0.5334 -0.254) (xy -0.5334 -0.2794)
				(xy 0.5334 -0.2794) (xy 0.5334 -0.254) (xy 0.635 -0.254) (xy 0.635 0.254) (xy 0.5334 0.254) (xy 0.5334 0.2794)
				(xy -0.508 0.2794) (xy -0.5334 0.2794)
			)
			(stroke
				(width 0)
				(type default)
			)
			(fill no)
			(layer "F.CrtYd")
		)
		(pad "1" smd rect
			(at 0.40005 0 90)
			(size 0.4572 0.508)
			(layers "F.Cu" "F.Mask" "F.Paste")
			(net "P3V3_10G_3_VCCT")
		)
		(pad "2" smd rect
			(at -0.40005 0 90)
			(size 0.4572 0.508)
			(layers "F.Cu" "F.Mask" "F.Paste")
			(net "GND")
		)
	)
	(footprint ""
		(layer "F.Cu")
		(at 28.437332 -19.7358 -90)
		(property "Reference" "R84"
			(at 0.9144 -5.110988 90)
			(unlocked yes)
			(layer "F.SilkS")
			(effects
				(font
					(size 0.7874 0.5842)
					(thickness 0.1524)
				)
				(justify left)
			)
		)
		(property "Value" ""
			(at 0 0 270)
			(layer "F.Fab")
			(effects
				(font
					(size 1.27 1.27)
				)
			)
		)
		(duplicate_pad_numbers_are_jumpers no)
		(fp_line
			(start -0.7874 0.4064)
			(end -0.7874 -0.4064)
			(stroke
				(width 0.1524)
				(type default)
			)
			(layer "F.SilkS")
		)
		(fp_line
			(start 0.7874 0.4064)
			(end -0.7874 0.4064)
			(stroke
				(width 0.1524)
				(type default)
			)
			(layer "F.SilkS")
		)
		(fp_line
			(start -0.7874 -0.4064)
			(end 0.7874 -0.4064)
			(stroke
				(width 0.1524)
				(type default)
			)
			(layer "F.SilkS")
		)
		(fp_line
			(start 0.7874 -0.4064)
			(end 0.7874 0.4064)
			(stroke
				(width 0.1524)
				(type default)
			)
			(layer "F.SilkS")
		)
		(fp_poly
			(pts
				(xy -0.508 0.2794) (xy -0.508 0.2286) (xy -0.635 0.2286) (xy -0.635 -0.254) (xy -0.5334 -0.254)
				(xy -0.5334 -0.2794) (xy 0.5334 -0.2794) (xy 0.5334 -0.254) (xy 0.635 -0.254) (xy 0.635 0.254) (xy 0.5334 0.254)
				(xy 0.5334 0.2794)
			)
			(stroke
				(width 0)
				(type default)
			)
			(fill no)
			(layer "F.CrtYd")
		)
		(pad "1" smd rect
			(at 0.40005 0 270)
			(size 0.4572 0.508)
			(layers "F.Cu" "F.Mask" "F.Paste")
			(net "N39386877")
		)
		(pad "2" smd rect
			(at -0.40005 0 270)
			(size 0.4572 0.508)
			(layers "F.Cu" "F.Mask" "F.Paste")
			(net "P12V")
		)
	)
	(footprint ""
		(layer "F.Cu")
		(at 313.07024 -30.368494)
		(property "Reference" "R18"
			(at -6.5532 -0.676148 0)
			(unlocked yes)
			(layer "F.SilkS")
			(effects
				(font
					(size 0.7874 0.5842)
					(thickness 0.1524)
				)
				(justify left)
			)
		)
		(property "Value" ""
			(at 0 0 0)
			(layer "F.Fab")
			(effects
				(font
					(size 1.27 1.27)
				)
			)
		)
		(duplicate_pad_numbers_are_jumpers no)
		(fp_line
			(start -0.7874 -0.4064)
			(end 0.7874 -0.4064)
			(stroke
				(width 0.1524)
				(type default)
			)
			(layer "F.SilkS")
		)
		(fp_line
			(start -0.7874 0.4064)
			(end -0.7874 -0.4064)
			(stroke
				(width 0.1524)
				(type default)
			)
			(layer "F.SilkS")
		)
		(fp_line
			(start 0.7874 -0.4064)
			(end 0.7874 0.4064)
			(stroke
				(width 0.1524)
				(type default)
			)
			(layer "F.SilkS")
		)
		(fp_line
			(start 0.7874 0.4064)
			(end -0.7874 0.4064)
			(stroke
				(width 0.1524)
				(type default)
			)
			(layer "F.SilkS")
		)
		(fp_poly
			(pts
				(xy -0.508 0.2794) (xy -0.508 0.2286) (xy -0.635 0.2286) (xy -0.635 -0.254) (xy -0.5334 -0.254)
				(xy -0.5334 -0.2794) (xy 0.5334 -0.2794) (xy 0.5334 -0.254) (xy 0.635 -0.254) (xy 0.635 0.254) (xy 0.5334 0.254)
				(xy 0.5334 0.2794)
			)
			(stroke
				(width 0)
				(type default)
			)
			(fill no)
			(layer "F.CrtYd")
		)
		(pad "1" smd rect
			(at 0.40005 0)
			(size 0.4572 0.508)
			(layers "F.Cu" "F.Mask" "F.Paste")
			(net "P3V3_BLAD2")
		)
		(pad "2" smd rect
			(at -0.40005 0)
			(size 0.4572 0.508)
			(layers "F.Cu" "F.Mask" "F.Paste")
			(net "ENET10G_4_TX_FAULT")
		)
	)
	(footprint ""
		(layer "F.Cu")
		(at 375.82856 -24.906478 180)
		(property "Reference" "R19"
			(at -33.81248 -16.726408 0)
			(unlocked yes)
			(layer "F.SilkS")
			(effects
				(font
					(size 0.7874 0.5842)
					(thickness 0.1524)
				)
				(justify left)
			)
		)
		(property "Value" ""
			(at 0 0 180)
			(layer "F.Fab")
			(effects
				(font
					(size 1.27 1.27)
				)
			)
		)
		(duplicate_pad_numbers_are_jumpers no)
		(fp_line
			(start 0.7874 0.4064)
			(end -0.7874 0.4064)
			(stroke
				(width 0.1524)
				(type default)
			)
			(layer "F.SilkS")
		)
		(fp_line
			(start 0.7874 -0.4064)
			(end 0.7874 0.4064)
			(stroke
				(width 0.1524)
				(type default)
			)
			(layer "F.SilkS")
		)
		(fp_line
			(start -0.7874 0.4064)
			(end -0.7874 -0.4064)
			(stroke
				(width 0.1524)
				(type default)
			)
			(layer "F.SilkS")
		)
		(fp_line
			(start -0.7874 -0.4064)
			(end 0.7874 -0.4064)
			(stroke
				(width 0.1524)
				(type default)
			)
			(layer "F.SilkS")
		)
		(fp_poly
			(pts
				(xy -0.508 0.2794) (xy -0.508 0.2286) (xy -0.635 0.2286) (xy -0.635 -0.254) (xy -0.5334 -0.254)
				(xy -0.5334 -0.2794) (xy 0.5334 -0.2794) (xy 0.5334 -0.254) (xy 0.635 -0.254) (xy 0.635 0.254) (xy 0.5334 0.254)
				(xy 0.5334 0.2794)
			)
			(stroke
				(width 0)
				(type default)
			)
			(fill no)
			(layer "F.CrtYd")
		)
		(pad "1" smd rect
			(at 0.40005 0 180)
			(size 0.4572 0.508)
			(layers "F.Cu" "F.Mask" "F.Paste")
			(net "P3V3_BLAD2")
		)
		(pad "2" smd rect
			(at -0.40005 0 180)
			(size 0.4572 0.508)
			(layers "F.Cu" "F.Mask" "F.Paste")
			(net "ENET10G_3_TX_DIS")
		)
	)
	(footprint ""
		(layer "F.Cu")
		(at 84.328 -33.7058 90)
		(property "Reference" "L2"
			(at -0.6096 -2.56413 90)
			(unlocked yes)
			(layer "F.SilkS")
			(effects
				(font
					(size 0.7874 0.5842)
					(thickness 0.1524)
				)
				(justify left)
			)
		)
		(property "Value" ""
			(at 0 0 90)
			(layer "F.Fab")
			(effects
				(font
					(size 1.27 1.27)
				)
			)
		)
		(duplicate_pad_numbers_are_jumpers no)
		(fp_line
			(start -1.905 -0.8636)
			(end 1.905 -0.8636)
			(stroke
				(width 0.1524)
				(type default)
			)
			(layer "F.SilkS")
		)
		(fp_line
			(start 1.905 0.8382)
			(end 1.905 -0.8382)
			(stroke
				(width 0.1524)
				(type default)
			)
			(layer "F.SilkS")
		)
		(fp_line
			(start 0.127 0.8382)
			(end 0.127 -0.8382)
			(stroke
				(width 0.1524)
				(type default)
			)
			(layer "F.SilkS")
		)
		(fp_line
			(start -0.127 0.8382)
			(end -0.127 -0.8382)
			(stroke
				(width 0.1524)
				(type default)
			)
			(layer "F.SilkS")
		)
		(fp_line
			(start -1.905 0.8382)
			(end -1.905 -0.8382)
			(stroke
				(width 0.1524)
				(type default)
			)
			(layer "F.SilkS")
		)
		(fp_line
			(start 1.905 0.8636)
			(end -1.905 0.8636)
			(stroke
				(width 0.1524)
				(type default)
			)
			(layer "F.SilkS")
		)
		(fp_rect
			(start -1.524 0.7112)
			(end 1.524 -0.7366)
			(stroke
				(width 0)
				(type default)
			)
			(fill no)
			(layer "F.CrtYd")
		)
		(pad "1" smd rect
			(at 0.94996 0 90)
			(size 1.1176 1.3716)
			(layers "F.Cu" "F.Mask" "F.Paste")
			(net "P3V3_10G_2_VCCT_L")
		)
		(pad "2" smd rect
			(at -0.94996 0 90)
			(size 1.1176 1.3716)
			(layers "F.Cu" "F.Mask" "F.Paste")
			(net "P3V3_10G_2_VCCT")
		)
	)
	(footprint ""
		(layer "B.Cu")
		(at 425.809918 -26.100024)
		(property "Reference" "GNDPAD2"
			(at -3.542284 6.335268 270)
			(unlocked yes)
			(layer "B.SilkS")
			(effects
				(font
					(size 0.7874 0.5842)
					(thickness 0.1524)
				)
				(justify left mirror)
			)
		)
		(property "Value" ""
			(at 0 0 0)
			(layer "B.Fab")
			(effects
				(font
					(size 1.27 1.27)
				)
				(justify mirror)
			)
		)
		(duplicate_pad_numbers_are_jumpers no)
		(fp_poly
			(pts
				(xy 1.3589 5.461) (xy -1.3589 5.461) (xy -1.3589 -5.461) (xy 1.3589 -5.461)
			)
			(stroke
				(width 0)
				(type default)
			)
			(fill no)
			(layer "B.CrtYd")
		)
		(pad "1" smd rect
			(at 0 0 180)
			(size 2.6162 10.8204)
			(layers "B.Cu" "B.Mask" "B.Paste")
			(net "GND")
		)
	)
	(gr_poly
		(pts
			(xy 146.7612 -2.54) (xy 146.7612 -1.651) (xy 146.558 -1.4478) (xy 142.6972 -1.4478) (xy 142.4432 -1.7018)
			(xy 142.4432 -2.7178) (xy 142.621 -2.8956) (xy 146.4056 -2.8956)
		)
		(stroke
			(width 0)
			(type solid)
		)
		(fill yes)
		(layer "F.Cu")
		(net "GND")
	)
	(gr_poly
		(pts
			(xy 160.0454 -27.432) (xy 160.0454 -22.0472) (xy 159.7914 -21.7932) (xy 158.2928 -21.7932) (xy 157.9372 -22.1488)
			(xy 157.9372 -27.3558) (xy 158.3436 -27.7622) (xy 159.7152 -27.7622)
		)
		(stroke
			(width 0)
			(type solid)
		)
		(fill yes)
		(layer "F.Cu")
		(net "GND")
	)
	(gr_poly
		(pts
			(xy 327.6346 -2.1336) (xy 327.6346 -1.5494) (xy 327.3806 -1.2954) (xy 322.6816 -1.2954) (xy 322.4022 -1.5748)
			(xy 322.4022 -2.2098) (xy 322.6308 -2.4384) (xy 327.3298 -2.4384)
		)
		(stroke
			(width 0)
			(type solid)
		)
		(fill yes)
		(layer "F.Cu")
		(net "GND")
	)
	(gr_poly
		(pts
			(xy 380.9492 -28.4226) (xy 380.9492 -22.7076) (xy 380.619 -22.3774) (xy 379.1966 -22.3774) (xy 378.6378 -22.9362)
			(xy 378.6378 -28.4734) (xy 378.9426 -28.7782) (xy 380.5936 -28.7782)
		)
		(stroke
			(width 0)
			(type solid)
		)
		(fill yes)
		(layer "F.Cu")
		(net "GND")
	)
	(gr_poly
		(pts
			(xy 426.212 -29.7688) (xy 426.212 -20.0406) (xy 425.8056 -19.6342) (xy 424.9928 -19.6342) (xy 424.6626 -19.9644)
			(xy 424.6626 -29.591) (xy 425.0944 -30.0228) (xy 425.958 -30.0228)
		)
		(stroke
			(width 0)
			(type solid)
		)
		(fill yes)
		(layer "F.Cu")
		(net "GND")
	)
	(gr_poly
		(pts
			(xy 31.7754 -15.9004) (xy 31.7754 -14.6304) (xy 31.496 -14.351) (xy 26.67 -14.351) (xy 25.7048 -14.351)
			(xy 25.4508 -14.605) (xy 25.4508 -16.002) (xy 25.6032 -16.1544) (xy 26.7462 -16.1544) (xy 31.5214 -16.1544)
		)
		(stroke
			(width 0)
			(type solid)
		)
		(fill yes)
		(layer "F.Cu")
		(net "GND")
	)
	(gr_poly
		(pts
			(xy 106.5276 -2.5908) (xy 106.5276 -1.6002) (xy 106.2482 -1.3208) (xy 102.0572 -1.3208) (xy 101.9302 -1.4478)
			(xy 101.9302 -2.6162) (xy 102.1207 -2.8067) (xy 104.2035 -2.8067) (xy 104.2162 -2.8194) (xy 106.299 -2.8194)
		)
		(stroke
			(width 0)
			(type solid)
		)
		(fill yes)
		(layer "F.Cu")
		(net "GND")
	)
	(gr_poly
		(pts
			(xy 155.7782 -43.8912) (xy 155.7782 -28.0924) (xy 154.7368 -27.051) (xy 154.7368 -21.9964) (xy 154.4574 -21.717)
			(xy 152.146 -21.717) (xy 151.6126 -22.2504) (xy 151.6126 -43.688) (xy 152.1714 -44.2468) (xy 155.4226 -44.2468)
		)
		(stroke
			(width 0)
			(type solid)
		)
		(fill yes)
		(layer "F.Cu")
		(net "P3V3_BLAD1")
	)
	(gr_poly
		(pts
			(xy 376.7836 -44.1452) (xy 376.7836 -29.21) (xy 375.666 -28.0924) (xy 375.666 -22.7584) (xy 375.3358 -22.4282)
			(xy 372.6688 -22.4282) (xy 372.1354 -22.9616) (xy 372.1354 -43.942) (xy 372.7958 -44.6024) (xy 376.3264 -44.6024)
		)
		(stroke
			(width 0)
			(type solid)
		)
		(fill yes)
		(layer "F.Cu")
		(net "P3V3_BLAD2")
	)
	(gr_poly
		(pts
			(xy 95.6564 -38.862) (xy 95.6564 -26.2128) (xy 95.0722 -25.6286) (xy 92.7354 -25.6286) (xy 92.2655 -26.0985)
			(xy 92.2655 -27.0891) (xy 92.2528 -27.1018) (xy 92.2528 -29.4894) (xy 91.4146 -30.3276) (xy 91.4146 -38.989)
			(xy 91.7194 -39.2938) (xy 95.2246 -39.2938)
		)
		(stroke
			(width 0)
			(type solid)
		)
		(fill yes)
		(layer "F.Cu")
		(net "P3V3_BLAD1")
	)
	(gr_poly
		(pts
			(xy 316.3824 -39.37) (xy 316.3824 -26.0096) (xy 316.1284 -25.7556) (xy 313.4106 -25.7556) (xy 313.2455 -25.9207)
			(xy 313.2455 -27.3431) (xy 313.2328 -27.3558) (xy 313.2328 -30.6324) (xy 312.3438 -31.5214) (xy 312.3438 -39.4208)
			(xy 312.8264 -39.9034) (xy 315.849 -39.9034)
		)
		(stroke
			(width 0)
			(type solid)
		)
		(fill yes)
		(layer "F.Cu")
		(net "P3V3_BLAD2")
	)
	(gr_poly
		(pts
			(arc
				(start 366.348772 -3.046476)
				(mid 366.384492 -3.042605)
				(end 366.4204 -3.041396)
			)
			(xy 367.722404 -3.041396) (xy 367.919 -2.8448) (xy 367.919 -1.9304) (xy 367.6142 -1.6256) (xy 363.982 -1.6256)
			(xy 363.728 -1.8796) (xy 363.728 -2.8702) (xy 363.873796 -3.015996)
			(arc
				(start 365.2266 -3.015996)
				(mid 365.304985 -3.022359)
				(end 365.381286 -3.041396)
			)
			(xy 365.401098 -3.048) (xy 366.339374 -3.048)
		)
		(stroke
			(width 0)
			(type solid)
		)
		(fill yes)
		(layer "F.Cu")
		(net "GND")
	)
	(gr_poly
		(pts
			(xy 94.6658 -21.0058) (xy 94.6658 -2.6162) (xy 93.6752 -1.6256) (xy 90.3986 -1.6256) (xy 89.3064 -2.7178)
			(arc
				(start 89.3064 -7.890256)
				(mid 89.340595 -7.976699)
				(end 89.42451 -8.016748)
			)
			(arc
				(start 89.42451 -8.016748)
				(mid 90.806892 -9.499845)
				(end 89.42451 -10.982706)
			)
			(arc
				(start 89.42451 -10.982706)
				(mid 89.340554 -11.022716)
				(end 89.3064 -11.109198)
			)
			(xy 89.3064 -15.5448) (xy 86.9696 -17.8816) (xy 86.9696 -22.7584) (xy 87.4014 -23.1902) (xy 92.4814 -23.1902)
		)
		(stroke
			(width 0)
			(type solid)
		)
		(fill yes)
		(layer "F.Cu")
		(net "P12V")
	)
	(gr_poly
		(pts
			(xy 202.972924 -43.699176) (xy 203.374752 -43.699176) (xy 203.374752 -41.463976) (xy 202.972924 -41.463976)
			(xy 202.972924 -28.687776) (xy 203.374752 -28.687776) (xy 203.374752 -26.477976) (xy 202.972924 -26.477976)
			(xy 202.972924 -19.910044) (xy 196.059552 -19.910044) (xy 196.059552 -22.020022) (xy 200.402952 -22.020022)
			(xy 200.396856 -26.300176) (xy 199.818752 -26.300176) (xy 199.818752 -28.890976) (xy 200.393046 -28.890976)
			(xy 200.387458 -32.675576) (xy 199.920352 -32.675576) (xy 199.920352 -34.529776) (xy 200.384918 -34.529776)
			(xy 200.375012 -41.311576) (xy 199.818752 -41.311576) (xy 199.818752 -43.826176) (xy 200.371456 -43.826176)
			(xy 200.371456 -43.851576) (xy 200.3679 -46.1899) (xy 182.622952 -46.1899) (xy 182.622952 -22.020022)
			(xy 187.144152 -22.020022) (xy 187.347352 -22.020022) (xy 187.347352 -19.924776) (xy 187.347352 -19.910044)
			(xy 187.144152 -19.910044) (xy 177.060352 -19.910044) (xy 177.060352 -22.020022) (xy 181.352952 -22.020022)
			(xy 181.352952 -46.1899) (xy 163.608004 -46.1899) (xy 163.61029 -43.851576) (xy 164.157152 -43.851576)
			(xy 164.157152 -41.336976) (xy 163.61283 -41.336976) (xy 163.61283 -34.504376) (xy 164.055552 -34.504376)
			(xy 164.055552 -32.675576) (xy 163.61283 -32.675576) (xy 163.61283 -28.840176) (xy 164.157152 -28.840176)
			(xy 164.157152 -26.325576) (xy 163.61283 -26.325576) (xy 163.61283 -22.020022) (xy 168.119552 -22.020022)
			(xy 168.322752 -22.020022) (xy 168.322752 -19.924776) (xy 168.322752 -19.910044) (xy 168.119552 -19.910044)
			(xy 161.00298 -19.910044) (xy 161.00298 -26.477976) (xy 160.595818 -26.477976) (xy 160.595818 -28.713176)
			(xy 161.00298 -28.713176) (xy 161.00298 -33.589976) (xy 161.00298 -41.463976) (xy 160.595818 -41.463976)
			(xy 160.595818 -43.699176) (xy 161.00298 -43.699176) (xy 161.00298 -50.390044) (xy 202.972924 -50.390044)
		)
		(stroke
			(width 0)
			(type solid)
		)
		(fill yes)
		(layer "F.Cu")
		(net "GND")
	)
	(gr_poly
		(pts
			(xy 423.97299 -43.699176) (xy 424.374818 -43.699176) (xy 424.374818 -41.463976) (xy 423.97299 -41.463976)
			(xy 423.97299 -28.687776) (xy 424.374818 -28.687776) (xy 424.374818 -26.477976) (xy 423.97299 -26.477976)
			(xy 423.97299 -19.910044) (xy 417.059618 -19.910044) (xy 417.059618 -22.020022) (xy 421.403018 -22.020022)
			(xy 421.396922 -26.300176) (xy 420.818818 -26.300176) (xy 420.818818 -28.890976) (xy 421.393112 -28.890976)
			(xy 421.387524 -32.675576) (xy 420.920418 -32.675576) (xy 420.920418 -34.529776) (xy 421.384984 -34.529776)
			(xy 421.375078 -41.311576) (xy 420.818818 -41.311576) (xy 420.818818 -43.826176) (xy 421.371522 -43.826176)
			(xy 421.371522 -43.851576) (xy 421.367966 -46.1899) (xy 403.623018 -46.1899) (xy 403.623018 -22.020022)
			(xy 408.144218 -22.020022) (xy 408.347418 -22.020022) (xy 408.347418 -19.924776) (xy 408.347418 -19.910044)
			(xy 408.144218 -19.910044) (xy 398.060418 -19.910044) (xy 398.060418 -22.020022) (xy 402.353018 -22.020022)
			(xy 402.353018 -46.1899) (xy 384.60807 -46.1899) (xy 384.610356 -43.851576) (xy 385.157218 -43.851576)
			(xy 385.157218 -41.336976) (xy 384.612896 -41.336976) (xy 384.612896 -34.504376) (xy 385.055618 -34.504376)
			(xy 385.055618 -32.675576) (xy 384.612896 -32.675576) (xy 384.612896 -28.840176) (xy 385.157218 -28.840176)
			(xy 385.157218 -26.325576) (xy 384.612896 -26.325576) (xy 384.612896 -22.020022) (xy 389.119618 -22.020022)
			(xy 389.322818 -22.020022) (xy 389.322818 -19.924776) (xy 389.322818 -19.910044) (xy 389.119618 -19.910044)
			(xy 382.003046 -19.910044) (xy 382.003046 -26.477976) (xy 381.595884 -26.477976) (xy 381.595884 -28.713176)
			(xy 382.003046 -28.713176) (xy 382.003046 -33.589976) (xy 382.003046 -41.463976) (xy 381.595884 -41.463976)
			(xy 381.595884 -43.699176) (xy 382.003046 -43.699176) (xy 382.003046 -50.390044) (xy 423.97299 -50.390044)
		)
		(stroke
			(width 0)
			(type solid)
		)
		(fill yes)
		(layer "F.Cu")
		(net "GND")
	)
	(gr_poly
		(pts
			(xy 351.1042 -26.8224)
			(arc
				(start 351.1042 -22.667976)
				(mid 351.067003 -22.578173)
				(end 350.9772 -22.540976)
			)
			(xy 350.896174 -22.540976)
			(arc
				(start 350.880172 -22.54504)
				(mid 350.777302 -22.558527)
				(end 350.674432 -22.54504)
			)
			(xy 350.65843 -22.540976)
			(arc
				(start 350.4438 -22.540976)
				(mid 350.353997 -22.578173)
				(end 350.3168 -22.667976)
			)
			(xy 350.3168 -23.114) (xy 349.7199 -23.7109) (xy 345.1733 -23.7109) (xy 345.036394 -23.573994)
			(arc
				(start 345.011502 -23.564342)
				(mid 344.715628 -23.223579)
				(end 344.8304 -22.787102)
			)
			(xy 344.8304 -22.0218) (xy 344.5764 -21.7678) (xy 343.9668 -21.7678) (xy 343.789 -21.9456) (xy 343.789 -22.5171)
			(xy 343.42705 -22.87905) (xy 341.91575 -22.87905) (xy 341.2744 -23.5204) (xy 341.12454 -23.5204)
			(xy 341.098886 -23.546308)
			(arc
				(start 340.4616 -23.546308)
				(mid 340.175374 -23.452328)
				(end 340.00059 -23.206964)
			)
			(xy 339.991192 -23.176992) (xy 339.2932 -22.479) (xy 339.2932 -22.235922)
			(arc
				(start 338.564728 -21.50745)
				(mid 338.474976 -21.470385)
				(end 338.38515 -21.50745)
			)
			(xy 338.3026 -21.59) (xy 338.3026 -26.924) (xy 338.6836 -27.305) (xy 350.6216 -27.305)
		)
		(stroke
			(width 0)
			(type solid)
		)
		(fill yes)
		(layer "F.Cu")
		(net "P3V3_BLAD2")
	)
	(gr_poly
		(pts
			(xy 130.2766 -28.0924) (xy 130.2766 -27.0764) (xy 129.9972 -26.797)
			(arc
				(start 129.9972 -22.863302)
				(mid 129.923254 -22.684146)
				(end 129.74447 -22.609302)
			)
			(arc
				(start 129.74447 -22.609302)
				(mid 129.693622 -22.605788)
				(end 129.643632 -22.59584)
			)
			(xy 129.62763 -22.591776) (xy 129.390648 -22.591776) (xy 129.390648 -22.39264)
			(arc
				(start 129.37998 -22.36851)
				(mid 129.355638 -22.291051)
				(end 129.347468 -22.210268)
			)
			(arc
				(start 129.347468 -22.0218)
				(mid 129.310271 -21.931997)
				(end 129.220468 -21.8948)
			)
			(arc
				(start 128.966722 -21.8948)
				(mid 128.786848 -21.969464)
				(end 128.712722 -22.149562)
			)
			(xy 128.712976 -22.150832) (xy 128.712976 -22.492716)
			(arc
				(start 128.78943 -22.56917)
				(mid 128.78943 -23.25243)
				(end 128.10617 -23.25243)
			)
			(xy 127.74676 -22.89302)
			(arc
				(start 127.74676 -22.76094)
				(mid 127.709547 -22.671227)
				(end 127.61976 -22.63394)
			)
			(arc
				(start 127.141732 -22.63394)
				(mid 126.966621 -22.601068)
				(end 126.815342 -22.50694)
			)
			(xy 126.760224 -22.50694) (xy 126.760224 -22.449536)
			(arc
				(start 126.739142 -22.417786)
				(mid 126.679114 -22.289623)
				(end 126.658878 -22.149562)
			)
			(arc
				(start 126.658878 -22.149562)
				(mid 126.584753 -21.969464)
				(end 126.404878 -21.8948)
			)
			(xy 125.6284 -21.8948) (xy 124.0917 -23.4315) (xy 123.4186 -23.4315) (xy 123.27255 -23.28545) (xy 123.27255 -22.00275)
			(xy 123.063 -21.7932) (xy 122.1994 -21.7932) (xy 122.0089 -21.9837) (xy 122.0089 -23.6347) (xy 121.666 -23.9776)
			(xy 119.7102 -23.9776) (xy 118.370858 -22.638258)
			(arc
				(start 118.333774 -22.630638)
				(mid 118.043937 -22.387493)
				(end 118.08714 -22.01164)
			)
			(xy 118.11 -21.978874)
			(arc
				(start 118.11 -21.9202)
				(mid 118.072803 -21.830397)
				(end 117.983 -21.7932)
			)
			(xy 117.7544 -21.7932) (xy 117.475 -22.0726) (xy 117.475 -28.0416) (xy 117.9068 -28.4734) (xy 129.8956 -28.4734)
		)
		(stroke
			(width 0)
			(type solid)
		)
		(fill yes)
		(layer "F.Cu")
		(net "P3V3_BLAD1")
	)
	(gr_poly
		(pts
			(xy 355.3333 -48.7553) (xy 369.5319 -48.7553) (xy 371.2972 -46.99) (xy 371.2972 -24.9428) (xy 369.7478 -23.3934)
			(xy 357.3018 -23.3934) (xy 354.933504 -25.761696) (xy 351.3074 -29.3878) (xy 351.3074 -38.3794) (xy 350.1136 -39.5732)
			(xy 340.5632 -39.5732) (xy 338.8614 -37.8714) (xy 338.8614 -29.0322) (xy 338.7979 -28.9687) (xy 338.7979 -28.8925)
			(xy 333.4258 -23.5204) (xy 308.4068 -23.5204) (xy 307.2384 -24.6888) (xy 307.2384 -30.6705) (xy 307.529992 -30.962092)
			(xy 309.778908 -30.962092) (xy 310.134 -30.607) (xy 310.134 -25.8064) (xy 310.515 -25.4254) (xy 316.6872 -25.4254)
			(xy 317.627 -26.3652) (xy 317.627 -44.933038) (xy 336.785706 -44.933038) (xy 336.785706 -44.805162)
			(xy 336.793735 -44.677538) (xy 336.809763 -44.55067) (xy 336.833724 -44.425058) (xy 336.865526 -44.3012)
			(xy 336.905042 -44.179582) (xy 336.952116 -44.060685) (xy 337.006563 -43.944979) (xy 337.068168 -43.83292)
			(xy 337.136688 -43.724951) (xy 337.211852 -43.621497) (xy 337.293363 -43.522966) (xy 337.3809 -43.429748)
			(xy 337.474118 -43.342211) (xy 337.572649 -43.2607) (xy 337.676103 -43.185536) (xy 337.784072 -43.117016)
			(xy 337.896131 -43.055411) (xy 338.011837 -43.000964) (xy 338.130734 -42.95389) (xy 338.252352 -42.914374)
			(xy 338.37621 -42.882572) (xy 338.501822 -42.858611) (xy 338.62869 -42.842583) (xy 338.756314 -42.834554)
			(xy 338.820252 -42.834052) (xy 338.88419 -42.834554) (xy 339.011814 -42.842583) (xy 339.138682 -42.858611)
			(xy 339.264294 -42.882572) (xy 339.388152 -42.914374) (xy 339.50977 -42.95389) (xy 339.628667 -43.000964)
			(xy 339.744373 -43.055411) (xy 339.856432 -43.117016) (xy 339.964401 -43.185536) (xy 340.067855 -43.2607)
			(xy 340.166386 -43.342211) (xy 340.259604 -43.429748) (xy 340.347141 -43.522966) (xy 340.428652 -43.621497)
			(xy 340.503816 -43.724951) (xy 340.572336 -43.83292) (xy 340.633941 -43.944979) (xy 340.688388 -44.060685)
			(xy 340.735462 -44.179582) (xy 340.774978 -44.3012) (xy 340.80678 -44.425058) (xy 340.830741 -44.55067)
			(xy 340.846769 -44.677538) (xy 340.854798 -44.805162) (xy 340.854798 -44.932982) (xy 348.217484 -44.932982)
			(xy 348.217484 -44.805218) (xy 348.225506 -44.677705) (xy 348.241519 -44.550948) (xy 348.26546 -44.425446)
			(xy 348.297234 -44.301696) (xy 348.336715 -44.180184) (xy 348.383748 -44.061392) (xy 348.438148 -43.945787)
			(xy 348.499699 -43.833826) (xy 348.568159 -43.725951) (xy 348.643257 -43.622587) (xy 348.724697 -43.524142)
			(xy 348.812158 -43.431006) (xy 348.905294 -43.343545) (xy 349.003739 -43.262105) (xy 349.107103 -43.187007)
			(xy 349.214978 -43.118547) (xy 349.326939 -43.056996) (xy 349.442544 -43.002596) (xy 349.561336 -42.955563)
			(xy 349.682848 -42.916082) (xy 349.806598 -42.884308) (xy 349.9321 -42.860367) (xy 350.058857 -42.844354)
			(xy 350.18637 -42.836332) (xy 350.250252 -42.83583) (xy 350.314134 -42.836332) (xy 350.441647 -42.844354)
			(xy 350.568404 -42.860367) (xy 350.693906 -42.884308) (xy 350.817656 -42.916082) (xy 350.939168 -42.955563)
			(xy 351.05796 -43.002596) (xy 351.173565 -43.056996) (xy 351.285526 -43.118547) (xy 351.393401 -43.187007)
			(xy 351.496765 -43.262105) (xy 351.59521 -43.343545) (xy 351.688346 -43.431006) (xy 351.775807 -43.524142)
			(xy 351.857247 -43.622587) (xy 351.932345 -43.725951) (xy 352.000805 -43.833826) (xy 352.062356 -43.945787)
			(xy 352.116756 -44.061392) (xy 352.163789 -44.180184) (xy 352.20327 -44.301696) (xy 352.235044 -44.425446)
			(xy 352.258985 -44.550948) (xy 352.274998 -44.677705) (xy 352.28302 -44.805218) (xy 352.28302 -44.932982)
			(xy 352.274998 -45.060495) (xy 352.258985 -45.187252) (xy 352.235044 -45.312754) (xy 352.20327 -45.436504)
			(xy 352.163789 -45.558016) (xy 352.116756 -45.676808) (xy 352.062356 -45.792413) (xy 352.000805 -45.904374)
			(xy 351.932345 -46.012249) (xy 351.857247 -46.115613) (xy 351.775807 -46.214058) (xy 351.688346 -46.307194)
			(xy 351.59521 -46.394655) (xy 351.496765 -46.476095) (xy 351.393401 -46.551193) (xy 351.285526 -46.619653)
			(xy 351.173565 -46.681204) (xy 351.05796 -46.735604) (xy 350.939168 -46.782637) (xy 350.817656 -46.822118)
			(xy 350.693906 -46.853892) (xy 350.568404 -46.877833) (xy 350.441647 -46.893846) (xy 350.314134 -46.901868)
			(xy 350.18637 -46.901868) (xy 350.058857 -46.893846) (xy 349.9321 -46.877833) (xy 349.806598 -46.853892)
			(xy 349.682848 -46.822118) (xy 349.561336 -46.782637) (xy 349.442544 -46.735604) (xy 349.326939 -46.681204)
			(xy 349.214978 -46.619653) (xy 349.107103 -46.551193) (xy 349.003739 -46.476095) (xy 348.905294 -46.394655)
			(xy 348.812158 -46.307194) (xy 348.724697 -46.214058) (xy 348.643257 -46.115613) (xy 348.568159 -46.012249)
			(xy 348.499699 -45.904374) (xy 348.438148 -45.792413) (xy 348.383748 -45.676808) (xy 348.336715 -45.558016)
			(xy 348.297234 -45.436504) (xy 348.26546 -45.312754) (xy 348.241519 -45.187252) (xy 348.225506 -45.060495)
			(xy 348.217484 -44.932982) (xy 340.854798 -44.932982) (xy 340.854798 -44.933038) (xy 340.846769 -45.060662)
			(xy 340.830741 -45.18753) (xy 340.80678 -45.313142) (xy 340.774978 -45.437) (xy 340.735462 -45.558618)
			(xy 340.688388 -45.677515) (xy 340.633941 -45.793221) (xy 340.572336 -45.90528) (xy 340.503816 -46.013249)
			(xy 340.428652 -46.116703) (xy 340.347141 -46.215234) (xy 340.259604 -46.308452) (xy 340.166386 -46.395989)
			(xy 340.067855 -46.4775) (xy 339.964401 -46.552664) (xy 339.856432 -46.621184) (xy 339.744373 -46.682789)
			(xy 339.628667 -46.737236) (xy 339.50977 -46.78431) (xy 339.388152 -46.823826) (xy 339.264294 -46.855628)
			(xy 339.138682 -46.879589) (xy 339.011814 -46.895617) (xy 338.88419 -46.903646) (xy 338.756314 -46.903646)
			(xy 338.62869 -46.895617) (xy 338.501822 -46.879589) (xy 338.37621 -46.855628) (xy 338.252352 -46.823826)
			(xy 338.130734 -46.78431) (xy 338.011837 -46.737236) (xy 337.896131 -46.682789) (xy 337.784072 -46.621184)
			(xy 337.676103 -46.552664) (xy 337.572649 -46.4775) (xy 337.474118 -46.395989) (xy 337.3809 -46.308452)
			(xy 337.293363 -46.215234) (xy 337.211852 -46.116703) (xy 337.136688 -46.013249) (xy 337.068168 -45.90528)
			(xy 337.006563 -45.793221) (xy 336.952116 -45.677515) (xy 336.905042 -45.558618) (xy 336.865526 -45.437)
			(xy 336.833724 -45.313142) (xy 336.809763 -45.18753) (xy 336.793735 -45.060662) (xy 336.785706 -44.933038)
			(xy 317.627 -44.933038) (xy 317.627 -47.3456) (xy 318.77 -48.4886) (xy 333.8068 -48.4886) (xy 336.0928 -50.7746)
			(xy 353.314 -50.7746)
		)
		(stroke
			(width 0)
			(type solid)
		)
		(fill yes)
		(layer "F.Cu")
		(net "GND")
	)
	(gr_poly
		(pts
			(xy 9.008618 -4.700016) (xy 9.008117 -4.604953) (xy 9.000102 -4.414996) (xy 8.984086 -4.225546) (xy 8.960098 -4.036939)
			(xy 8.92818 -3.849511) (xy 8.888389 -3.663595) (xy 8.840796 -3.479522) (xy 8.785485 -3.297619) (xy 8.722556 -3.11821)
			(xy 8.652119 -2.941613) (xy 8.574299 -2.768142) (xy 8.489236 -2.598106) (xy 8.397081 -2.431807) (xy 8.297997 -2.269541)
			(xy 8.19216 -2.111596) (xy 8.079759 -1.958254) (xy 7.960994 -1.809786) (xy 7.836075 -1.666457) (xy 7.705225 -1.528521)
			(xy 7.568676 -1.396224) (xy 7.426672 -1.269802) (xy 7.279465 -1.149478) (xy 7.127315 -1.035466) (xy 6.970495 -0.927971)
			(xy 6.809283 -0.827181) (xy 6.643965 -0.733278) (xy 6.474835 -0.646427) (xy 6.302194 -0.566783) (xy 6.126349 -0.494488)
			(xy 5.947613 -0.429671) (xy 5.766303 -0.372446) (xy 5.582743 -0.322915) (xy 5.397257 -0.281166) (xy 5.210176 -0.247274)
			(xy 5.021832 -0.221299) (xy 4.832561 -0.203287) (xy 4.642699 -0.19327) (xy 4.452584 -0.191266) (xy 4.262553 -0.197278)
			(xy 4.072944 -0.211295) (xy 3.884095 -0.233294) (xy 3.696341 -0.263234) (xy 3.510016 -0.301063) (xy 3.325452 -0.346713)
			(xy 3.142976 -0.400103) (xy 2.962913 -0.461138) (xy 2.785583 -0.529709) (xy 2.611302 -0.605695) (xy 2.440378 -0.688961)
			(xy 2.273117 -0.779358) (xy 2.109816 -0.876726) (xy 1.950764 -0.980892) (xy 1.796245 -1.09167) (xy 1.646533 -1.208864)
			(xy 1.501895 -1.332264) (xy 1.362588 -1.461653) (xy 1.228859 -1.596799) (xy 1.100946 -1.737463) (xy 0.979077 -1.883394)
			(xy 0.863468 -2.034333) (xy 0.754325 -2.190011) (xy 0.651842 -2.350152) (xy 0.556201 -2.514471) (xy 0.467572 -2.682676)
			(xy 0.386113 -2.854467) (xy 0.311968 -3.02954) (xy 0.24527 -3.207583) (xy 0.186136 -3.388279) (xy 0.134673 -3.571308)
			(xy 0.090972 -3.756343) (xy 0.055109 -3.943057) (xy 0.02715 -4.131116) (xy 0.007144 -4.320186) (xy -0.004875 -4.509932)
			(xy -0.008883 -4.700016) (xy 2.185679 -4.700016) (xy 2.189668 -4.564187) (xy 2.201622 -4.428826)
			(xy 2.221499 -4.294401) (xy 2.249231 -4.161373) (xy 2.284722 -4.030202) (xy 2.327851 -3.90134) (xy 2.378467 -3.775232)
			(xy 2.436397 -3.652311) (xy 2.501442 -3.533002) (xy 2.573376 -3.417716) (xy 2.651952 -3.30685) (xy 2.736899 -3.200787)
			(xy 2.827924 -3.099892) (xy 2.924714 -3.004513) (xy 3.026934 -2.914979) (xy 3.134233 -2.831598) (xy 3.24624 -2.754658)
			(xy 3.36257 -2.684424) (xy 3.482821 -2.621138) (xy 3.606579 -2.565018) (xy 3.733417 -2.516258) (xy 3.862898 -2.475026)
			(xy 3.994576 -2.441465) (xy 4.127996 -2.415688) (xy 4.262699 -2.397787) (xy 4.398221 -2.387821) (xy 4.534094 -2.385826)
			(xy 4.669849 -2.391809) (xy 4.80502 -2.405749) (xy 4.939139 -2.427597) (xy 5.071746 -2.457279) (xy 5.202381 -2.494692)
			(xy 5.330596 -2.539707) (xy 5.455948 -2.592169) (xy 5.578005 -2.651898) (xy 5.696346 -2.718687) (xy 5.810564 -2.792306)
			(xy 5.920264 -2.872501) (xy 6.025069 -2.958996) (xy 6.124617 -3.051492) (xy 6.218565 -3.149671) (xy 6.306589 -3.253195)
			(xy 6.388386 -3.361706) (xy 6.463673 -3.474831) (xy 6.532192 -3.592179) (xy 6.593706 -3.713346) (xy 6.648003 -3.837915)
			(xy 6.694895 -3.965455) (xy 6.734222 -4.095527) (xy 6.765847 -4.227683) (xy 6.789662 -4.361468) (xy 6.805585 -4.496419)
			(xy 6.813559 -4.632072) (xy 6.814058 -4.700016) (xy 6.813559 -4.76796) (xy 6.805585 -4.903613) (xy 6.789662 -5.038564)
			(xy 6.765847 -5.172349) (xy 6.734222 -5.304505) (xy 6.694895 -5.434577) (xy 6.648003 -5.562117) (xy 6.593706 -5.686686)
			(xy 6.532192 -5.807853) (xy 6.463673 -5.925201) (xy 6.388386 -6.038326) (xy 6.306589 -6.146837) (xy 6.218565 -6.250361)
			(xy 6.124617 -6.34854) (xy 6.025069 -6.441036) (xy 5.920264 -6.527531) (xy 5.810564 -6.607726) (xy 5.696346 -6.681345)
			(xy 5.578005 -6.748134) (xy 5.455948 -6.807863) (xy 5.330596 -6.860325) (xy 5.202381 -6.90534) (xy 5.071746 -6.942753)
			(xy 4.939139 -6.972435) (xy 4.80502 -6.994283) (xy 4.669849 -7.008223) (xy 4.534094 -7.014206) (xy 4.398221 -7.012211)
			(xy 4.262699 -7.002245) (xy 4.127996 -6.984344) (xy 3.994576 -6.958567) (xy 3.862898 -6.925006) (xy 3.733417 -6.883774)
			(xy 3.606579 -6.835014) (xy 3.482821 -6.778894) (xy 3.36257 -6.715608) (xy 3.24624 -6.645374) (xy 3.134233 -6.568434)
			(xy 3.026934 -6.485053) (xy 2.924714 -6.395519) (xy 2.827924 -6.30014) (xy 2.736899 -6.199245) (xy 2.651952 -6.093182)
			(xy 2.573376 -5.982316) (xy 2.501442 -5.86703) (xy 2.436397 -5.747721) (xy 2.378467 -5.6248) (xy 2.327851 -5.498692)
			(xy 2.284722 -5.36983) (xy 2.249231 -5.238659) (xy 2.221499 -5.105631) (xy 2.201622 -4.971206) (xy 2.189668 -4.835845)
			(xy 2.185679 -4.700016) (xy -0.008883 -4.700016) (xy -0.004875 -4.8901) (xy 0.007144 -5.079846) (xy 0.02715 -5.268916)
			(xy 0.055109 -5.456975) (xy 0.090972 -5.643689) (xy 0.134673 -5.828724) (xy 0.186136 -6.011753) (xy 0.24527 -6.192449)
			(xy 0.311968 -6.370492) (xy 0.386113 -6.545565) (xy 0.467572 -6.717356) (xy 0.556201 -6.885561) (xy 0.651842 -7.04988)
			(xy 0.754325 -7.210021) (xy 0.863468 -7.365699) (xy 0.979077 -7.516638) (xy 1.100946 -7.662569) (xy 1.228859 -7.803233)
			(xy 1.362588 -7.938379) (xy 1.501895 -8.067768) (xy 1.646533 -8.191168) (xy 1.796245 -8.308362) (xy 1.950764 -8.41914)
			(xy 2.109816 -8.523306) (xy 2.273117 -8.620674) (xy 2.440378 -8.711071) (xy 2.611302 -8.794337) (xy 2.785583 -8.870323)
			(xy 2.962913 -8.938894) (xy 3.142976 -8.999929) (xy 3.325452 -9.053319) (xy 3.510016 -9.098969) (xy 3.696341 -9.136798)
			(xy 3.884095 -9.166738) (xy 4.072944 -9.188737) (xy 4.262553 -9.202754) (xy 4.452584 -9.208766) (xy 4.642699 -9.206762)
			(xy 4.832561 -9.196745) (xy 5.021832 -9.178733) (xy 5.210176 -9.152758) (xy 5.397257 -9.118866) (xy 5.582743 -9.077117)
			(xy 5.766303 -9.027586) (xy 5.947613 -8.970361) (xy 6.126349 -8.905544) (xy 6.302194 -8.833249) (xy 6.474835 -8.753605)
			(xy 6.643965 -8.666754) (xy 6.809283 -8.572851) (xy 6.970495 -8.472061) (xy 7.127315 -8.364566) (xy 7.279465 -8.250554)
			(xy 7.426672 -8.13023) (xy 7.568676 -8.003808) (xy 7.705225 -7.871511) (xy 7.836075 -7.733575) (xy 7.960994 -7.590246)
			(xy 8.079759 -7.441778) (xy 8.19216 -7.288436) (xy 8.297997 -7.130491) (xy 8.397081 -6.968225) (xy 8.489236 -6.801926)
			(xy 8.574299 -6.63189) (xy 8.652119 -6.458419) (xy 8.722556 -6.281822) (xy 8.785485 -6.102413) (xy 8.840796 -5.92051)
			(xy 8.888389 -5.736437) (xy 8.92818 -5.550521) (xy 8.960098 -5.363093) (xy 8.984086 -5.174486) (xy 9.000102 -4.985036)
			(xy 9.008117 -4.795079)
		)
		(stroke
			(width 0)
			(type solid)
		)
		(fill yes)
		(layer "F.Cu")
		(net "GND")
	)
	(gr_poly
		(pts
			(xy 428.818548 -4.700016) (xy 428.818047 -4.604953) (xy 428.810032 -4.414996) (xy 428.794016 -4.225546)
			(xy 428.770028 -4.036939) (xy 428.73811 -3.849511) (xy 428.698319 -3.663595) (xy 428.650726 -3.479522)
			(xy 428.595415 -3.297619) (xy 428.532486 -3.11821) (xy 428.462049 -2.941613) (xy 428.384229 -2.768142)
			(xy 428.299166 -2.598106) (xy 428.207011 -2.431807) (xy 428.107927 -2.269541) (xy 428.00209 -2.111596)
			(xy 427.889689 -1.958254) (xy 427.770924 -1.809786) (xy 427.646005 -1.666457) (xy 427.515155 -1.528521)
			(xy 427.378606 -1.396224) (xy 427.236602 -1.269802) (xy 427.089395 -1.149478) (xy 426.937245 -1.035466)
			(xy 426.780425 -0.927971) (xy 426.619213 -0.827181) (xy 426.453895 -0.733278) (xy 426.284765 -0.646427)
			(xy 426.112124 -0.566783) (xy 425.936279 -0.494488) (xy 425.757543 -0.429671) (xy 425.576233 -0.372446)
			(xy 425.392673 -0.322915) (xy 425.207187 -0.281166) (xy 425.020106 -0.247274) (xy 424.831762 -0.221299)
			(xy 424.642491 -0.203287) (xy 424.452629 -0.19327) (xy 424.262514 -0.191266) (xy 424.072483 -0.197278)
			(xy 423.882874 -0.211295) (xy 423.694025 -0.233294) (xy 423.506271 -0.263234) (xy 423.319946 -0.301063)
			(xy 423.135382 -0.346713) (xy 422.952906 -0.400103) (xy 422.772843 -0.461138) (xy 422.595513 -0.529709)
			(xy 422.421232 -0.605695) (xy 422.250308 -0.688961) (xy 422.083047 -0.779358) (xy 421.919746 -0.876726)
			(xy 421.760694 -0.980892) (xy 421.606175 -1.09167) (xy 421.456463 -1.208864) (xy 421.311825 -1.332264)
			(xy 421.172518 -1.461653) (xy 421.038789 -1.596799) (xy 420.910876 -1.737463) (xy 420.789007 -1.883394)
			(xy 420.673398 -2.034333) (xy 420.564255 -2.190011) (xy 420.461772 -2.350152) (xy 420.366131 -2.514471)
			(xy 420.277502 -2.682676) (xy 420.196043 -2.854467) (xy 420.121898 -3.02954) (xy 420.0552 -3.207583)
			(xy 419.996066 -3.388279) (xy 419.944603 -3.571308) (xy 419.900902 -3.756343) (xy 419.865039 -3.943057)
			(xy 419.83708 -4.131116) (xy 419.817074 -4.320186) (xy 419.805055 -4.509932) (xy 419.801047 -4.700016)
			(xy 421.995609 -4.700016) (xy 421.999598 -4.564187) (xy 422.011552 -4.428826) (xy 422.031429 -4.294401)
			(xy 422.059161 -4.161373) (xy 422.094652 -4.030202) (xy 422.137781 -3.90134) (xy 422.188397 -3.775232)
			(xy 422.246327 -3.652311) (xy 422.311372 -3.533002) (xy 422.383306 -3.417716) (xy 422.461882 -3.30685)
			(xy 422.546829 -3.200787) (xy 422.637854 -3.099892) (xy 422.734644 -3.004513) (xy 422.836864 -2.914979)
			(xy 422.944163 -2.831598) (xy 423.05617 -2.754658) (xy 423.1725 -2.684424) (xy 423.292751 -2.621138)
			(xy 423.416509 -2.565018) (xy 423.543347 -2.516258) (xy 423.672828 -2.475026) (xy 423.804506 -2.441465)
			(xy 423.937926 -2.415688) (xy 424.072629 -2.397787) (xy 424.208151 -2.387821) (xy 424.344024 -2.385826)
			(xy 424.479779 -2.391809) (xy 424.61495 -2.405749) (xy 424.749069 -2.427597) (xy 424.881676 -2.457279)
			(xy 425.012311 -2.494692) (xy 425.140526 -2.539707) (xy 425.265878 -2.592169) (xy 425.387935 -2.651898)
			(xy 425.506276 -2.718687) (xy 425.620494 -2.792306) (xy 425.730194 -2.872501) (xy 425.834999 -2.958996)
			(xy 425.934547 -3.051492) (xy 426.028495 -3.149671) (xy 426.116519 -3.253195) (xy 426.198316 -3.361706)
			(xy 426.273603 -3.474831) (xy 426.342122 -3.592179) (xy 426.403636 -3.713346) (xy 426.457933 -3.837915)
			(xy 426.504825 -3.965455) (xy 426.544152 -4.095527) (xy 426.575777 -4.227683) (xy 426.599592 -4.361468)
			(xy 426.615515 -4.496419) (xy 426.623489 -4.632072) (xy 426.623988 -4.700016) (xy 426.623489 -4.76796)
			(xy 426.615515 -4.903613) (xy 426.599592 -5.038564) (xy 426.575777 -5.172349) (xy 426.544152 -5.304505)
			(xy 426.504825 -5.434577) (xy 426.457933 -5.562117) (xy 426.403636 -5.686686) (xy 426.342122 -5.807853)
			(xy 426.273603 -5.925201) (xy 426.198316 -6.038326) (xy 426.116519 -6.146837) (xy 426.028495 -6.250361)
			(xy 425.934547 -6.34854) (xy 425.834999 -6.441036) (xy 425.730194 -6.527531) (xy 425.620494 -6.607726)
			(xy 425.506276 -6.681345) (xy 425.387935 -6.748134) (xy 425.265878 -6.807863) (xy 425.140526 -6.860325)
			(xy 425.012311 -6.90534) (xy 424.881676 -6.942753) (xy 424.749069 -6.972435) (xy 424.61495 -6.994283)
			(xy 424.479779 -7.008223) (xy 424.344024 -7.014206) (xy 424.208151 -7.012211) (xy 424.072629 -7.002245)
			(xy 423.937926 -6.984344) (xy 423.804506 -6.958567) (xy 423.672828 -6.925006) (xy 423.543347 -6.883774)
			(xy 423.416509 -6.835014) (xy 423.292751 -6.778894) (xy 423.1725 -6.715608) (xy 423.05617 -6.645374)
			(xy 422.944163 -6.568434) (xy 422.836864 -6.485053) (xy 422.734644 -6.395519) (xy 422.637854 -6.30014)
			(xy 422.546829 -6.199245) (xy 422.461882 -6.093182) (xy 422.383306 -5.982316) (xy 422.311372 -5.86703)
			(xy 422.246327 -5.747721) (xy 422.188397 -5.6248) (xy 422.137781 -5.498692) (xy 422.094652 -5.36983)
			(xy 422.059161 -5.238659) (xy 422.031429 -5.105631) (xy 422.011552 -4.971206) (xy 421.999598 -4.835845)
			(xy 421.995609 -4.700016) (xy 419.801047 -4.700016) (xy 419.805055 -4.8901) (xy 419.817074 -5.079846)
			(xy 419.83708 -5.268916) (xy 419.865039 -5.456975) (xy 419.900902 -5.643689) (xy 419.944603 -5.828724)
			(xy 419.996066 -6.011753) (xy 420.0552 -6.192449) (xy 420.121898 -6.370492) (xy 420.196043 -6.545565)
			(xy 420.277502 -6.717356) (xy 420.366131 -6.885561) (xy 420.461772 -7.04988) (xy 420.564255 -7.210021)
			(xy 420.673398 -7.365699) (xy 420.789007 -7.516638) (xy 420.910876 -7.662569) (xy 421.038789 -7.803233)
			(xy 421.172518 -7.938379) (xy 421.311825 -8.067768) (xy 421.456463 -8.191168) (xy 421.606175 -8.308362)
			(xy 421.760694 -8.41914) (xy 421.919746 -8.523306) (xy 422.083047 -8.620674) (xy 422.250308 -8.711071)
			(xy 422.421232 -8.794337) (xy 422.595513 -8.870323) (xy 422.772843 -8.938894) (xy 422.952906 -8.999929)
			(xy 423.135382 -9.053319) (xy 423.319946 -9.098969) (xy 423.506271 -9.136798) (xy 423.694025 -9.166738)
			(xy 423.882874 -9.188737) (xy 424.072483 -9.202754) (xy 424.262514 -9.208766) (xy 424.452629 -9.206762)
			(xy 424.642491 -9.196745) (xy 424.831762 -9.178733) (xy 425.020106 -9.152758) (xy 425.207187 -9.118866)
			(xy 425.392673 -9.077117) (xy 425.576233 -9.027586) (xy 425.757543 -8.970361) (xy 425.936279 -8.905544)
			(xy 426.112124 -8.833249) (xy 426.284765 -8.753605) (xy 426.453895 -8.666754) (xy 426.619213 -8.572851)
			(xy 426.780425 -8.472061) (xy 426.937245 -8.364566) (xy 427.089395 -8.250554) (xy 427.236602 -8.13023)
			(xy 427.378606 -8.003808) (xy 427.515155 -7.871511) (xy 427.646005 -7.733575) (xy 427.770924 -7.590246)
			(xy 427.889689 -7.441778) (xy 428.00209 -7.288436) (xy 428.107927 -7.130491) (xy 428.207011 -6.968225)
			(xy 428.299166 -6.801926) (xy 428.384229 -6.63189) (xy 428.462049 -6.458419) (xy 428.532486 -6.281822)
			(xy 428.595415 -6.102413) (xy 428.650726 -5.92051) (xy 428.698319 -5.736437) (xy 428.73811 -5.550521)
			(xy 428.770028 -5.363093) (xy 428.794016 -5.174486) (xy 428.810032 -4.985036) (xy 428.818047 -4.795079)
		)
		(stroke
			(width 0)
			(type solid)
		)
		(fill yes)
		(layer "F.Cu")
		(net "GND")
	)
	(gr_poly
		(pts
			(xy 0.499872 -34.99993) (xy 0.500295 -35.075331) (xy 0.989549 -35.075331) (xy 0.989944 -34.907967)
			(xy 0.998314 -34.740813) (xy 1.014639 -34.574246) (xy 1.038884 -34.408648) (xy 1.070993 -34.244392)
			(xy 1.110892 -34.081853) (xy 1.158491 -33.9214) (xy 1.213683 -33.763398) (xy 1.276341 -33.608206)
			(xy 1.346323 -33.456175) (xy 1.423471 -33.307652) (xy 1.507609 -33.162974) (xy 1.598545 -33.02247)
			(xy 1.696074 -32.886459) (xy 1.799973 -32.755251) (xy 1.910007 -32.629142) (xy 2.025925 -32.50842)
			(xy 2.086356 -32.450532) (xy 2.110056 -32.427339) (xy 2.151613 -32.375665) (xy 2.185811 -32.318852)
			(xy 2.212021 -32.25794) (xy 2.229764 -32.194046) (xy 2.238715 -32.128342) (xy 2.239264 -32.095186)
			(xy 2.239264 -28.999942) (xy 2.23976 -28.932938) (xy 2.247699 -28.799166) (xy 2.263549 -28.666099)
			(xy 2.287253 -28.534204) (xy 2.31873 -28.403946) (xy 2.357868 -28.275781) (xy 2.404529 -28.15016)
			(xy 2.458551 -28.027523) (xy 2.519743 -27.908302) (xy 2.58789 -27.792916) (xy 2.662753 -27.681769)
			(xy 2.744069 -27.575253) (xy 2.831552 -27.47374) (xy 2.924895 -27.377589) (xy 3.02377 -27.287136)
			(xy 3.12783 -27.202699) (xy 3.23671 -27.124576) (xy 3.350026 -27.053039) (xy 3.467381 -26.988341)
			(xy 3.588363 -26.930709) (xy 3.712547 -26.880346) (xy 3.839495 -26.837427) (xy 3.968764 -26.802104)
			(xy 4.099898 -26.774502) (xy 4.232437 -26.754716) (xy 4.365915 -26.742817) (xy 4.499864 -26.738846)
			(xy 4.633813 -26.742817) (xy 4.767291 -26.754716) (xy 4.89983 -26.774502) (xy 5.030964 -26.802104)
			(xy 5.160233 -26.837427) (xy 5.287181 -26.880346) (xy 5.411365 -26.930709) (xy 5.532347 -26.988341)
			(xy 5.649702 -27.053039) (xy 5.763018 -27.124576) (xy 5.871898 -27.202699) (xy 5.975958 -27.287136)
			(xy 6.074833 -27.377589) (xy 6.168176 -27.47374) (xy 6.255659 -27.575253) (xy 6.336975 -27.681769)
			(xy 6.411838 -27.792916) (xy 6.479985 -27.908302) (xy 6.541177 -28.027523) (xy 6.595199 -28.15016)
			(xy 6.64186 -28.275781) (xy 6.680998 -28.403946) (xy 6.712475 -28.534204) (xy 6.736179 -28.666099)
			(xy 6.752029 -28.799166) (xy 6.759968 -28.932938) (xy 6.760464 -28.999942) (xy 6.760464 -32.095186)
			(xy 6.761047 -32.128339) (xy 6.770007 -32.194038) (xy 6.787752 -32.257926) (xy 6.813957 -32.318835)
			(xy 6.848142 -32.37565) (xy 6.889683 -32.427331) (xy 6.913372 -32.450532) (xy 6.973803 -32.50842)
			(xy 7.089721 -32.629142) (xy 7.199755 -32.755251) (xy 7.303654 -32.886459) (xy 7.401183 -33.02247)
			(xy 7.492119 -33.162974) (xy 7.576257 -33.307652) (xy 7.653405 -33.456175) (xy 7.723387 -33.608206)
			(xy 7.786045 -33.763398) (xy 7.841237 -33.9214) (xy 7.888836 -34.081853) (xy 7.928735 -34.244392)
			(xy 7.960844 -34.408648) (xy 7.985089 -34.574246) (xy 8.001414 -34.740813) (xy 8.009784 -34.907967)
			(xy 8.010179 -35.075331) (xy 8.002598 -35.242524) (xy 7.987058 -35.409165) (xy 7.963595 -35.574877)
			(xy 7.932262 -35.739282) (xy 7.89313 -35.902007) (xy 7.846288 -36.062682) (xy 7.791843 -36.220943)
			(xy 7.729917 -36.37643) (xy 7.660653 -36.528789) (xy 7.584207 -36.677674) (xy 7.500753 -36.822747)
			(xy 7.41048 -36.963679) (xy 7.313595 -37.100148) (xy 7.210316 -37.231846) (xy 7.100878 -37.358472)
			(xy 6.985531 -37.47974) (xy 6.864536 -37.595373) (xy 6.738168 -37.705109) (xy 6.606714 -37.808698)
			(xy 6.470474 -37.905906) (xy 6.329756 -37.99651) (xy 6.18488 -38.080306) (xy 6.036175 -38.157104)
			(xy 5.88398 -38.226727) (xy 5.72864 -38.289019) (xy 5.570508 -38.343838) (xy 5.409943 -38.391059)
			(xy 5.247311 -38.430574) (xy 5.08298 -38.462295) (xy 4.917324 -38.486149) (xy 4.75072 -38.502082)
			(xy 4.583546 -38.510057) (xy 4.416182 -38.510057) (xy 4.249008 -38.502082) (xy 4.082404 -38.486149)
			(xy 3.916748 -38.462295) (xy 3.752417 -38.430574) (xy 3.589785 -38.391059) (xy 3.42922 -38.343838)
			(xy 3.271088 -38.289019) (xy 3.115748 -38.226727) (xy 2.963553 -38.157104) (xy 2.814848 -38.080306)
			(xy 2.669972 -37.99651) (xy 2.529254 -37.905906) (xy 2.393014 -37.808698) (xy 2.26156 -37.705109)
			(xy 2.135192 -37.595373) (xy 2.014197 -37.47974) (xy 1.89885 -37.358472) (xy 1.789412 -37.231846)
			(xy 1.686133 -37.100148) (xy 1.589248 -36.963679) (xy 1.498975 -36.822747) (xy 1.415521 -36.677674)
			(xy 1.339075 -36.528789) (xy 1.269811 -36.37643) (xy 1.207885 -36.220943) (xy 1.15344 -36.062682)
			(xy 1.106598 -35.902007) (xy 1.067466 -35.739282) (xy 1.036133 -35.574877) (xy 1.01267 -35.409165)
			(xy 0.99713 -35.242524) (xy 0.989549 -35.075331) (xy 0.500295 -35.075331) (xy 0.500376 -35.089693)
			(xy 0.50843 -35.269039) (xy 0.524523 -35.447843) (xy 0.548621 -35.625745) (xy 0.580677 -35.802387)
			(xy 0.620625 -35.977413) (xy 0.668386 -36.15047) (xy 0.723863 -36.32121) (xy 0.786944 -36.489289)
			(xy 0.857503 -36.654369) (xy 0.935396 -36.816117) (xy 1.020469 -36.974207) (xy 1.112548 -37.128322)
			(xy 1.211448 -37.27815) (xy 1.316972 -37.42339) (xy 1.428905 -37.56375) (xy 1.547022 -37.698946)
			(xy 1.671087 -37.828707) (xy 1.800848 -37.952772) (xy 1.936044 -38.070889) (xy 2.076404 -38.182822)
			(xy 2.221644 -38.288346) (xy 2.371472 -38.387246) (xy 2.525587 -38.479325) (xy 2.683677 -38.564398)
			(xy 2.845425 -38.642291) (xy 3.010505 -38.71285) (xy 3.178584 -38.775931) (xy 3.349324 -38.831408)
			(xy 3.522381 -38.879169) (xy 3.697407 -38.919117) (xy 3.874049 -38.951173) (xy 4.051951 -38.975271)
			(xy 4.230755 -38.991364) (xy 4.410101 -38.999418) (xy 4.589627 -38.999418) (xy 4.768973 -38.991364)
			(xy 4.947777 -38.975271) (xy 5.125679 -38.951173) (xy 5.302321 -38.919117) (xy 5.477347 -38.879169)
			(xy 5.650404 -38.831408) (xy 5.821144 -38.775931) (xy 5.989223 -38.71285) (xy 6.154303 -38.642291)
			(xy 6.316051 -38.564398) (xy 6.474141 -38.479325) (xy 6.628256 -38.387246) (xy 6.778084 -38.288346)
			(xy 6.923324 -38.182822) (xy 7.063684 -38.070889) (xy 7.19888 -37.952772) (xy 7.328641 -37.828707)
			(xy 7.452706 -37.698946) (xy 7.570823 -37.56375) (xy 7.682756 -37.42339) (xy 7.78828 -37.27815) (xy 7.88718 -37.128322)
			(xy 7.979259 -36.974207) (xy 8.064332 -36.816117) (xy 8.142225 -36.654369) (xy 8.212784 -36.489289)
			(xy 8.275865 -36.32121) (xy 8.331342 -36.15047) (xy 8.379103 -35.977413) (xy 8.419051 -35.802387)
			(xy 8.451107 -35.625745) (xy 8.475205 -35.447843) (xy 8.491298 -35.269039) (xy 8.499352 -35.089693)
			(xy 8.499856 -34.99993) (xy 8.499856 -28.999942) (xy 8.499352 -28.910179) (xy 8.491298 -28.730833)
			(xy 8.475205 -28.552029) (xy 8.451107 -28.374127) (xy 8.419051 -28.197485) (xy 8.379103 -28.022459)
			(xy 8.331342 -27.849402) (xy 8.275865 -27.678662) (xy 8.212784 -27.510583) (xy 8.142225 -27.345503)
			(xy 8.064332 -27.183755) (xy 7.979259 -27.025665) (xy 7.88718 -26.87155) (xy 7.78828 -26.721722)
			(xy 7.682756 -26.576482) (xy 7.570823 -26.436122) (xy 7.452706 -26.300926) (xy 7.328641 -26.171165)
			(xy 7.19888 -26.0471) (xy 7.063684 -25.928983) (xy 6.923324 -25.81705) (xy 6.778084 -25.711526) (xy 6.628256 -25.612626)
			(xy 6.474141 -25.520547) (xy 6.316051 -25.435474) (xy 6.154303 -25.357581) (xy 5.989223 -25.287022)
			(xy 5.821144 -25.223941) (xy 5.650404 -25.168464) (xy 5.477347 -25.120703) (xy 5.302321 -25.080755)
			(xy 5.125679 -25.048699) (xy 4.947777 -25.024601) (xy 4.768973 -25.008508) (xy 4.589627 -25.000454)
			(xy 4.410101 -25.000454) (xy 4.230755 -25.008508) (xy 4.051951 -25.024601) (xy 3.874049 -25.048699)
			(xy 3.697407 -25.080755) (xy 3.522381 -25.120703) (xy 3.349324 -25.168464) (xy 3.178584 -25.223941)
			(xy 3.010505 -25.287022) (xy 2.845425 -25.357581) (xy 2.683677 -25.435474) (xy 2.525587 -25.520547)
			(xy 2.371472 -25.612626) (xy 2.221644 -25.711526) (xy 2.076404 -25.81705) (xy 1.936044 -25.928983)
			(xy 1.800848 -26.0471) (xy 1.671087 -26.171165) (xy 1.547022 -26.300926) (xy 1.428905 -26.436122)
			(xy 1.316972 -26.576482) (xy 1.211448 -26.721722) (xy 1.112548 -26.87155) (xy 1.020469 -27.025665)
			(xy 0.935396 -27.183755) (xy 0.857503 -27.345503) (xy 0.786944 -27.510583) (xy 0.723863 -27.678662)
			(xy 0.668386 -27.849402) (xy 0.620625 -28.022459) (xy 0.580677 -28.197485) (xy 0.548621 -28.374127)
			(xy 0.524523 -28.552029) (xy 0.50843 -28.730833) (xy 0.500376 -28.910179) (xy 0.499872 -28.999942)
		)
		(stroke
			(width 0)
			(type solid)
		)
		(fill yes)
		(layer "F.Cu")
		(net "GND")
	)
	(gr_poly
		(pts
			(xy 75.81011 -47.500032) (xy 75.810533 -47.575433) (xy 76.299787 -47.575433) (xy 76.300182 -47.408069)
			(xy 76.308552 -47.240915) (xy 76.324877 -47.074348) (xy 76.349122 -46.90875) (xy 76.381231 -46.744494)
			(xy 76.42113 -46.581955) (xy 76.468729 -46.421502) (xy 76.523921 -46.2635) (xy 76.586579 -46.108308)
			(xy 76.656561 -45.956277) (xy 76.733709 -45.807754) (xy 76.817847 -45.663076) (xy 76.908783 -45.522572)
			(xy 77.006312 -45.386561) (xy 77.110211 -45.255353) (xy 77.220245 -45.129244) (xy 77.336163 -45.008522)
			(xy 77.396594 -44.950634) (xy 77.420287 -44.927434) (xy 77.461844 -44.875761) (xy 77.496041 -44.818949)
			(xy 77.522252 -44.758039) (xy 77.539997 -44.694147) (xy 77.548951 -44.628443) (xy 77.549502 -44.595288)
			(xy 77.549502 -41.500044) (xy 77.549998 -41.43304) (xy 77.557937 -41.299268) (xy 77.573787 -41.166201)
			(xy 77.597491 -41.034306) (xy 77.628968 -40.904048) (xy 77.668106 -40.775883) (xy 77.714767 -40.650262)
			(xy 77.768789 -40.527625) (xy 77.829981 -40.408404) (xy 77.898128 -40.293018) (xy 77.972991 -40.181871)
			(xy 78.054307 -40.075355) (xy 78.14179 -39.973842) (xy 78.235133 -39.877691) (xy 78.334008 -39.787238)
			(xy 78.438068 -39.702801) (xy 78.546948 -39.624678) (xy 78.660264 -39.553141) (xy 78.777619 -39.488443)
			(xy 78.898601 -39.430811) (xy 79.022785 -39.380448) (xy 79.149733 -39.337529) (xy 79.279002 -39.302206)
			(xy 79.410136 -39.274604) (xy 79.542675 -39.254818) (xy 79.676153 -39.242919) (xy 79.810102 -39.238948)
			(xy 79.944051 -39.242919) (xy 80.077529 -39.254818) (xy 80.210068 -39.274604) (xy 80.341202 -39.302206)
			(xy 80.470471 -39.337529) (xy 80.597419 -39.380448) (xy 80.721603 -39.430811) (xy 80.842585 -39.488443)
			(xy 80.95994 -39.553141) (xy 81.073256 -39.624678) (xy 81.182136 -39.702801) (xy 81.286196 -39.787238)
			(xy 81.385071 -39.877691) (xy 81.478414 -39.973842) (xy 81.565897 -40.075355) (xy 81.647213 -40.181871)
			(xy 81.722076 -40.293018) (xy 81.790223 -40.408404) (xy 81.851415 -40.527625) (xy 81.905437 -40.650262)
			(xy 81.952098 -40.775883) (xy 81.991236 -40.904048) (xy 82.022713 -41.034306) (xy 82.046417 -41.166201)
			(xy 82.062267 -41.299268) (xy 82.070206 -41.43304) (xy 82.070702 -41.500044) (xy 82.070702 -44.595288)
			(xy 82.071271 -44.628442) (xy 82.080233 -44.694141) (xy 82.09798 -44.75803) (xy 82.124187 -44.818939)
			(xy 82.158375 -44.875754) (xy 82.199919 -44.927434) (xy 82.22361 -44.950634) (xy 82.284041 -45.008522)
			(xy 82.399959 -45.129244) (xy 82.509993 -45.255353) (xy 82.613892 -45.386561) (xy 82.711421 -45.522572)
			(xy 82.802357 -45.663076) (xy 82.886495 -45.807754) (xy 82.963643 -45.956277) (xy 83.033625 -46.108308)
			(xy 83.096283 -46.2635) (xy 83.151475 -46.421502) (xy 83.199074 -46.581955) (xy 83.238973 -46.744494)
			(xy 83.271082 -46.90875) (xy 83.295327 -47.074348) (xy 83.311652 -47.240915) (xy 83.320022 -47.408069)
			(xy 83.320417 -47.575433) (xy 83.312836 -47.742626) (xy 83.297296 -47.909267) (xy 83.273833 -48.074979)
			(xy 83.2425 -48.239384) (xy 83.203368 -48.402109) (xy 83.156526 -48.562784) (xy 83.102081 -48.721045)
			(xy 83.040155 -48.876532) (xy 82.970891 -49.028891) (xy 82.894445 -49.177776) (xy 82.810991 -49.322849)
			(xy 82.720718 -49.463781) (xy 82.623833 -49.60025) (xy 82.520554 -49.731948) (xy 82.411116 -49.858574)
			(xy 82.295769 -49.979842) (xy 82.174774 -50.095475) (xy 82.048406 -50.205211) (xy 81.916952 -50.3088)
			(xy 81.780712 -50.406008) (xy 81.639994 -50.496612) (xy 81.495118 -50.580408) (xy 81.346413 -50.657206)
			(xy 81.194218 -50.726829) (xy 81.038878 -50.789121) (xy 80.880746 -50.84394) (xy 80.720181 -50.891161)
			(xy 80.557549 -50.930676) (xy 80.393218 -50.962397) (xy 80.227562 -50.986251) (xy 80.060958 -51.002184)
			(xy 79.893784 -51.010159) (xy 79.72642 -51.010159) (xy 79.559246 -51.002184) (xy 79.392642 -50.986251)
			(xy 79.226986 -50.962397) (xy 79.062655 -50.930676) (xy 78.900023 -50.891161) (xy 78.739458 -50.84394)
			(xy 78.581326 -50.789121) (xy 78.425986 -50.726829) (xy 78.273791 -50.657206) (xy 78.125086 -50.580408)
			(xy 77.98021 -50.496612) (xy 77.839492 -50.406008) (xy 77.703252 -50.3088) (xy 77.571798 -50.205211)
			(xy 77.44543 -50.095475) (xy 77.324435 -49.979842) (xy 77.209088 -49.858574) (xy 77.09965 -49.731948)
			(xy 76.996371 -49.60025) (xy 76.899486 -49.463781) (xy 76.809213 -49.322849) (xy 76.725759 -49.177776)
			(xy 76.649313 -49.028891) (xy 76.580049 -48.876532) (xy 76.518123 -48.721045) (xy 76.463678 -48.562784)
			(xy 76.416836 -48.402109) (xy 76.377704 -48.239384) (xy 76.346371 -48.074979) (xy 76.322908 -47.909267)
			(xy 76.307368 -47.742626) (xy 76.299787 -47.575433) (xy 75.810533 -47.575433) (xy 75.810614 -47.589795)
			(xy 75.818668 -47.769141) (xy 75.834761 -47.947945) (xy 75.858859 -48.125847) (xy 75.890915 -48.302489)
			(xy 75.930863 -48.477515) (xy 75.978624 -48.650572) (xy 76.034101 -48.821312) (xy 76.097182 -48.989391)
			(xy 76.167741 -49.154471) (xy 76.245634 -49.316219) (xy 76.330707 -49.474309) (xy 76.422786 -49.628424)
			(xy 76.521686 -49.778252) (xy 76.62721 -49.923492) (xy 76.739143 -50.063852) (xy 76.85726 -50.199048)
			(xy 76.981325 -50.328809) (xy 77.111086 -50.452874) (xy 77.246282 -50.570991) (xy 77.386642 -50.682924)
			(xy 77.531882 -50.788448) (xy 77.68171 -50.887348) (xy 77.835825 -50.979427) (xy 77.993915 -51.0645)
			(xy 78.155663 -51.142393) (xy 78.320743 -51.212952) (xy 78.488822 -51.276033) (xy 78.659562 -51.33151)
			(xy 78.832619 -51.379271) (xy 79.007645 -51.419219) (xy 79.184287 -51.451275) (xy 79.362189 -51.475373)
			(xy 79.540993 -51.491466) (xy 79.720339 -51.49952) (xy 79.899865 -51.49952) (xy 80.079211 -51.491466)
			(xy 80.258015 -51.475373) (xy 80.435917 -51.451275) (xy 80.612559 -51.419219) (xy 80.787585 -51.379271)
			(xy 80.960642 -51.33151) (xy 81.131382 -51.276033) (xy 81.299461 -51.212952) (xy 81.464541 -51.142393)
			(xy 81.626289 -51.0645) (xy 81.784379 -50.979427) (xy 81.938494 -50.887348) (xy 82.088322 -50.788448)
			(xy 82.233562 -50.682924) (xy 82.373922 -50.570991) (xy 82.509118 -50.452874) (xy 82.638879 -50.328809)
			(xy 82.762944 -50.199048) (xy 82.881061 -50.063852) (xy 82.992994 -49.923492) (xy 83.098518 -49.778252)
			(xy 83.197418 -49.628424) (xy 83.289497 -49.474309) (xy 83.37457 -49.316219) (xy 83.452463 -49.154471)
			(xy 83.523022 -48.989391) (xy 83.586103 -48.821312) (xy 83.64158 -48.650572) (xy 83.689341 -48.477515)
			(xy 83.729289 -48.302489) (xy 83.761345 -48.125847) (xy 83.785443 -47.947945) (xy 83.801536 -47.769141)
			(xy 83.80959 -47.589795) (xy 83.810094 -47.500032) (xy 83.810094 -41.500044) (xy 83.80959 -41.410281)
			(xy 83.801536 -41.230935) (xy 83.785443 -41.052131) (xy 83.761345 -40.874229) (xy 83.729289 -40.697587)
			(xy 83.689341 -40.522561) (xy 83.64158 -40.349504) (xy 83.586103 -40.178764) (xy 83.523022 -40.010685)
			(xy 83.452463 -39.845605) (xy 83.37457 -39.683857) (xy 83.289497 -39.525767) (xy 83.197418 -39.371652)
			(xy 83.098518 -39.221824) (xy 82.992994 -39.076584) (xy 82.881061 -38.936224) (xy 82.762944 -38.801028)
			(xy 82.638879 -38.671267) (xy 82.509118 -38.547202) (xy 82.373922 -38.429085) (xy 82.233562 -38.317152)
			(xy 82.088322 -38.211628) (xy 81.938494 -38.112728) (xy 81.784379 -38.020649) (xy 81.626289 -37.935576)
			(xy 81.464541 -37.857683) (xy 81.299461 -37.787124) (xy 81.131382 -37.724043) (xy 80.960642 -37.668566)
			(xy 80.787585 -37.620805) (xy 80.612559 -37.580857) (xy 80.435917 -37.548801) (xy 80.258015 -37.524703)
			(xy 80.079211 -37.50861) (xy 79.899865 -37.500556) (xy 79.720339 -37.500556) (xy 79.540993 -37.50861)
			(xy 79.362189 -37.524703) (xy 79.184287 -37.548801) (xy 79.007645 -37.580857) (xy 78.832619 -37.620805)
			(xy 78.659562 -37.668566) (xy 78.488822 -37.724043) (xy 78.320743 -37.787124) (xy 78.155663 -37.857683)
			(xy 77.993915 -37.935576) (xy 77.835825 -38.020649) (xy 77.68171 -38.112728) (xy 77.531882 -38.211628)
			(xy 77.386642 -38.317152) (xy 77.246282 -38.429085) (xy 77.111086 -38.547202) (xy 76.981325 -38.671267)
			(xy 76.85726 -38.801028) (xy 76.739143 -38.936224) (xy 76.62721 -39.076584) (xy 76.521686 -39.221824)
			(xy 76.422786 -39.371652) (xy 76.330707 -39.525767) (xy 76.245634 -39.683857) (xy 76.167741 -39.845605)
			(xy 76.097182 -40.010685) (xy 76.034101 -40.178764) (xy 75.978624 -40.349504) (xy 75.930863 -40.522561)
			(xy 75.890915 -40.697587) (xy 75.858859 -40.874229) (xy 75.834761 -41.052131) (xy 75.818668 -41.230935)
			(xy 75.810614 -41.410281) (xy 75.81011 -41.500044)
		)
		(stroke
			(width 0)
			(type solid)
		)
		(fill yes)
		(layer "F.Cu")
		(net "GND")
	)
	(gr_poly
		(pts
			(xy 195.049902 -10.700004) (xy 195.050325 -10.775405) (xy 195.539579 -10.775405) (xy 195.539974 -10.608041)
			(xy 195.548344 -10.440887) (xy 195.564669 -10.27432) (xy 195.588914 -10.108722) (xy 195.621023 -9.944466)
			(xy 195.660922 -9.781927) (xy 195.708521 -9.621474) (xy 195.763713 -9.463472) (xy 195.826371 -9.30828)
			(xy 195.896353 -9.156249) (xy 195.973501 -9.007726) (xy 196.057639 -8.863048) (xy 196.148575 -8.722544)
			(xy 196.246104 -8.586533) (xy 196.350003 -8.455325) (xy 196.460037 -8.329216) (xy 196.575955 -8.208494)
			(xy 196.636386 -8.150606) (xy 196.660091 -8.127418) (xy 196.701647 -8.075742) (xy 196.735843 -8.018928)
			(xy 196.762052 -7.958015) (xy 196.779794 -7.894121) (xy 196.788745 -7.828416) (xy 196.789294 -7.79526)
			(xy 196.789294 -4.700016) (xy 196.78979 -4.633012) (xy 196.797729 -4.49924) (xy 196.813579 -4.366173)
			(xy 196.837283 -4.234278) (xy 196.86876 -4.10402) (xy 196.907898 -3.975855) (xy 196.954559 -3.850234)
			(xy 197.008581 -3.727597) (xy 197.069773 -3.608376) (xy 197.13792 -3.49299) (xy 197.212783 -3.381843)
			(xy 197.294099 -3.275327) (xy 197.381582 -3.173814) (xy 197.474925 -3.077663) (xy 197.5738 -2.98721)
			(xy 197.67786 -2.902773) (xy 197.78674 -2.82465) (xy 197.900056 -2.753113) (xy 198.017411 -2.688415)
			(xy 198.138393 -2.630783) (xy 198.262577 -2.58042) (xy 198.389525 -2.537501) (xy 198.518794 -2.502178)
			(xy 198.649928 -2.474576) (xy 198.782467 -2.45479) (xy 198.915945 -2.442891) (xy 199.049894 -2.43892)
			(xy 199.183843 -2.442891) (xy 199.317321 -2.45479) (xy 199.44986 -2.474576) (xy 199.580994 -2.502178)
			(xy 199.710263 -2.537501) (xy 199.837211 -2.58042) (xy 199.961395 -2.630783) (xy 200.082377 -2.688415)
			(xy 200.199732 -2.753113) (xy 200.313048 -2.82465) (xy 200.421928 -2.902773) (xy 200.525988 -2.98721)
			(xy 200.624863 -3.077663) (xy 200.718206 -3.173814) (xy 200.805689 -3.275327) (xy 200.887005 -3.381843)
			(xy 200.961868 -3.49299) (xy 201.030015 -3.608376) (xy 201.091207 -3.727597) (xy 201.145229 -3.850234)
			(xy 201.19189 -3.975855) (xy 201.231028 -4.10402) (xy 201.262505 -4.234278) (xy 201.286209 -4.366173)
			(xy 201.302059 -4.49924) (xy 201.309998 -4.633012) (xy 201.310494 -4.700016) (xy 201.310494 -7.79526)
			(xy 201.311019 -7.828415) (xy 201.319989 -7.894117) (xy 201.337745 -7.958006) (xy 201.363961 -8.018915)
			(xy 201.398157 -8.075729) (xy 201.439708 -8.127407) (xy 201.463402 -8.150606) (xy 201.523833 -8.208494)
			(xy 201.639751 -8.329216) (xy 201.749785 -8.455325) (xy 201.853684 -8.586533) (xy 201.951213 -8.722544)
			(xy 202.042149 -8.863048) (xy 202.126287 -9.007726) (xy 202.203435 -9.156249) (xy 202.273417 -9.30828)
			(xy 202.336075 -9.463472) (xy 202.391267 -9.621474) (xy 202.438866 -9.781927) (xy 202.478765 -9.944466)
			(xy 202.510874 -10.108722) (xy 202.535119 -10.27432) (xy 202.551444 -10.440887) (xy 202.559814 -10.608041)
			(xy 202.560209 -10.775405) (xy 202.552628 -10.942598) (xy 202.537088 -11.109239) (xy 202.513625 -11.274951)
			(xy 202.482292 -11.439356) (xy 202.44316 -11.602081) (xy 202.396318 -11.762756) (xy 202.341873 -11.921017)
			(xy 202.279947 -12.076504) (xy 202.210683 -12.228863) (xy 202.134237 -12.377748) (xy 202.050783 -12.522821)
			(xy 201.96051 -12.663753) (xy 201.863625 -12.800222) (xy 201.760346 -12.93192) (xy 201.650908 -13.058546)
			(xy 201.535561 -13.179814) (xy 201.414566 -13.295447) (xy 201.288198 -13.405183) (xy 201.156744 -13.508772)
			(xy 201.020504 -13.60598) (xy 200.879786 -13.696584) (xy 200.73491 -13.78038) (xy 200.586205 -13.857178)
			(xy 200.43401 -13.926801) (xy 200.27867 -13.989093) (xy 200.120538 -14.043912) (xy 199.959973 -14.091133)
			(xy 199.797341 -14.130648) (xy 199.63301 -14.162369) (xy 199.467354 -14.186223) (xy 199.30075 -14.202156)
			(xy 199.133576 -14.210131) (xy 198.966212 -14.210131) (xy 198.799038 -14.202156) (xy 198.632434 -14.186223)
			(xy 198.466778 -14.162369) (xy 198.302447 -14.130648) (xy 198.139815 -14.091133) (xy 197.97925 -14.043912)
			(xy 197.821118 -13.989093) (xy 197.665778 -13.926801) (xy 197.513583 -13.857178) (xy 197.364878 -13.78038)
			(xy 197.220002 -13.696584) (xy 197.079284 -13.60598) (xy 196.943044 -13.508772) (xy 196.81159 -13.405183)
			(xy 196.685222 -13.295447) (xy 196.564227 -13.179814) (xy 196.44888 -13.058546) (xy 196.339442 -12.93192)
			(xy 196.236163 -12.800222) (xy 196.139278 -12.663753) (xy 196.049005 -12.522821) (xy 195.965551 -12.377748)
			(xy 195.889105 -12.228863) (xy 195.819841 -12.076504) (xy 195.757915 -11.921017) (xy 195.70347 -11.762756)
			(xy 195.656628 -11.602081) (xy 195.617496 -11.439356) (xy 195.586163 -11.274951) (xy 195.5627 -11.109239)
			(xy 195.54716 -10.942598) (xy 195.539579 -10.775405) (xy 195.050325 -10.775405) (xy 195.050406 -10.789767)
			(xy 195.05846 -10.969113) (xy 195.074553 -11.147917) (xy 195.098651 -11.325819) (xy 195.130707 -11.502461)
			(xy 195.170655 -11.677487) (xy 195.218416 -11.850544) (xy 195.273893 -12.021284) (xy 195.336974 -12.189363)
			(xy 195.407533 -12.354443) (xy 195.485426 -12.516191) (xy 195.570499 -12.674281) (xy 195.662578 -12.828396)
			(xy 195.761478 -12.978224) (xy 195.867002 -13.123464) (xy 195.978935 -13.263824) (xy 196.097052 -13.39902)
			(xy 196.221117 -13.528781) (xy 196.350878 -13.652846) (xy 196.486074 -13.770963) (xy 196.626434 -13.882896)
			(xy 196.771674 -13.98842) (xy 196.921502 -14.08732) (xy 197.075617 -14.179399) (xy 197.233707 -14.264472)
			(xy 197.395455 -14.342365) (xy 197.560535 -14.412924) (xy 197.728614 -14.476005) (xy 197.899354 -14.531482)
			(xy 198.072411 -14.579243) (xy 198.247437 -14.619191) (xy 198.424079 -14.651247) (xy 198.601981 -14.675345)
			(xy 198.780785 -14.691438) (xy 198.960131 -14.699492) (xy 199.139657 -14.699492) (xy 199.319003 -14.691438)
			(xy 199.497807 -14.675345) (xy 199.675709 -14.651247) (xy 199.852351 -14.619191) (xy 200.027377 -14.579243)
			(xy 200.200434 -14.531482) (xy 200.371174 -14.476005) (xy 200.539253 -14.412924) (xy 200.704333 -14.342365)
			(xy 200.866081 -14.264472) (xy 201.024171 -14.179399) (xy 201.178286 -14.08732) (xy 201.328114 -13.98842)
			(xy 201.473354 -13.882896) (xy 201.613714 -13.770963) (xy 201.74891 -13.652846) (xy 201.878671 -13.528781)
			(xy 202.002736 -13.39902) (xy 202.120853 -13.263824) (xy 202.232786 -13.123464) (xy 202.33831 -12.978224)
			(xy 202.43721 -12.828396) (xy 202.529289 -12.674281) (xy 202.614362 -12.516191) (xy 202.692255 -12.354443)
			(xy 202.762814 -12.189363) (xy 202.825895 -12.021284) (xy 202.881372 -11.850544) (xy 202.929133 -11.677487)
			(xy 202.969081 -11.502461) (xy 203.001137 -11.325819) (xy 203.025235 -11.147917) (xy 203.041328 -10.969113)
			(xy 203.049382 -10.789767) (xy 203.049886 -10.700004) (xy 203.049886 -4.700016) (xy 203.049382 -4.610253)
			(xy 203.041328 -4.430907) (xy 203.025235 -4.252103) (xy 203.001137 -4.074201) (xy 202.969081 -3.897559)
			(xy 202.929133 -3.722533) (xy 202.881372 -3.549476) (xy 202.825895 -3.378736) (xy 202.762814 -3.210657)
			(xy 202.692255 -3.045577) (xy 202.614362 -2.883829) (xy 202.529289 -2.725739) (xy 202.43721 -2.571624)
			(xy 202.33831 -2.421796) (xy 202.232786 -2.276556) (xy 202.120853 -2.136196) (xy 202.002736 -2.001)
			(xy 201.878671 -1.871239) (xy 201.74891 -1.747174) (xy 201.613714 -1.629057) (xy 201.473354 -1.517124)
			(xy 201.328114 -1.4116) (xy 201.178286 -1.3127) (xy 201.024171 -1.220621) (xy 200.866081 -1.135548)
			(xy 200.704333 -1.057655) (xy 200.539253 -0.987096) (xy 200.371174 -0.924015) (xy 200.200434 -0.868538)
			(xy 200.027377 -0.820777) (xy 199.852351 -0.780829) (xy 199.675709 -0.748773) (xy 199.497807 -0.724675)
			(xy 199.319003 -0.708582) (xy 199.139657 -0.700528) (xy 198.960131 -0.700528) (xy 198.780785 -0.708582)
			(xy 198.601981 -0.724675) (xy 198.424079 -0.748773) (xy 198.247437 -0.780829) (xy 198.072411 -0.820777)
			(xy 197.899354 -0.868538) (xy 197.728614 -0.924015) (xy 197.560535 -0.987096) (xy 197.395455 -1.057655)
			(xy 197.233707 -1.135548) (xy 197.075617 -1.220621) (xy 196.921502 -1.3127) (xy 196.771674 -1.4116)
			(xy 196.626434 -1.517124) (xy 196.486074 -1.629057) (xy 196.350878 -1.747174) (xy 196.221117 -1.871239)
			(xy 196.097052 -2.001) (xy 195.978935 -2.136196) (xy 195.867002 -2.276556) (xy 195.761478 -2.421796)
			(xy 195.662578 -2.571624) (xy 195.570499 -2.725739) (xy 195.485426 -2.883829) (xy 195.407533 -3.045577)
			(xy 195.336974 -3.210657) (xy 195.273893 -3.378736) (xy 195.218416 -3.549476) (xy 195.170655 -3.722533)
			(xy 195.130707 -3.897559) (xy 195.098651 -4.074201) (xy 195.074553 -4.252103) (xy 195.05846 -4.430907)
			(xy 195.050406 -4.610253) (xy 195.049902 -4.700016)
		)
		(stroke
			(width 0)
			(type solid)
		)
		(fill yes)
		(layer "F.Cu")
		(net "GND")
	)
	(gr_poly
		(pts
			(xy 205.810104 -47.500032) (xy 205.810527 -47.575433) (xy 206.299781 -47.575433) (xy 206.300176 -47.408069)
			(xy 206.308546 -47.240915) (xy 206.324871 -47.074348) (xy 206.349116 -46.90875) (xy 206.381225 -46.744494)
			(xy 206.421124 -46.581955) (xy 206.468723 -46.421502) (xy 206.523915 -46.2635) (xy 206.586573 -46.108308)
			(xy 206.656555 -45.956277) (xy 206.733703 -45.807754) (xy 206.817841 -45.663076) (xy 206.908777 -45.522572)
			(xy 207.006306 -45.386561) (xy 207.110205 -45.255353) (xy 207.220239 -45.129244) (xy 207.336157 -45.008522)
			(xy 207.396588 -44.950634) (xy 207.42028 -44.927433) (xy 207.461837 -44.87576) (xy 207.496034 -44.818948)
			(xy 207.522246 -44.758038) (xy 207.539991 -44.694146) (xy 207.548945 -44.628443) (xy 207.549496 -44.595288)
			(xy 207.549496 -41.500044) (xy 207.549992 -41.43304) (xy 207.557931 -41.299268) (xy 207.573781 -41.166201)
			(xy 207.597485 -41.034306) (xy 207.628962 -40.904048) (xy 207.6681 -40.775883) (xy 207.714761 -40.650262)
			(xy 207.768783 -40.527625) (xy 207.829975 -40.408404) (xy 207.898122 -40.293018) (xy 207.972985 -40.181871)
			(xy 208.054301 -40.075355) (xy 208.141784 -39.973842) (xy 208.235127 -39.877691) (xy 208.334002 -39.787238)
			(xy 208.438062 -39.702801) (xy 208.546942 -39.624678) (xy 208.660258 -39.553141) (xy 208.777613 -39.488443)
			(xy 208.898595 -39.430811) (xy 209.022779 -39.380448) (xy 209.149727 -39.337529) (xy 209.278996 -39.302206)
			(xy 209.41013 -39.274604) (xy 209.542669 -39.254818) (xy 209.676147 -39.242919) (xy 209.810096 -39.238948)
			(xy 209.944045 -39.242919) (xy 210.077523 -39.254818) (xy 210.210062 -39.274604) (xy 210.341196 -39.302206)
			(xy 210.470465 -39.337529) (xy 210.597413 -39.380448) (xy 210.721597 -39.430811) (xy 210.842579 -39.488443)
			(xy 210.959934 -39.553141) (xy 211.07325 -39.624678) (xy 211.18213 -39.702801) (xy 211.28619 -39.787238)
			(xy 211.385065 -39.877691) (xy 211.478408 -39.973842) (xy 211.565891 -40.075355) (xy 211.647207 -40.181871)
			(xy 211.72207 -40.293018) (xy 211.790217 -40.408404) (xy 211.851409 -40.527625) (xy 211.905431 -40.650262)
			(xy 211.952092 -40.775883) (xy 211.99123 -40.904048) (xy 212.022707 -41.034306) (xy 212.046411 -41.166201)
			(xy 212.062261 -41.299268) (xy 212.0702 -41.43304) (xy 212.070696 -41.500044) (xy 212.070696 -44.595288)
			(xy 212.071267 -44.628442) (xy 212.080229 -44.694141) (xy 212.097975 -44.75803) (xy 212.124182 -44.818939)
			(xy 212.15837 -44.875754) (xy 212.199913 -44.927434) (xy 212.223604 -44.950634) (xy 212.284035 -45.008522)
			(xy 212.399953 -45.129244) (xy 212.509987 -45.255353) (xy 212.613886 -45.386561) (xy 212.711415 -45.522572)
			(xy 212.802351 -45.663076) (xy 212.886489 -45.807754) (xy 212.963637 -45.956277) (xy 213.033619 -46.108308)
			(xy 213.096277 -46.2635) (xy 213.151469 -46.421502) (xy 213.199068 -46.581955) (xy 213.238967 -46.744494)
			(xy 213.271076 -46.90875) (xy 213.295321 -47.074348) (xy 213.311646 -47.240915) (xy 213.320016 -47.408069)
			(xy 213.320411 -47.575433) (xy 213.31283 -47.742626) (xy 213.29729 -47.909267) (xy 213.273827 -48.074979)
			(xy 213.242494 -48.239384) (xy 213.203362 -48.402109) (xy 213.15652 -48.562784) (xy 213.102075 -48.721045)
			(xy 213.040149 -48.876532) (xy 212.970885 -49.028891) (xy 212.894439 -49.177776) (xy 212.810985 -49.322849)
			(xy 212.720712 -49.463781) (xy 212.623827 -49.60025) (xy 212.520548 -49.731948) (xy 212.41111 -49.858574)
			(xy 212.295763 -49.979842) (xy 212.174768 -50.095475) (xy 212.0484 -50.205211) (xy 211.916946 -50.3088)
			(xy 211.780706 -50.406008) (xy 211.639988 -50.496612) (xy 211.495112 -50.580408) (xy 211.346407 -50.657206)
			(xy 211.194212 -50.726829) (xy 211.038872 -50.789121) (xy 210.88074 -50.84394) (xy 210.720175 -50.891161)
			(xy 210.557543 -50.930676) (xy 210.393212 -50.962397) (xy 210.227556 -50.986251) (xy 210.060952 -51.002184)
			(xy 209.893778 -51.010159) (xy 209.726414 -51.010159) (xy 209.55924 -51.002184) (xy 209.392636 -50.986251)
			(xy 209.22698 -50.962397) (xy 209.062649 -50.930676) (xy 208.900017 -50.891161) (xy 208.739452 -50.84394)
			(xy 208.58132 -50.789121) (xy 208.42598 -50.726829) (xy 208.273785 -50.657206) (xy 208.12508 -50.580408)
			(xy 207.980204 -50.496612) (xy 207.839486 -50.406008) (xy 207.703246 -50.3088) (xy 207.571792 -50.205211)
			(xy 207.445424 -50.095475) (xy 207.324429 -49.979842) (xy 207.209082 -49.858574) (xy 207.099644 -49.731948)
			(xy 206.996365 -49.60025) (xy 206.89948 -49.463781) (xy 206.809207 -49.322849) (xy 206.725753 -49.177776)
			(xy 206.649307 -49.028891) (xy 206.580043 -48.876532) (xy 206.518117 -48.721045) (xy 206.463672 -48.562784)
			(xy 206.41683 -48.402109) (xy 206.377698 -48.239384) (xy 206.346365 -48.074979) (xy 206.322902 -47.909267)
			(xy 206.307362 -47.742626) (xy 206.299781 -47.575433) (xy 205.810527 -47.575433) (xy 205.810608 -47.589795)
			(xy 205.818662 -47.769141) (xy 205.834755 -47.947945) (xy 205.858853 -48.125847) (xy 205.890909 -48.302489)
			(xy 205.930857 -48.477515) (xy 205.978618 -48.650572) (xy 206.034095 -48.821312) (xy 206.097176 -48.989391)
			(xy 206.167735 -49.154471) (xy 206.245628 -49.316219) (xy 206.330701 -49.474309) (xy 206.42278 -49.628424)
			(xy 206.52168 -49.778252) (xy 206.627204 -49.923492) (xy 206.739137 -50.063852) (xy 206.857254 -50.199048)
			(xy 206.981319 -50.328809) (xy 207.11108 -50.452874) (xy 207.246276 -50.570991) (xy 207.386636 -50.682924)
			(xy 207.531876 -50.788448) (xy 207.681704 -50.887348) (xy 207.835819 -50.979427) (xy 207.993909 -51.0645)
			(xy 208.155657 -51.142393) (xy 208.320737 -51.212952) (xy 208.488816 -51.276033) (xy 208.659556 -51.33151)
			(xy 208.832613 -51.379271) (xy 209.007639 -51.419219) (xy 209.184281 -51.451275) (xy 209.362183 -51.475373)
			(xy 209.540987 -51.491466) (xy 209.720333 -51.49952) (xy 209.899859 -51.49952) (xy 210.079205 -51.491466)
			(xy 210.258009 -51.475373) (xy 210.435911 -51.451275) (xy 210.612553 -51.419219) (xy 210.787579 -51.379271)
			(xy 210.960636 -51.33151) (xy 211.131376 -51.276033) (xy 211.299455 -51.212952) (xy 211.464535 -51.142393)
			(xy 211.626283 -51.0645) (xy 211.784373 -50.979427) (xy 211.938488 -50.887348) (xy 212.088316 -50.788448)
			(xy 212.233556 -50.682924) (xy 212.373916 -50.570991) (xy 212.509112 -50.452874) (xy 212.638873 -50.328809)
			(xy 212.762938 -50.199048) (xy 212.881055 -50.063852) (xy 212.992988 -49.923492) (xy 213.098512 -49.778252)
			(xy 213.197412 -49.628424) (xy 213.289491 -49.474309) (xy 213.374564 -49.316219) (xy 213.452457 -49.154471)
			(xy 213.523016 -48.989391) (xy 213.586097 -48.821312) (xy 213.641574 -48.650572) (xy 213.689335 -48.477515)
			(xy 213.729283 -48.302489) (xy 213.761339 -48.125847) (xy 213.785437 -47.947945) (xy 213.80153 -47.769141)
			(xy 213.809584 -47.589795) (xy 213.810088 -47.500032) (xy 213.810088 -41.500044) (xy 213.809584 -41.410281)
			(xy 213.80153 -41.230935) (xy 213.785437 -41.052131) (xy 213.761339 -40.874229) (xy 213.729283 -40.697587)
			(xy 213.689335 -40.522561) (xy 213.641574 -40.349504) (xy 213.586097 -40.178764) (xy 213.523016 -40.010685)
			(xy 213.452457 -39.845605) (xy 213.374564 -39.683857) (xy 213.289491 -39.525767) (xy 213.197412 -39.371652)
			(xy 213.098512 -39.221824) (xy 212.992988 -39.076584) (xy 212.881055 -38.936224) (xy 212.762938 -38.801028)
			(xy 212.638873 -38.671267) (xy 212.509112 -38.547202) (xy 212.373916 -38.429085) (xy 212.233556 -38.317152)
			(xy 212.088316 -38.211628) (xy 211.938488 -38.112728) (xy 211.784373 -38.020649) (xy 211.626283 -37.935576)
			(xy 211.464535 -37.857683) (xy 211.299455 -37.787124) (xy 211.131376 -37.724043) (xy 210.960636 -37.668566)
			(xy 210.787579 -37.620805) (xy 210.612553 -37.580857) (xy 210.435911 -37.548801) (xy 210.258009 -37.524703)
			(xy 210.079205 -37.50861) (xy 209.899859 -37.500556) (xy 209.720333 -37.500556) (xy 209.540987 -37.50861)
			(xy 209.362183 -37.524703) (xy 209.184281 -37.548801) (xy 209.007639 -37.580857) (xy 208.832613 -37.620805)
			(xy 208.659556 -37.668566) (xy 208.488816 -37.724043) (xy 208.320737 -37.787124) (xy 208.155657 -37.857683)
			(xy 207.993909 -37.935576) (xy 207.835819 -38.020649) (xy 207.681704 -38.112728) (xy 207.531876 -38.211628)
			(xy 207.386636 -38.317152) (xy 207.246276 -38.429085) (xy 207.11108 -38.547202) (xy 206.981319 -38.671267)
			(xy 206.857254 -38.801028) (xy 206.739137 -38.936224) (xy 206.627204 -39.076584) (xy 206.52168 -39.221824)
			(xy 206.42278 -39.371652) (xy 206.330701 -39.525767) (xy 206.245628 -39.683857) (xy 206.167735 -39.845605)
			(xy 206.097176 -40.010685) (xy 206.034095 -40.178764) (xy 205.978618 -40.349504) (xy 205.930857 -40.522561)
			(xy 205.890909 -40.697587) (xy 205.858853 -40.874229) (xy 205.834755 -41.052131) (xy 205.818662 -41.230935)
			(xy 205.810608 -41.410281) (xy 205.810104 -41.500044)
		)
		(stroke
			(width 0)
			(type solid)
		)
		(fill yes)
		(layer "F.Cu")
		(net "GND")
	)
	(gr_poly
		(pts
			(xy 275.810218 -10.700004) (xy 275.810641 -10.775405) (xy 276.299895 -10.775405) (xy 276.30029 -10.608041)
			(xy 276.30866 -10.440887) (xy 276.324985 -10.27432) (xy 276.34923 -10.108722) (xy 276.381339 -9.944466)
			(xy 276.421238 -9.781927) (xy 276.468837 -9.621474) (xy 276.524029 -9.463472) (xy 276.586687 -9.30828)
			(xy 276.656669 -9.156249) (xy 276.733817 -9.007726) (xy 276.817955 -8.863048) (xy 276.908891 -8.722544)
			(xy 277.00642 -8.586533) (xy 277.110319 -8.455325) (xy 277.220353 -8.329216) (xy 277.336271 -8.208494)
			(xy 277.396702 -8.150606) (xy 277.420392 -8.127402) (xy 277.461952 -8.075732) (xy 277.496152 -8.018921)
			(xy 277.522364 -7.958011) (xy 277.540109 -7.894119) (xy 277.549061 -7.828415) (xy 277.54961 -7.79526)
			(xy 277.54961 -4.700016) (xy 277.550106 -4.633012) (xy 277.558045 -4.49924) (xy 277.573895 -4.366173)
			(xy 277.597599 -4.234278) (xy 277.629076 -4.10402) (xy 277.668214 -3.975855) (xy 277.714875 -3.850234)
			(xy 277.768897 -3.727597) (xy 277.830089 -3.608376) (xy 277.898236 -3.49299) (xy 277.973099 -3.381843)
			(xy 278.054415 -3.275327) (xy 278.141898 -3.173814) (xy 278.235241 -3.077663) (xy 278.334116 -2.98721)
			(xy 278.438176 -2.902773) (xy 278.547056 -2.82465) (xy 278.660372 -2.753113) (xy 278.777727 -2.688415)
			(xy 278.898709 -2.630783) (xy 279.022893 -2.58042) (xy 279.149841 -2.537501) (xy 279.27911 -2.502178)
			(xy 279.410244 -2.474576) (xy 279.542783 -2.45479) (xy 279.676261 -2.442891) (xy 279.81021 -2.43892)
			(xy 279.944159 -2.442891) (xy 280.077637 -2.45479) (xy 280.210176 -2.474576) (xy 280.34131 -2.502178)
			(xy 280.470579 -2.537501) (xy 280.597527 -2.58042) (xy 280.721711 -2.630783) (xy 280.842693 -2.688415)
			(xy 280.960048 -2.753113) (xy 281.073364 -2.82465) (xy 281.182244 -2.902773) (xy 281.286304 -2.98721)
			(xy 281.385179 -3.077663) (xy 281.478522 -3.173814) (xy 281.566005 -3.275327) (xy 281.647321 -3.381843)
			(xy 281.722184 -3.49299) (xy 281.790331 -3.608376) (xy 281.851523 -3.727597) (xy 281.905545 -3.850234)
			(xy 281.952206 -3.975855) (xy 281.991344 -4.10402) (xy 282.022821 -4.234278) (xy 282.046525 -4.366173)
			(xy 282.062375 -4.49924) (xy 282.070314 -4.633012) (xy 282.07081 -4.700016) (xy 282.07081 -7.79526)
			(xy 282.07133 -7.828416) (xy 282.080301 -7.894117) (xy 282.098057 -7.958007) (xy 282.124274 -8.018916)
			(xy 282.158471 -8.07573) (xy 282.200023 -8.127408) (xy 282.223718 -8.150606) (xy 282.284149 -8.208494)
			(xy 282.400067 -8.329216) (xy 282.510101 -8.455325) (xy 282.614 -8.586533) (xy 282.711529 -8.722544)
			(xy 282.802465 -8.863048) (xy 282.886603 -9.007726) (xy 282.963751 -9.156249) (xy 283.033733 -9.30828)
			(xy 283.096391 -9.463472) (xy 283.151583 -9.621474) (xy 283.199182 -9.781927) (xy 283.239081 -9.944466)
			(xy 283.27119 -10.108722) (xy 283.295435 -10.27432) (xy 283.31176 -10.440887) (xy 283.32013 -10.608041)
			(xy 283.320525 -10.775405) (xy 283.312944 -10.942598) (xy 283.297404 -11.109239) (xy 283.273941 -11.274951)
			(xy 283.242608 -11.439356) (xy 283.203476 -11.602081) (xy 283.156634 -11.762756) (xy 283.102189 -11.921017)
			(xy 283.040263 -12.076504) (xy 282.970999 -12.228863) (xy 282.894553 -12.377748) (xy 282.811099 -12.522821)
			(xy 282.720826 -12.663753) (xy 282.623941 -12.800222) (xy 282.520662 -12.93192) (xy 282.411224 -13.058546)
			(xy 282.295877 -13.179814) (xy 282.174882 -13.295447) (xy 282.048514 -13.405183) (xy 281.91706 -13.508772)
			(xy 281.78082 -13.60598) (xy 281.640102 -13.696584) (xy 281.495226 -13.78038) (xy 281.346521 -13.857178)
			(xy 281.194326 -13.926801) (xy 281.038986 -13.989093) (xy 280.880854 -14.043912) (xy 280.720289 -14.091133)
			(xy 280.557657 -14.130648) (xy 280.393326 -14.162369) (xy 280.22767 -14.186223) (xy 280.061066 -14.202156)
			(xy 279.893892 -14.210131) (xy 279.726528 -14.210131) (xy 279.559354 -14.202156) (xy 279.39275 -14.186223)
			(xy 279.227094 -14.162369) (xy 279.062763 -14.130648) (xy 278.900131 -14.091133) (xy 278.739566 -14.043912)
			(xy 278.581434 -13.989093) (xy 278.426094 -13.926801) (xy 278.273899 -13.857178) (xy 278.125194 -13.78038)
			(xy 277.980318 -13.696584) (xy 277.8396 -13.60598) (xy 277.70336 -13.508772) (xy 277.571906 -13.405183)
			(xy 277.445538 -13.295447) (xy 277.324543 -13.179814) (xy 277.209196 -13.058546) (xy 277.099758 -12.93192)
			(xy 276.996479 -12.800222) (xy 276.899594 -12.663753) (xy 276.809321 -12.522821) (xy 276.725867 -12.377748)
			(xy 276.649421 -12.228863) (xy 276.580157 -12.076504) (xy 276.518231 -11.921017) (xy 276.463786 -11.762756)
			(xy 276.416944 -11.602081) (xy 276.377812 -11.439356) (xy 276.346479 -11.274951) (xy 276.323016 -11.109239)
			(xy 276.307476 -10.942598) (xy 276.299895 -10.775405) (xy 275.810641 -10.775405) (xy 275.810722 -10.789767)
			(xy 275.818776 -10.969113) (xy 275.834869 -11.147917) (xy 275.858967 -11.325819) (xy 275.891023 -11.502461)
			(xy 275.930971 -11.677487) (xy 275.978732 -11.850544) (xy 276.034209 -12.021284) (xy 276.09729 -12.189363)
			(xy 276.167849 -12.354443) (xy 276.245742 -12.516191) (xy 276.330815 -12.674281) (xy 276.422894 -12.828396)
			(xy 276.521794 -12.978224) (xy 276.627318 -13.123464) (xy 276.739251 -13.263824) (xy 276.857368 -13.39902)
			(xy 276.981433 -13.528781) (xy 277.111194 -13.652846) (xy 277.24639 -13.770963) (xy 277.38675 -13.882896)
			(xy 277.53199 -13.98842) (xy 277.681818 -14.08732) (xy 277.835933 -14.179399) (xy 277.994023 -14.264472)
			(xy 278.155771 -14.342365) (xy 278.320851 -14.412924) (xy 278.48893 -14.476005) (xy 278.65967 -14.531482)
			(xy 278.832727 -14.579243) (xy 279.007753 -14.619191) (xy 279.184395 -14.651247) (xy 279.362297 -14.675345)
			(xy 279.541101 -14.691438) (xy 279.720447 -14.699492) (xy 279.899973 -14.699492) (xy 280.079319 -14.691438)
			(xy 280.258123 -14.675345) (xy 280.436025 -14.651247) (xy 280.612667 -14.619191) (xy 280.787693 -14.579243)
			(xy 280.96075 -14.531482) (xy 281.13149 -14.476005) (xy 281.299569 -14.412924) (xy 281.464649 -14.342365)
			(xy 281.626397 -14.264472) (xy 281.784487 -14.179399) (xy 281.938602 -14.08732) (xy 282.08843 -13.98842)
			(xy 282.23367 -13.882896) (xy 282.37403 -13.770963) (xy 282.509226 -13.652846) (xy 282.638987 -13.528781)
			(xy 282.763052 -13.39902) (xy 282.881169 -13.263824) (xy 282.993102 -13.123464) (xy 283.098626 -12.978224)
			(xy 283.197526 -12.828396) (xy 283.289605 -12.674281) (xy 283.374678 -12.516191) (xy 283.452571 -12.354443)
			(xy 283.52313 -12.189363) (xy 283.586211 -12.021284) (xy 283.641688 -11.850544) (xy 283.689449 -11.677487)
			(xy 283.729397 -11.502461) (xy 283.761453 -11.325819) (xy 283.785551 -11.147917) (xy 283.801644 -10.969113)
			(xy 283.809698 -10.789767) (xy 283.810202 -10.700004) (xy 283.810202 -4.700016) (xy 283.809698 -4.610253)
			(xy 283.801644 -4.430907) (xy 283.785551 -4.252103) (xy 283.761453 -4.074201) (xy 283.729397 -3.897559)
			(xy 283.689449 -3.722533) (xy 283.641688 -3.549476) (xy 283.586211 -3.378736) (xy 283.52313 -3.210657)
			(xy 283.452571 -3.045577) (xy 283.374678 -2.883829) (xy 283.289605 -2.725739) (xy 283.197526 -2.571624)
			(xy 283.098626 -2.421796) (xy 282.993102 -2.276556) (xy 282.881169 -2.136196) (xy 282.763052 -2.001)
			(xy 282.638987 -1.871239) (xy 282.509226 -1.747174) (xy 282.37403 -1.629057) (xy 282.23367 -1.517124)
			(xy 282.08843 -1.4116) (xy 281.938602 -1.3127) (xy 281.784487 -1.220621) (xy 281.626397 -1.135548)
			(xy 281.464649 -1.057655) (xy 281.299569 -0.987096) (xy 281.13149 -0.924015) (xy 280.96075 -0.868538)
			(xy 280.787693 -0.820777) (xy 280.612667 -0.780829) (xy 280.436025 -0.748773) (xy 280.258123 -0.724675)
			(xy 280.079319 -0.708582) (xy 279.899973 -0.700528) (xy 279.720447 -0.700528) (xy 279.541101 -0.708582)
			(xy 279.362297 -0.724675) (xy 279.184395 -0.748773) (xy 279.007753 -0.780829) (xy 278.832727 -0.820777)
			(xy 278.65967 -0.868538) (xy 278.48893 -0.924015) (xy 278.320851 -0.987096) (xy 278.155771 -1.057655)
			(xy 277.994023 -1.135548) (xy 277.835933 -1.220621) (xy 277.681818 -1.3127) (xy 277.53199 -1.4116)
			(xy 277.38675 -1.517124) (xy 277.24639 -1.629057) (xy 277.111194 -1.747174) (xy 276.981433 -1.871239)
			(xy 276.857368 -2.001) (xy 276.739251 -2.136196) (xy 276.627318 -2.276556) (xy 276.521794 -2.421796)
			(xy 276.422894 -2.571624) (xy 276.330815 -2.725739) (xy 276.245742 -2.883829) (xy 276.167849 -3.045577)
			(xy 276.09729 -3.210657) (xy 276.034209 -3.378736) (xy 275.978732 -3.549476) (xy 275.930971 -3.722533)
			(xy 275.891023 -3.897559) (xy 275.858967 -4.074201) (xy 275.834869 -4.252103) (xy 275.818776 -4.430907)
			(xy 275.810722 -4.610253) (xy 275.810218 -4.700016)
		)
		(stroke
			(width 0)
			(type solid)
		)
		(fill yes)
		(layer "F.Cu")
		(net "GND")
	)
	(gr_poly
		(pts
			(xy 296.810176 -47.500032) (xy 296.810599 -47.575433) (xy 297.299853 -47.575433) (xy 297.300248 -47.408069)
			(xy 297.308618 -47.240915) (xy 297.324943 -47.074348) (xy 297.349188 -46.90875) (xy 297.381297 -46.744494)
			(xy 297.421196 -46.581955) (xy 297.468795 -46.421502) (xy 297.523987 -46.2635) (xy 297.586645 -46.108308)
			(xy 297.656627 -45.956277) (xy 297.733775 -45.807754) (xy 297.817913 -45.663076) (xy 297.908849 -45.522572)
			(xy 298.006378 -45.386561) (xy 298.110277 -45.255353) (xy 298.220311 -45.129244) (xy 298.336229 -45.008522)
			(xy 298.39666 -44.950634) (xy 298.420347 -44.927428) (xy 298.461905 -44.875757) (xy 298.496104 -44.818946)
			(xy 298.522317 -44.758037) (xy 298.540063 -44.694146) (xy 298.549017 -44.628443) (xy 298.549568 -44.595288)
			(xy 298.549568 -41.500044) (xy 298.550064 -41.43304) (xy 298.558003 -41.299268) (xy 298.573853 -41.166201)
			(xy 298.597557 -41.034306) (xy 298.629034 -40.904048) (xy 298.668172 -40.775883) (xy 298.714833 -40.650262)
			(xy 298.768855 -40.527625) (xy 298.830047 -40.408404) (xy 298.898194 -40.293018) (xy 298.973057 -40.181871)
			(xy 299.054373 -40.075355) (xy 299.141856 -39.973842) (xy 299.235199 -39.877691) (xy 299.334074 -39.787238)
			(xy 299.438134 -39.702801) (xy 299.547014 -39.624678) (xy 299.66033 -39.553141) (xy 299.777685 -39.488443)
			(xy 299.898667 -39.430811) (xy 300.022851 -39.380448) (xy 300.149799 -39.337529) (xy 300.279068 -39.302206)
			(xy 300.410202 -39.274604) (xy 300.542741 -39.254818) (xy 300.676219 -39.242919) (xy 300.810168 -39.238948)
			(xy 300.944117 -39.242919) (xy 301.077595 -39.254818) (xy 301.210134 -39.274604) (xy 301.341268 -39.302206)
			(xy 301.470537 -39.337529) (xy 301.597485 -39.380448) (xy 301.721669 -39.430811) (xy 301.842651 -39.488443)
			(xy 301.960006 -39.553141) (xy 302.073322 -39.624678) (xy 302.182202 -39.702801) (xy 302.286262 -39.787238)
			(xy 302.385137 -39.877691) (xy 302.47848 -39.973842) (xy 302.565963 -40.075355) (xy 302.647279 -40.181871)
			(xy 302.722142 -40.293018) (xy 302.790289 -40.408404) (xy 302.851481 -40.527625) (xy 302.905503 -40.650262)
			(xy 302.952164 -40.775883) (xy 302.991302 -40.904048) (xy 303.022779 -41.034306) (xy 303.046483 -41.166201)
			(xy 303.062333 -41.299268) (xy 303.070272 -41.43304) (xy 303.070768 -41.500044) (xy 303.070768 -44.595288)
			(xy 303.071348 -44.628441) (xy 303.080309 -44.69414) (xy 303.098054 -44.758028) (xy 303.12426 -44.818937)
			(xy 303.158446 -44.875752) (xy 303.199987 -44.927433) (xy 303.223676 -44.950634) (xy 303.284107 -45.008522)
			(xy 303.400025 -45.129244) (xy 303.510059 -45.255353) (xy 303.613958 -45.386561) (xy 303.711487 -45.522572)
			(xy 303.802423 -45.663076) (xy 303.886561 -45.807754) (xy 303.963709 -45.956277) (xy 304.033691 -46.108308)
			(xy 304.096349 -46.2635) (xy 304.151541 -46.421502) (xy 304.19914 -46.581955) (xy 304.239039 -46.744494)
			(xy 304.271148 -46.90875) (xy 304.295393 -47.074348) (xy 304.311718 -47.240915) (xy 304.320088 -47.408069)
			(xy 304.320483 -47.575433) (xy 304.312902 -47.742626) (xy 304.297362 -47.909267) (xy 304.273899 -48.074979)
			(xy 304.242566 -48.239384) (xy 304.203434 -48.402109) (xy 304.156592 -48.562784) (xy 304.102147 -48.721045)
			(xy 304.040221 -48.876532) (xy 303.970957 -49.028891) (xy 303.894511 -49.177776) (xy 303.811057 -49.322849)
			(xy 303.720784 -49.463781) (xy 303.623899 -49.60025) (xy 303.52062 -49.731948) (xy 303.411182 -49.858574)
			(xy 303.295835 -49.979842) (xy 303.17484 -50.095475) (xy 303.048472 -50.205211) (xy 302.917018 -50.3088)
			(xy 302.780778 -50.406008) (xy 302.64006 -50.496612) (xy 302.495184 -50.580408) (xy 302.346479 -50.657206)
			(xy 302.194284 -50.726829) (xy 302.038944 -50.789121) (xy 301.880812 -50.84394) (xy 301.720247 -50.891161)
			(xy 301.557615 -50.930676) (xy 301.393284 -50.962397) (xy 301.227628 -50.986251) (xy 301.061024 -51.002184)
			(xy 300.89385 -51.010159) (xy 300.726486 -51.010159) (xy 300.559312 -51.002184) (xy 300.392708 -50.986251)
			(xy 300.227052 -50.962397) (xy 300.062721 -50.930676) (xy 299.900089 -50.891161) (xy 299.739524 -50.84394)
			(xy 299.581392 -50.789121) (xy 299.426052 -50.726829) (xy 299.273857 -50.657206) (xy 299.125152 -50.580408)
			(xy 298.980276 -50.496612) (xy 298.839558 -50.406008) (xy 298.703318 -50.3088) (xy 298.571864 -50.205211)
			(xy 298.445496 -50.095475) (xy 298.324501 -49.979842) (xy 298.209154 -49.858574) (xy 298.099716 -49.731948)
			(xy 297.996437 -49.60025) (xy 297.899552 -49.463781) (xy 297.809279 -49.322849) (xy 297.725825 -49.177776)
			(xy 297.649379 -49.028891) (xy 297.580115 -48.876532) (xy 297.518189 -48.721045) (xy 297.463744 -48.562784)
			(xy 297.416902 -48.402109) (xy 297.37777 -48.239384) (xy 297.346437 -48.074979) (xy 297.322974 -47.909267)
			(xy 297.307434 -47.742626) (xy 297.299853 -47.575433) (xy 296.810599 -47.575433) (xy 296.81068 -47.589795)
			(xy 296.818734 -47.769141) (xy 296.834827 -47.947945) (xy 296.858925 -48.125847) (xy 296.890981 -48.302489)
			(xy 296.930929 -48.477515) (xy 296.97869 -48.650572) (xy 297.034167 -48.821312) (xy 297.097248 -48.989391)
			(xy 297.167807 -49.154471) (xy 297.2457 -49.316219) (xy 297.330773 -49.474309) (xy 297.422852 -49.628424)
			(xy 297.521752 -49.778252) (xy 297.627276 -49.923492) (xy 297.739209 -50.063852) (xy 297.857326 -50.199048)
			(xy 297.981391 -50.328809) (xy 298.111152 -50.452874) (xy 298.246348 -50.570991) (xy 298.386708 -50.682924)
			(xy 298.531948 -50.788448) (xy 298.681776 -50.887348) (xy 298.835891 -50.979427) (xy 298.993981 -51.0645)
			(xy 299.155729 -51.142393) (xy 299.320809 -51.212952) (xy 299.488888 -51.276033) (xy 299.659628 -51.33151)
			(xy 299.832685 -51.379271) (xy 300.007711 -51.419219) (xy 300.184353 -51.451275) (xy 300.362255 -51.475373)
			(xy 300.541059 -51.491466) (xy 300.720405 -51.49952) (xy 300.899931 -51.49952) (xy 301.079277 -51.491466)
			(xy 301.258081 -51.475373) (xy 301.435983 -51.451275) (xy 301.612625 -51.419219) (xy 301.787651 -51.379271)
			(xy 301.960708 -51.33151) (xy 302.131448 -51.276033) (xy 302.299527 -51.212952) (xy 302.464607 -51.142393)
			(xy 302.626355 -51.0645) (xy 302.784445 -50.979427) (xy 302.93856 -50.887348) (xy 303.088388 -50.788448)
			(xy 303.233628 -50.682924) (xy 303.373988 -50.570991) (xy 303.509184 -50.452874) (xy 303.638945 -50.328809)
			(xy 303.76301 -50.199048) (xy 303.881127 -50.063852) (xy 303.99306 -49.923492) (xy 304.098584 -49.778252)
			(xy 304.197484 -49.628424) (xy 304.289563 -49.474309) (xy 304.374636 -49.316219) (xy 304.452529 -49.154471)
			(xy 304.523088 -48.989391) (xy 304.586169 -48.821312) (xy 304.641646 -48.650572) (xy 304.689407 -48.477515)
			(xy 304.729355 -48.302489) (xy 304.761411 -48.125847) (xy 304.785509 -47.947945) (xy 304.801602 -47.769141)
			(xy 304.809656 -47.589795) (xy 304.81016 -47.500032) (xy 304.81016 -41.500044) (xy 304.809656 -41.410281)
			(xy 304.801602 -41.230935) (xy 304.785509 -41.052131) (xy 304.761411 -40.874229) (xy 304.729355 -40.697587)
			(xy 304.689407 -40.522561) (xy 304.641646 -40.349504) (xy 304.586169 -40.178764) (xy 304.523088 -40.010685)
			(xy 304.452529 -39.845605) (xy 304.374636 -39.683857) (xy 304.289563 -39.525767) (xy 304.197484 -39.371652)
			(xy 304.098584 -39.221824) (xy 303.99306 -39.076584) (xy 303.881127 -38.936224) (xy 303.76301 -38.801028)
			(xy 303.638945 -38.671267) (xy 303.509184 -38.547202) (xy 303.373988 -38.429085) (xy 303.233628 -38.317152)
			(xy 303.088388 -38.211628) (xy 302.93856 -38.112728) (xy 302.784445 -38.020649) (xy 302.626355 -37.935576)
			(xy 302.464607 -37.857683) (xy 302.299527 -37.787124) (xy 302.131448 -37.724043) (xy 301.960708 -37.668566)
			(xy 301.787651 -37.620805) (xy 301.612625 -37.580857) (xy 301.435983 -37.548801) (xy 301.258081 -37.524703)
			(xy 301.079277 -37.50861) (xy 300.899931 -37.500556) (xy 300.720405 -37.500556) (xy 300.541059 -37.50861)
			(xy 300.362255 -37.524703) (xy 300.184353 -37.548801) (xy 300.007711 -37.580857) (xy 299.832685 -37.620805)
			(xy 299.659628 -37.668566) (xy 299.488888 -37.724043) (xy 299.320809 -37.787124) (xy 299.155729 -37.857683)
			(xy 298.993981 -37.935576) (xy 298.835891 -38.020649) (xy 298.681776 -38.112728) (xy 298.531948 -38.211628)
			(xy 298.386708 -38.317152) (xy 298.246348 -38.429085) (xy 298.111152 -38.547202) (xy 297.981391 -38.671267)
			(xy 297.857326 -38.801028) (xy 297.739209 -38.936224) (xy 297.627276 -39.076584) (xy 297.521752 -39.221824)
			(xy 297.422852 -39.371652) (xy 297.330773 -39.525767) (xy 297.2457 -39.683857) (xy 297.167807 -39.845605)
			(xy 297.097248 -40.010685) (xy 297.034167 -40.178764) (xy 296.97869 -40.349504) (xy 296.930929 -40.522561)
			(xy 296.890981 -40.697587) (xy 296.858925 -40.874229) (xy 296.834827 -41.052131) (xy 296.818734 -41.230935)
			(xy 296.81068 -41.410281) (xy 296.810176 -41.500044)
		)
		(stroke
			(width 0)
			(type solid)
		)
		(fill yes)
		(layer "F.Cu")
		(net "GND")
	)
	(gr_poly
		(pts
			(xy 40.875204 -51.6128) (xy 40.891852 -51.612256) (xy 40.924013 -51.603638) (xy 40.952848 -51.586989)
			(xy 40.976392 -51.563445) (xy 40.993039 -51.53461) (xy 41.001657 -51.502448) (xy 41.002204 -51.4858)
			(xy 41.002204 -45.449236) (xy 41.552368 -45.449236) (xy 41.552368 -51.4858) (xy 41.552911 -51.50245)
			(xy 41.561528 -51.534615) (xy 41.578176 -51.563455) (xy 41.601719 -51.587005) (xy 41.630555 -51.603659)
			(xy 41.662718 -51.612285) (xy 41.679368 -51.6128) (xy 50.7492 -51.6128) (xy 51.054 -51.308) (xy 51.054 -44.8056)
			(xy 50.3174 -44.069) (xy 50.3174 -41.4782) (xy 51.9176 -39.878) (xy 56.896 -39.878) (xy 57.541261 -40.523261)
			(xy 63.423792 -40.523261) (xy 63.423792 -40.451939) (xy 63.431778 -40.381065) (xy 63.447648 -40.31153)
			(xy 63.471205 -40.24421) (xy 63.50215 -40.179951) (xy 63.540096 -40.11956) (xy 63.584565 -40.063798)
			(xy 63.634998 -40.013365) (xy 63.69076 -39.968896) (xy 63.751151 -39.93095) (xy 63.81541 -39.900005)
			(xy 63.88273 -39.876448) (xy 63.952265 -39.860578) (xy 64.023139 -39.852592) (xy 64.0588 -39.852092)
			(xy 64.094461 -39.852592) (xy 64.165335 -39.860578) (xy 64.23487 -39.876448) (xy 64.30219 -39.900005)
			(xy 64.366449 -39.93095) (xy 64.42684 -39.968896) (xy 64.482602 -40.013365) (xy 64.533035 -40.063798)
			(xy 64.577504 -40.11956) (xy 64.61545 -40.179951) (xy 64.646395 -40.24421) (xy 64.669952 -40.31153)
			(xy 64.685822 -40.381065) (xy 64.693808 -40.451939) (xy 64.693808 -40.523261) (xy 64.685822 -40.594135)
			(xy 64.678809 -40.624861) (xy 70.484992 -40.624861) (xy 70.484992 -40.553539) (xy 70.492978 -40.482665)
			(xy 70.508848 -40.41313) (xy 70.532405 -40.34581) (xy 70.56335 -40.281551) (xy 70.601296 -40.22116)
			(xy 70.645765 -40.165398) (xy 70.696198 -40.114965) (xy 70.75196 -40.070496) (xy 70.812351 -40.03255)
			(xy 70.87661 -40.001605) (xy 70.94393 -39.978048) (xy 71.013465 -39.962178) (xy 71.084339 -39.954192)
			(xy 71.12 -39.953692) (xy 71.155661 -39.954192) (xy 71.226535 -39.962178) (xy 71.29607 -39.978048)
			(xy 71.36339 -40.001605) (xy 71.427649 -40.03255) (xy 71.48804 -40.070496) (xy 71.543802 -40.114965)
			(xy 71.594235 -40.165398) (xy 71.638704 -40.22116) (xy 71.67665 -40.281551) (xy 71.707595 -40.34581)
			(xy 71.731152 -40.41313) (xy 71.747022 -40.482665) (xy 71.755008 -40.553539) (xy 71.755008 -40.624861)
			(xy 71.747022 -40.695735) (xy 71.731152 -40.76527) (xy 71.707595 -40.83259) (xy 71.67665 -40.896849)
			(xy 71.638704 -40.95724) (xy 71.594235 -41.013002) (xy 71.543802 -41.063435) (xy 71.48804 -41.107904)
			(xy 71.427649 -41.14585) (xy 71.36339 -41.176795) (xy 71.29607 -41.200352) (xy 71.226535 -41.216222)
			(xy 71.155661 -41.224208) (xy 71.084339 -41.224208) (xy 71.013465 -41.216222) (xy 70.94393 -41.200352)
			(xy 70.87661 -41.176795) (xy 70.812351 -41.14585) (xy 70.75196 -41.107904) (xy 70.696198 -41.063435)
			(xy 70.645765 -41.013002) (xy 70.601296 -40.95724) (xy 70.56335 -40.896849) (xy 70.532405 -40.83259)
			(xy 70.508848 -40.76527) (xy 70.492978 -40.695735) (xy 70.484992 -40.624861) (xy 64.678809 -40.624861)
			(xy 64.669952 -40.66367) (xy 64.646395 -40.73099) (xy 64.61545 -40.795249) (xy 64.577504 -40.85564)
			(xy 64.533035 -40.911402) (xy 64.482602 -40.961835) (xy 64.42684 -41.006304) (xy 64.366449 -41.04425)
			(xy 64.30219 -41.075195) (xy 64.23487 -41.098752) (xy 64.165335 -41.114622) (xy 64.094461 -41.122608)
			(xy 64.023139 -41.122608) (xy 63.952265 -41.114622) (xy 63.88273 -41.098752) (xy 63.81541 -41.075195)
			(xy 63.751151 -41.04425) (xy 63.69076 -41.006304) (xy 63.634998 -40.961835) (xy 63.584565 -40.911402)
			(xy 63.540096 -40.85564) (xy 63.50215 -40.795249) (xy 63.471205 -40.73099) (xy 63.447648 -40.66367)
			(xy 63.431778 -40.594135) (xy 63.423792 -40.523261) (xy 57.541261 -40.523261) (xy 58.5724 -41.5544)
			(xy 58.5724 -45.730261) (xy 63.576192 -45.730261) (xy 63.576192 -45.658939) (xy 63.584178 -45.588065)
			(xy 63.600048 -45.51853) (xy 63.623605 -45.45121) (xy 63.65455 -45.386951) (xy 63.692496 -45.32656)
			(xy 63.736965 -45.270798) (xy 63.787398 -45.220365) (xy 63.84316 -45.175896) (xy 63.903551 -45.13795)
			(xy 63.96781 -45.107005) (xy 64.03513 -45.083448) (xy 64.104665 -45.067578) (xy 64.175539 -45.059592)
			(xy 64.2112 -45.059092) (xy 64.246861 -45.059592) (xy 64.317735 -45.067578) (xy 64.38727 -45.083448)
			(xy 64.45459 -45.107005) (xy 64.518849 -45.13795) (xy 64.57924 -45.175896) (xy 64.635002 -45.220365)
			(xy 64.685435 -45.270798) (xy 64.729904 -45.32656) (xy 64.76785 -45.386951) (xy 64.798795 -45.45121)
			(xy 64.822352 -45.51853) (xy 64.838222 -45.588065) (xy 64.846208 -45.658939) (xy 64.846208 -45.730261)
			(xy 64.838222 -45.801135) (xy 64.822352 -45.87067) (xy 64.80038 -45.933461) (xy 70.738992 -45.933461)
			(xy 70.738992 -45.862139) (xy 70.746978 -45.791265) (xy 70.762848 -45.72173) (xy 70.786405 -45.65441)
			(xy 70.81735 -45.590151) (xy 70.855296 -45.52976) (xy 70.899765 -45.473998) (xy 70.950198 -45.423565)
			(xy 71.00596 -45.379096) (xy 71.066351 -45.34115) (xy 71.13061 -45.310205) (xy 71.19793 -45.286648)
			(xy 71.267465 -45.270778) (xy 71.338339 -45.262792) (xy 71.374 -45.262292) (xy 71.409661 -45.262792)
			(xy 71.480535 -45.270778) (xy 71.55007 -45.286648) (xy 71.61739 -45.310205) (xy 71.681649 -45.34115)
			(xy 71.74204 -45.379096) (xy 71.797802 -45.423565) (xy 71.848235 -45.473998) (xy 71.892704 -45.52976)
			(xy 71.93065 -45.590151) (xy 71.961595 -45.65441) (xy 71.985152 -45.72173) (xy 72.001022 -45.791265)
			(xy 72.009008 -45.862139) (xy 72.009008 -45.933461) (xy 72.001022 -46.004335) (xy 71.985152 -46.07387)
			(xy 71.961595 -46.14119) (xy 71.93065 -46.205449) (xy 71.892704 -46.26584) (xy 71.848235 -46.321602)
			(xy 71.797802 -46.372035) (xy 71.74204 -46.416504) (xy 71.681649 -46.45445) (xy 71.61739 -46.485395)
			(xy 71.55007 -46.508952) (xy 71.480535 -46.524822) (xy 71.409661 -46.532808) (xy 71.338339 -46.532808)
			(xy 71.267465 -46.524822) (xy 71.19793 -46.508952) (xy 71.13061 -46.485395) (xy 71.066351 -46.45445)
			(xy 71.00596 -46.416504) (xy 70.950198 -46.372035) (xy 70.899765 -46.321602) (xy 70.855296 -46.26584)
			(xy 70.81735 -46.205449) (xy 70.786405 -46.14119) (xy 70.762848 -46.07387) (xy 70.746978 -46.004335)
			(xy 70.738992 -45.933461) (xy 64.80038 -45.933461) (xy 64.798795 -45.93799) (xy 64.76785 -46.002249)
			(xy 64.729904 -46.06264) (xy 64.685435 -46.118402) (xy 64.635002 -46.168835) (xy 64.57924 -46.213304)
			(xy 64.518849 -46.25125) (xy 64.45459 -46.282195) (xy 64.38727 -46.305752) (xy 64.317735 -46.321622)
			(xy 64.246861 -46.329608) (xy 64.175539 -46.329608) (xy 64.104665 -46.321622) (xy 64.03513 -46.305752)
			(xy 63.96781 -46.282195) (xy 63.903551 -46.25125) (xy 63.84316 -46.213304) (xy 63.787398 -46.168835)
			(xy 63.736965 -46.118402) (xy 63.692496 -46.06264) (xy 63.65455 -46.002249) (xy 63.623605 -45.93799)
			(xy 63.600048 -45.87067) (xy 63.584178 -45.801135) (xy 63.576192 -45.730261) (xy 58.5724 -45.730261)
			(xy 58.5724 -48.2854) (xy 60.4774 -50.1904) (xy 76.942696 -50.1904) (xy 76.964949 -50.18994) (xy 77.008774 -50.182191)
			(xy 77.050581 -50.166929) (xy 77.089092 -50.144621) (xy 77.123129 -50.115948) (xy 77.151654 -50.081786)
			(xy 77.173795 -50.043179) (xy 77.188875 -50.001306) (xy 77.196434 -49.957447) (xy 77.19624 -49.912942)
			(xy 77.188299 -49.869151) (xy 77.172855 -49.827412) (xy 77.150379 -49.788999) (xy 77.136244 -49.771808)
			(xy 77.082765 -49.708109) (xy 76.981192 -49.576383) (xy 76.885974 -49.439991) (xy 76.797327 -49.29924)
			(xy 76.71545 -49.154446) (xy 76.640526 -49.005935) (xy 76.572724 -48.85404) (xy 76.512197 -48.699103)
			(xy 76.459079 -48.541472) (xy 76.413491 -48.3815) (xy 76.375536 -48.219548) (xy 76.345297 -48.05598)
			(xy 76.322844 -47.891162) (xy 76.308227 -47.725465) (xy 76.301478 -47.559262) (xy 76.302613 -47.392925)
			(xy 76.311629 -47.226829) (xy 76.328506 -47.061347) (xy 76.353206 -46.896851) (xy 76.385674 -46.73371)
			(xy 76.425836 -46.572291) (xy 76.473603 -46.412957) (xy 76.528866 -46.256065) (xy 76.591502 -46.101968)
			(xy 76.661371 -45.951013) (xy 76.738314 -45.803538) (xy 76.82216 -45.659875) (xy 76.912719 -45.520347)
			(xy 77.009789 -45.385267) (xy 77.113151 -45.254939) (xy 77.222573 -45.129656) (xy 77.337809 -45.009698)
			(xy 77.397864 -44.952158) (xy 77.421653 -44.92886) (xy 77.463365 -44.876958) (xy 77.497684 -44.819897)
			(xy 77.523982 -44.758725) (xy 77.541776 -44.694561) (xy 77.550741 -44.628581) (xy 77.55128 -44.595288)
			(xy 77.55128 -41.500044) (xy 77.551776 -41.433093) (xy 77.559709 -41.299426) (xy 77.575546 -41.166463)
			(xy 77.599232 -41.034673) (xy 77.630683 -40.904517) (xy 77.669791 -40.776453) (xy 77.716415 -40.65093)
			(xy 77.770395 -40.52839) (xy 77.831538 -40.409263) (xy 77.899632 -40.293967) (xy 77.974436 -40.182908)
			(xy 78.055688 -40.076475) (xy 78.143102 -39.975043) (xy 78.236372 -39.878967) (xy 78.335169 -39.788585)
			(xy 78.439148 -39.704215) (xy 78.547941 -39.626153) (xy 78.661168 -39.554673) (xy 78.778431 -39.490026)
			(xy 78.899318 -39.432439) (xy 79.023404 -39.382115) (xy 79.150253 -39.33923) (xy 79.27942 -39.303935)
			(xy 79.410451 -39.276354) (xy 79.542885 -39.256584) (xy 79.676259 -39.244694) (xy 79.810102 -39.240726)
			(xy 79.943945 -39.244694) (xy 80.077319 -39.256584) (xy 80.209753 -39.276354) (xy 80.340784 -39.303935)
			(xy 80.469951 -39.33923) (xy 80.5968 -39.382115) (xy 80.720886 -39.432439) (xy 80.841773 -39.490026)
			(xy 80.959036 -39.554673) (xy 81.072263 -39.626153) (xy 81.181056 -39.704215) (xy 81.285035 -39.788585)
			(xy 81.383832 -39.878967) (xy 81.477102 -39.975043) (xy 81.564516 -40.076475) (xy 81.645768 -40.182908)
			(xy 81.720572 -40.293967) (xy 81.788666 -40.409263) (xy 81.849809 -40.52839) (xy 81.903789 -40.65093)
			(xy 81.950413 -40.776453) (xy 81.989521 -40.904517) (xy 82.020972 -41.034673) (xy 82.038619 -41.132861)
			(xy 88.264992 -41.132861) (xy 88.264992 -41.061539) (xy 88.272978 -40.990665) (xy 88.288848 -40.92113)
			(xy 88.312405 -40.85381) (xy 88.34335 -40.789551) (xy 88.381296 -40.72916) (xy 88.425765 -40.673398)
			(xy 88.476198 -40.622965) (xy 88.53196 -40.578496) (xy 88.592351 -40.54055) (xy 88.65661 -40.509605)
			(xy 88.72393 -40.486048) (xy 88.793465 -40.470178) (xy 88.864339 -40.462192) (xy 88.9 -40.461692)
			(xy 88.935661 -40.462192) (xy 89.006535 -40.470178) (xy 89.07607 -40.486048) (xy 89.14339 -40.509605)
			(xy 89.207649 -40.54055) (xy 89.26804 -40.578496) (xy 89.323802 -40.622965) (xy 89.374235 -40.673398)
			(xy 89.418704 -40.72916) (xy 89.45665 -40.789551) (xy 89.487595 -40.85381) (xy 89.511152 -40.92113)
			(xy 89.527022 -40.990665) (xy 89.535008 -41.061539) (xy 89.535008 -41.132861) (xy 89.527022 -41.203735)
			(xy 89.511152 -41.27327) (xy 89.487595 -41.34059) (xy 89.45665 -41.404849) (xy 89.418704 -41.46524)
			(xy 89.374235 -41.521002) (xy 89.323802 -41.571435) (xy 89.26804 -41.615904) (xy 89.207649 -41.65385)
			(xy 89.14339 -41.684795) (xy 89.07607 -41.708352) (xy 89.006535 -41.724222) (xy 88.935661 -41.732208)
			(xy 88.864339 -41.732208) (xy 88.793465 -41.724222) (xy 88.72393 -41.708352) (xy 88.65661 -41.684795)
			(xy 88.592351 -41.65385) (xy 88.53196 -41.615904) (xy 88.476198 -41.571435) (xy 88.425765 -41.521002)
			(xy 88.381296 -41.46524) (xy 88.34335 -41.404849) (xy 88.312405 -41.34059) (xy 88.288848 -41.27327)
			(xy 88.272978 -41.203735) (xy 88.264992 -41.132861) (xy 82.038619 -41.132861) (xy 82.044658 -41.166463)
			(xy 82.060495 -41.299426) (xy 82.068428 -41.433093) (xy 82.068924 -41.500044) (xy 82.06867 -44.595288)
			(xy 82.069218 -44.628591) (xy 82.078209 -44.694588) (xy 82.09604 -44.758763) (xy 82.122383 -44.819938)
			(xy 82.156756 -44.876989) (xy 82.198527 -44.92887) (xy 82.202789 -44.933038) (xy 115.78564 -44.933038)
			(xy 115.78564 -44.805162) (xy 115.793669 -44.677538) (xy 115.809697 -44.55067) (xy 115.833658 -44.425058)
			(xy 115.86546 -44.3012) (xy 115.904976 -44.179582) (xy 115.95205 -44.060685) (xy 116.006497 -43.944979)
			(xy 116.068102 -43.83292) (xy 116.136622 -43.724951) (xy 116.211786 -43.621497) (xy 116.293297 -43.522966)
			(xy 116.380834 -43.429748) (xy 116.474052 -43.342211) (xy 116.572583 -43.2607) (xy 116.676037 -43.185536)
			(xy 116.784006 -43.117016) (xy 116.896065 -43.055411) (xy 117.011771 -43.000964) (xy 117.130668 -42.95389)
			(xy 117.252286 -42.914374) (xy 117.376144 -42.882572) (xy 117.501756 -42.858611) (xy 117.628624 -42.842583)
			(xy 117.756248 -42.834554) (xy 117.820186 -42.834052) (xy 117.884124 -42.834554) (xy 118.011748 -42.842583)
			(xy 118.138616 -42.858611) (xy 118.264228 -42.882572) (xy 118.388086 -42.914374) (xy 118.509704 -42.95389)
			(xy 118.628601 -43.000964) (xy 118.744307 -43.055411) (xy 118.856366 -43.117016) (xy 118.964335 -43.185536)
			(xy 119.067789 -43.2607) (xy 119.16632 -43.342211) (xy 119.259538 -43.429748) (xy 119.347075 -43.522966)
			(xy 119.428586 -43.621497) (xy 119.50375 -43.724951) (xy 119.57227 -43.83292) (xy 119.633875 -43.944979)
			(xy 119.688322 -44.060685) (xy 119.735396 -44.179582) (xy 119.774912 -44.3012) (xy 119.806714 -44.425058)
			(xy 119.830675 -44.55067) (xy 119.846703 -44.677538) (xy 119.854732 -44.805162) (xy 119.854732 -44.932982)
			(xy 127.217418 -44.932982) (xy 127.217418 -44.805218) (xy 127.22544 -44.677705) (xy 127.241453 -44.550948)
			(xy 127.265394 -44.425446) (xy 127.297168 -44.301696) (xy 127.336649 -44.180184) (xy 127.383682 -44.061392)
			(xy 127.438082 -43.945787) (xy 127.499633 -43.833826) (xy 127.568093 -43.725951) (xy 127.643191 -43.622587)
			(xy 127.724631 -43.524142) (xy 127.812092 -43.431006) (xy 127.905228 -43.343545) (xy 128.003673 -43.262105)
			(xy 128.107037 -43.187007) (xy 128.214912 -43.118547) (xy 128.326873 -43.056996) (xy 128.442478 -43.002596)
			(xy 128.56127 -42.955563) (xy 128.682782 -42.916082) (xy 128.806532 -42.884308) (xy 128.932034 -42.860367)
			(xy 129.058791 -42.844354) (xy 129.186304 -42.836332) (xy 129.250186 -42.83583) (xy 129.314068 -42.836332)
			(xy 129.441581 -42.844354) (xy 129.568338 -42.860367) (xy 129.69384 -42.884308) (xy 129.81759 -42.916082)
			(xy 129.939102 -42.955563) (xy 130.057894 -43.002596) (xy 130.173499 -43.056996) (xy 130.28546 -43.118547)
			(xy 130.393335 -43.187007) (xy 130.496699 -43.262105) (xy 130.595144 -43.343545) (xy 130.68828 -43.431006)
			(xy 130.775741 -43.524142) (xy 130.857181 -43.622587) (xy 130.932279 -43.725951) (xy 131.000739 -43.833826)
			(xy 131.06229 -43.945787) (xy 131.11669 -44.061392) (xy 131.163723 -44.180184) (xy 131.203204 -44.301696)
			(xy 131.234978 -44.425446) (xy 131.258919 -44.550948) (xy 131.274932 -44.677705) (xy 131.282954 -44.805218)
			(xy 131.282954 -44.932982) (xy 131.274932 -45.060495) (xy 131.258919 -45.187252) (xy 131.234978 -45.312754)
			(xy 131.203204 -45.436504) (xy 131.163723 -45.558016) (xy 131.11669 -45.676808) (xy 131.06229 -45.792413)
			(xy 131.000739 -45.904374) (xy 130.932279 -46.012249) (xy 130.857181 -46.115613) (xy 130.775741 -46.214058)
			(xy 130.68828 -46.307194) (xy 130.595144 -46.394655) (xy 130.496699 -46.476095) (xy 130.393335 -46.551193)
			(xy 130.28546 -46.619653) (xy 130.173499 -46.681204) (xy 130.057894 -46.735604) (xy 129.939102 -46.782637)
			(xy 129.81759 -46.822118) (xy 129.69384 -46.853892) (xy 129.568338 -46.877833) (xy 129.441581 -46.893846)
			(xy 129.314068 -46.901868) (xy 129.186304 -46.901868) (xy 129.058791 -46.893846) (xy 128.932034 -46.877833)
			(xy 128.806532 -46.853892) (xy 128.682782 -46.822118) (xy 128.56127 -46.782637) (xy 128.442478 -46.735604)
			(xy 128.326873 -46.681204) (xy 128.214912 -46.619653) (xy 128.107037 -46.551193) (xy 128.003673 -46.476095)
			(xy 127.905228 -46.394655) (xy 127.812092 -46.307194) (xy 127.724631 -46.214058) (xy 127.643191 -46.115613)
			(xy 127.568093 -46.012249) (xy 127.499633 -45.904374) (xy 127.438082 -45.792413) (xy 127.383682 -45.676808)
			(xy 127.336649 -45.558016) (xy 127.297168 -45.436504) (xy 127.265394 -45.312754) (xy 127.241453 -45.187252)
			(xy 127.22544 -45.060495) (xy 127.217418 -44.932982) (xy 119.854732 -44.932982) (xy 119.854732 -44.933038)
			(xy 119.846703 -45.060662) (xy 119.830675 -45.18753) (xy 119.806714 -45.313142) (xy 119.774912 -45.437)
			(xy 119.735396 -45.558618) (xy 119.688322 -45.677515) (xy 119.633875 -45.793221) (xy 119.57227 -45.90528)
			(xy 119.50375 -46.013249) (xy 119.428586 -46.116703) (xy 119.347075 -46.215234) (xy 119.259538 -46.308452)
			(xy 119.16632 -46.395989) (xy 119.067789 -46.4775) (xy 118.964335 -46.552664) (xy 118.856366 -46.621184)
			(xy 118.744307 -46.682789) (xy 118.628601 -46.737236) (xy 118.509704 -46.78431) (xy 118.388086 -46.823826)
			(xy 118.264228 -46.855628) (xy 118.138616 -46.879589) (xy 118.011748 -46.895617) (xy 117.884124 -46.903646)
			(xy 117.756248 -46.903646) (xy 117.628624 -46.895617) (xy 117.501756 -46.879589) (xy 117.376144 -46.855628)
			(xy 117.252286 -46.823826) (xy 117.130668 -46.78431) (xy 117.011771 -46.737236) (xy 116.896065 -46.682789)
			(xy 116.784006 -46.621184) (xy 116.676037 -46.552664) (xy 116.572583 -46.4775) (xy 116.474052 -46.395989)
			(xy 116.380834 -46.308452) (xy 116.293297 -46.215234) (xy 116.211786 -46.116703) (xy 116.136622 -46.013249)
			(xy 116.068102 -45.90528) (xy 116.006497 -45.793221) (xy 115.95205 -45.677515) (xy 115.904976 -45.558618)
			(xy 115.86546 -45.437) (xy 115.833658 -45.313142) (xy 115.809697 -45.18753) (xy 115.793669 -45.060662)
			(xy 115.78564 -44.933038) (xy 82.202789 -44.933038) (xy 82.22234 -44.952158) (xy 82.2824 -45.009694)
			(xy 82.397637 -45.129651) (xy 82.507059 -45.254934) (xy 82.610422 -45.385262) (xy 82.707493 -45.520342)
			(xy 82.798053 -45.65987) (xy 82.881899 -45.803533) (xy 82.958843 -45.951008) (xy 82.997746 -46.035061)
			(xy 88.315792 -46.035061) (xy 88.315792 -45.963739) (xy 88.323778 -45.892865) (xy 88.339648 -45.82333)
			(xy 88.363205 -45.75601) (xy 88.39415 -45.691751) (xy 88.432096 -45.63136) (xy 88.476565 -45.575598)
			(xy 88.526998 -45.525165) (xy 88.58276 -45.480696) (xy 88.643151 -45.44275) (xy 88.70741 -45.411805)
			(xy 88.77473 -45.388248) (xy 88.844265 -45.372378) (xy 88.915139 -45.364392) (xy 88.9508 -45.363892)
			(xy 88.986461 -45.364392) (xy 89.057335 -45.372378) (xy 89.12687 -45.388248) (xy 89.19419 -45.411805)
			(xy 89.258449 -45.44275) (xy 89.31884 -45.480696) (xy 89.374602 -45.525165) (xy 89.425035 -45.575598)
			(xy 89.469504 -45.63136) (xy 89.50745 -45.691751) (xy 89.538395 -45.75601) (xy 89.561952 -45.82333)
			(xy 89.577822 -45.892865) (xy 89.585808 -45.963739) (xy 89.585808 -46.035061) (xy 89.577822 -46.105935)
			(xy 89.561952 -46.17547) (xy 89.538395 -46.24279) (xy 89.50745 -46.307049) (xy 89.469504 -46.36744)
			(xy 89.425035 -46.423202) (xy 89.374602 -46.473635) (xy 89.31884 -46.518104) (xy 89.258449 -46.55605)
			(xy 89.19419 -46.586995) (xy 89.12687 -46.610552) (xy 89.057335 -46.626422) (xy 88.986461 -46.634408)
			(xy 88.915139 -46.634408) (xy 88.844265 -46.626422) (xy 88.77473 -46.610552) (xy 88.70741 -46.586995)
			(xy 88.643151 -46.55605) (xy 88.58276 -46.518104) (xy 88.526998 -46.473635) (xy 88.476565 -46.423202)
			(xy 88.432096 -46.36744) (xy 88.39415 -46.307049) (xy 88.363205 -46.24279) (xy 88.339648 -46.17547)
			(xy 88.323778 -46.105935) (xy 88.315792 -46.035061) (xy 82.997746 -46.035061) (xy 83.028711 -46.101963)
			(xy 83.091348 -46.25606) (xy 83.146612 -46.412952) (xy 83.194378 -46.572287) (xy 83.234541 -46.733706)
			(xy 83.267008 -46.896847) (xy 83.291708 -47.061344) (xy 83.308585 -47.226826) (xy 83.317601 -47.392922)
			(xy 83.318736 -47.559259) (xy 83.311987 -47.725463) (xy 83.297369 -47.89116) (xy 83.274915 -48.055978)
			(xy 83.244676 -48.219547) (xy 83.206719 -48.381499) (xy 83.161131 -48.541471) (xy 83.108013 -48.699102)
			(xy 83.047484 -48.85404) (xy 82.979681 -49.005934) (xy 82.904756 -49.154445) (xy 82.822877 -49.299238)
			(xy 82.734229 -49.439989) (xy 82.639011 -49.57638) (xy 82.537435 -49.708106) (xy 82.48396 -49.771808)
			(xy 82.469891 -49.789055) (xy 82.447396 -49.827456) (xy 82.431935 -49.869188) (xy 82.423979 -49.912976)
			(xy 82.423774 -49.95748) (xy 82.431324 -50.00134) (xy 82.446399 -50.043213) (xy 82.468538 -50.081821)
			(xy 82.497063 -50.115981) (xy 82.531104 -50.14465) (xy 82.569618 -50.166951) (xy 82.611428 -50.182201)
			(xy 82.655255 -50.189936) (xy 82.677508 -50.1904) (xy 94.488 -50.1904) (xy 96.2914 -48.387) (xy 96.323658 -48.387)
			(xy 96.340316 -48.38651) (xy 96.3725 -48.377896) (xy 96.401357 -48.361244) (xy 96.424919 -48.33769)
			(xy 96.44158 -48.308839) (xy 96.450205 -48.276658) (xy 96.450658 -48.26) (xy 112.1664 -48.26) (xy 112.695736 -48.789336)
			(xy 112.695736 -48.814736) (xy 114.8842 -51.0032) (xy 131.7244 -51.0032) (xy 134.333488 -48.394112)
			(xy 148.176488 -48.394112) (xy 150.6982 -45.8724) (xy 150.6982 -24.9174) (xy 149.5552 -23.7744) (xy 135.7376 -23.7744)
			(xy 128.8796 -30.6324) (xy 128.8796 -32.2072) (xy 128.8796 -36.053879) (xy 133.355087 -36.053879)
			(xy 133.360987 -35.997741) (xy 133.374643 -35.942969) (xy 133.395789 -35.890632) (xy 133.424013 -35.841746)
			(xy 133.458766 -35.797265) (xy 133.499371 -35.758053) (xy 133.545039 -35.724873) (xy 133.594879 -35.698373)
			(xy 133.647923 -35.679066) (xy 133.703138 -35.66733) (xy 133.759448 -35.663393) (xy 133.815758 -35.66733)
			(xy 133.870973 -35.679066) (xy 133.924017 -35.698373) (xy 133.973857 -35.724873) (xy 134.019525 -35.758053)
			(xy 134.06013 -35.797265) (xy 134.094883 -35.841746) (xy 134.123107 -35.890632) (xy 134.144253 -35.942969)
			(xy 134.157909 -35.997741) (xy 134.163809 -36.053879) (xy 134.161839 -36.110293) (xy 134.152037 -36.165883)
			(xy 134.134594 -36.219569) (xy 134.109848 -36.270304) (xy 134.078283 -36.317101) (xy 134.040512 -36.35905)
			(xy 133.99727 -36.395334) (xy 133.9494 -36.425247) (xy 133.897832 -36.448207) (xy 133.843571 -36.463766)
			(xy 133.787672 -36.471622) (xy 133.759448 -36.472114) (xy 133.731224 -36.471622) (xy 133.675325 -36.463766)
			(xy 133.621064 -36.448207) (xy 133.569496 -36.425247) (xy 133.521626 -36.395334) (xy 133.478384 -36.35905)
			(xy 133.440613 -36.317101) (xy 133.409048 -36.270304) (xy 133.384302 -36.219569) (xy 133.366859 -36.165883)
			(xy 133.357057 -36.110293) (xy 133.355087 -36.053879) (xy 128.8796 -36.053879) (xy 128.8796 -39.0906)
			(xy 128.75514 -39.21506) (xy 128.75514 -39.294308) (xy 128.675892 -39.294308) (xy 128.2446 -39.7256)
			(xy 119.6594 -39.7256) (xy 117.2718 -37.338) (xy 117.2718 -29.972) (xy 115.57 -28.2702) (xy 115.57 -28.2448)
			(xy 111.5822 -24.257) (xy 99.695 -24.257) (xy 96.2406 -27.7114) (xy 96.2406 -39.878762) (xy 96.232472 -39.886128)
			(xy 96.0882 -40.0304) (xy 91.5162 -40.0304) (xy 90.678 -39.1922) (xy 88.6714 -39.1922) (xy 87.122 -37.6428)
			(xy 85.4964 -37.6428) (xy 83.2358 -35.3822) (xy 83.2358 -31.75) (xy 84.8868 -30.099) (xy 88.9254 -30.099)
			(xy 89.3064 -29.718) (xy 89.3064 -25.781) (xy 89.5858 -25.5016) (xy 92.329 -25.5016) (xy 92.7862 -25.0444)
			(xy 92.7862 -23.9776) (xy 92.4306 -23.622) (xy 86.8934 -23.622) (xy 86.0806 -22.8092) (xy 86.0806 -17.4752)
			(xy 87.8078 -15.748) (xy 87.8078 -15.1892) (xy 87.8078 -2.6162) (xy 87.1728 -1.9812) (xy 74.803 -1.9812)
			(xy 73.0504 -3.7338) (xy 73.0504 -11.557) (xy 72.898 -11.7094) (xy 72.86625 -11.67765) (xy 61.51245 -11.67765)
			(xy 60.149639 -13.040461) (xy 64.846192 -13.040461) (xy 64.846192 -12.969139) (xy 64.854178 -12.898265)
			(xy 64.870048 -12.82873) (xy 64.893605 -12.76141) (xy 64.92455 -12.697151) (xy 64.962496 -12.63676)
			(xy 65.006965 -12.580998) (xy 65.057398 -12.530565) (xy 65.11316 -12.486096) (xy 65.173551 -12.44815)
			(xy 65.23781 -12.417205) (xy 65.30513 -12.393648) (xy 65.374665 -12.377778) (xy 65.445539 -12.369792)
			(xy 65.4812 -12.369292) (xy 65.516861 -12.369792) (xy 65.587735 -12.377778) (xy 65.65727 -12.393648)
			(xy 65.72459 -12.417205) (xy 65.788849 -12.44815) (xy 65.84924 -12.486096) (xy 65.905002 -12.530565)
			(xy 65.955435 -12.580998) (xy 65.999904 -12.63676) (xy 66.03785 -12.697151) (xy 66.068795 -12.76141)
			(xy 66.092352 -12.82873) (xy 66.108222 -12.898265) (xy 66.116208 -12.969139) (xy 66.116208 -13.040461)
			(xy 66.108222 -13.111335) (xy 66.092352 -13.18087) (xy 66.068795 -13.24819) (xy 66.03785 -13.312449)
			(xy 65.999904 -13.37284) (xy 65.955435 -13.428602) (xy 65.905002 -13.479035) (xy 65.84924 -13.523504)
			(xy 65.788849 -13.56145) (xy 65.72459 -13.592395) (xy 65.65727 -13.615952) (xy 65.587735 -13.631822)
			(xy 65.516861 -13.639808) (xy 65.445539 -13.639808) (xy 65.374665 -13.631822) (xy 65.30513 -13.615952)
			(xy 65.23781 -13.592395) (xy 65.173551 -13.56145) (xy 65.11316 -13.523504) (xy 65.057398 -13.479035)
			(xy 65.006965 -13.428602) (xy 64.962496 -13.37284) (xy 64.92455 -13.312449) (xy 64.893605 -13.24819)
			(xy 64.870048 -13.18087) (xy 64.854178 -13.111335) (xy 64.846192 -13.040461) (xy 60.149639 -13.040461)
			(xy 55.501439 -17.688661) (xy 71.399392 -17.688661) (xy 71.399392 -17.617339) (xy 71.407378 -17.546465)
			(xy 71.423248 -17.47693) (xy 71.446805 -17.40961) (xy 71.47775 -17.345351) (xy 71.515696 -17.28496)
			(xy 71.560165 -17.229198) (xy 71.610598 -17.178765) (xy 71.66636 -17.134296) (xy 71.726751 -17.09635)
			(xy 71.79101 -17.065405) (xy 71.85833 -17.041848) (xy 71.927865 -17.025978) (xy 71.998739 -17.017992)
			(xy 72.0344 -17.017492) (xy 72.070061 -17.017992) (xy 72.140935 -17.025978) (xy 72.21047 -17.041848)
			(xy 72.27779 -17.065405) (xy 72.342049 -17.09635) (xy 72.40244 -17.134296) (xy 72.458202 -17.178765)
			(xy 72.508635 -17.229198) (xy 72.553104 -17.28496) (xy 72.59105 -17.345351) (xy 72.621995 -17.40961)
			(xy 72.645552 -17.47693) (xy 72.661422 -17.546465) (xy 72.669408 -17.617339) (xy 72.669408 -17.688661)
			(xy 72.661422 -17.759535) (xy 72.645552 -17.82907) (xy 72.621995 -17.89639) (xy 72.59105 -17.960649)
			(xy 72.553104 -18.02104) (xy 72.508635 -18.076802) (xy 72.458202 -18.127235) (xy 72.40244 -18.171704)
			(xy 72.342049 -18.20965) (xy 72.27779 -18.240595) (xy 72.21047 -18.264152) (xy 72.140935 -18.280022)
			(xy 72.070061 -18.288008) (xy 71.998739 -18.288008) (xy 71.927865 -18.280022) (xy 71.85833 -18.264152)
			(xy 71.79101 -18.240595) (xy 71.726751 -18.20965) (xy 71.66636 -18.171704) (xy 71.610598 -18.127235)
			(xy 71.560165 -18.076802) (xy 71.515696 -18.02104) (xy 71.47775 -17.960649) (xy 71.446805 -17.89639)
			(xy 71.423248 -17.82907) (xy 71.407378 -17.759535) (xy 71.399392 -17.688661) (xy 55.501439 -17.688661)
			(xy 54.282239 -18.907861) (xy 63.982592 -18.907861) (xy 63.982592 -18.836539) (xy 63.990578 -18.765665)
			(xy 64.006448 -18.69613) (xy 64.030005 -18.62881) (xy 64.06095 -18.564551) (xy 64.098896 -18.50416)
			(xy 64.143365 -18.448398) (xy 64.193798 -18.397965) (xy 64.24956 -18.353496) (xy 64.309951 -18.31555)
			(xy 64.37421 -18.284605) (xy 64.44153 -18.261048) (xy 64.511065 -18.245178) (xy 64.581939 -18.237192)
			(xy 64.6176 -18.236692) (xy 64.653261 -18.237192) (xy 64.724135 -18.245178) (xy 64.79367 -18.261048)
			(xy 64.86099 -18.284605) (xy 64.925249 -18.31555) (xy 64.98564 -18.353496) (xy 65.041402 -18.397965)
			(xy 65.091835 -18.448398) (xy 65.136304 -18.50416) (xy 65.17425 -18.564551) (xy 65.205195 -18.62881)
			(xy 65.228752 -18.69613) (xy 65.244622 -18.765665) (xy 65.252608 -18.836539) (xy 65.252608 -18.907861)
			(xy 65.244622 -18.978735) (xy 65.228752 -19.04827) (xy 65.205195 -19.11559) (xy 65.17425 -19.179849)
			(xy 65.136304 -19.24024) (xy 65.091835 -19.296002) (xy 65.041402 -19.346435) (xy 64.98564 -19.390904)
			(xy 64.925249 -19.42885) (xy 64.86099 -19.459795) (xy 64.79367 -19.483352) (xy 64.724135 -19.499222)
			(xy 64.653261 -19.507208) (xy 64.581939 -19.507208) (xy 64.511065 -19.499222) (xy 64.44153 -19.483352)
			(xy 64.37421 -19.459795) (xy 64.309951 -19.42885) (xy 64.24956 -19.390904) (xy 64.193798 -19.346435)
			(xy 64.143365 -19.296002) (xy 64.098896 -19.24024) (xy 64.06095 -19.179849) (xy 64.030005 -19.11559)
			(xy 64.006448 -19.04827) (xy 63.990578 -18.978735) (xy 63.982592 -18.907861) (xy 54.282239 -18.907861)
			(xy 49.049839 -24.140261) (xy 68.783192 -24.140261) (xy 68.783192 -24.068939) (xy 68.791178 -23.998065)
			(xy 68.807048 -23.92853) (xy 68.830605 -23.86121) (xy 68.86155 -23.796951) (xy 68.899496 -23.73656)
			(xy 68.943965 -23.680798) (xy 68.994398 -23.630365) (xy 69.05016 -23.585896) (xy 69.110551 -23.54795)
			(xy 69.17481 -23.517005) (xy 69.24213 -23.493448) (xy 69.311665 -23.477578) (xy 69.382539 -23.469592)
			(xy 69.4182 -23.469092) (xy 69.453861 -23.469592) (xy 69.524735 -23.477578) (xy 69.59427 -23.493448)
			(xy 69.66159 -23.517005) (xy 69.725849 -23.54795) (xy 69.78624 -23.585896) (xy 69.842002 -23.630365)
			(xy 69.892435 -23.680798) (xy 69.936904 -23.73656) (xy 69.97485 -23.796951) (xy 70.005795 -23.86121)
			(xy 70.029352 -23.92853) (xy 70.045222 -23.998065) (xy 70.053208 -24.068939) (xy 70.053208 -24.140261)
			(xy 70.045222 -24.211135) (xy 70.029352 -24.28067) (xy 70.005795 -24.34799) (xy 69.97485 -24.412249)
			(xy 69.936904 -24.47264) (xy 69.892435 -24.528402) (xy 69.842002 -24.578835) (xy 69.78624 -24.623304)
			(xy 69.725849 -24.66125) (xy 69.66159 -24.692195) (xy 69.59427 -24.715752) (xy 69.524735 -24.731622)
			(xy 69.453861 -24.739608) (xy 69.382539 -24.739608) (xy 69.311665 -24.731622) (xy 69.24213 -24.715752)
			(xy 69.17481 -24.692195) (xy 69.110551 -24.66125) (xy 69.05016 -24.623304) (xy 68.994398 -24.578835)
			(xy 68.943965 -24.528402) (xy 68.899496 -24.47264) (xy 68.86155 -24.412249) (xy 68.830605 -24.34799)
			(xy 68.807048 -24.28067) (xy 68.791178 -24.211135) (xy 68.783192 -24.140261) (xy 49.049839 -24.140261)
			(xy 47.627439 -25.562661) (xy 54.330592 -25.562661) (xy 54.330592 -25.491339) (xy 54.338578 -25.420465)
			(xy 54.354448 -25.35093) (xy 54.378005 -25.28361) (xy 54.40895 -25.219351) (xy 54.446896 -25.15896)
			(xy 54.491365 -25.103198) (xy 54.541798 -25.052765) (xy 54.59756 -25.008296) (xy 54.657951 -24.97035)
			(xy 54.72221 -24.939405) (xy 54.78953 -24.915848) (xy 54.859065 -24.899978) (xy 54.929939 -24.891992)
			(xy 54.9656 -24.891492) (xy 55.001261 -24.891992) (xy 55.072135 -24.899978) (xy 55.14167 -24.915848)
			(xy 55.20899 -24.939405) (xy 55.273249 -24.97035) (xy 55.33364 -25.008296) (xy 55.389402 -25.052765)
			(xy 55.439835 -25.103198) (xy 55.484304 -25.15896) (xy 55.52225 -25.219351) (xy 55.553195 -25.28361)
			(xy 55.576752 -25.35093) (xy 55.592622 -25.420465) (xy 55.597196 -25.461061) (xy 63.271392 -25.461061)
			(xy 63.271392 -25.389739) (xy 63.279378 -25.318865) (xy 63.295248 -25.24933) (xy 63.318805 -25.18201)
			(xy 63.34975 -25.117751) (xy 63.387696 -25.05736) (xy 63.432165 -25.001598) (xy 63.482598 -24.951165)
			(xy 63.53836 -24.906696) (xy 63.598751 -24.86875) (xy 63.66301 -24.837805) (xy 63.73033 -24.814248)
			(xy 63.799865 -24.798378) (xy 63.870739 -24.790392) (xy 63.9064 -24.789892) (xy 63.942061 -24.790392)
			(xy 64.012935 -24.798378) (xy 64.08247 -24.814248) (xy 64.14979 -24.837805) (xy 64.214049 -24.86875)
			(xy 64.27444 -24.906696) (xy 64.330202 -24.951165) (xy 64.380635 -25.001598) (xy 64.425104 -25.05736)
			(xy 64.46305 -25.117751) (xy 64.493995 -25.18201) (xy 64.517552 -25.24933) (xy 64.533422 -25.318865)
			(xy 64.541408 -25.389739) (xy 64.541408 -25.461061) (xy 64.533422 -25.531935) (xy 64.517552 -25.60147)
			(xy 64.49558 -25.664261) (xy 70.942192 -25.664261) (xy 70.942192 -25.592939) (xy 70.950178 -25.522065)
			(xy 70.966048 -25.45253) (xy 70.989605 -25.38521) (xy 71.02055 -25.320951) (xy 71.058496 -25.26056)
			(xy 71.102965 -25.204798) (xy 71.153398 -25.154365) (xy 71.20916 -25.109896) (xy 71.269551 -25.07195)
			(xy 71.33381 -25.041005) (xy 71.40113 -25.017448) (xy 71.470665 -25.001578) (xy 71.541539 -24.993592)
			(xy 71.5772 -24.993092) (xy 71.612861 -24.993592) (xy 71.683735 -25.001578) (xy 71.75327 -25.017448)
			(xy 71.82059 -25.041005) (xy 71.884849 -25.07195) (xy 71.94524 -25.109896) (xy 72.001002 -25.154365)
			(xy 72.051435 -25.204798) (xy 72.095904 -25.26056) (xy 72.13385 -25.320951) (xy 72.164795 -25.38521)
			(xy 72.188352 -25.45253) (xy 72.204222 -25.522065) (xy 72.212208 -25.592939) (xy 72.212208 -25.664261)
			(xy 72.206484 -25.715061) (xy 77.546192 -25.715061) (xy 77.546192 -25.643739) (xy 77.554178 -25.572865)
			(xy 77.570048 -25.50333) (xy 77.593605 -25.43601) (xy 77.62455 -25.371751) (xy 77.662496 -25.31136)
			(xy 77.706965 -25.255598) (xy 77.757398 -25.205165) (xy 77.81316 -25.160696) (xy 77.873551 -25.12275)
			(xy 77.93781 -25.091805) (xy 78.00513 -25.068248) (xy 78.074665 -25.052378) (xy 78.145539 -25.044392)
			(xy 78.1812 -25.043892) (xy 78.216861 -25.044392) (xy 78.287735 -25.052378) (xy 78.35727 -25.068248)
			(xy 78.42459 -25.091805) (xy 78.488849 -25.12275) (xy 78.54924 -25.160696) (xy 78.605002 -25.205165)
			(xy 78.655435 -25.255598) (xy 78.699904 -25.31136) (xy 78.73785 -25.371751) (xy 78.768795 -25.43601)
			(xy 78.792352 -25.50333) (xy 78.808222 -25.572865) (xy 78.816208 -25.643739) (xy 78.816208 -25.715061)
			(xy 78.808222 -25.785935) (xy 78.792352 -25.85547) (xy 78.768795 -25.92279) (xy 78.73785 -25.987049)
			(xy 78.699904 -26.04744) (xy 78.655435 -26.103202) (xy 78.605002 -26.153635) (xy 78.54924 -26.198104)
			(xy 78.488849 -26.23605) (xy 78.42459 -26.266995) (xy 78.35727 -26.290552) (xy 78.287735 -26.306422)
			(xy 78.216861 -26.314408) (xy 78.145539 -26.314408) (xy 78.074665 -26.306422) (xy 78.00513 -26.290552)
			(xy 77.93781 -26.266995) (xy 77.873551 -26.23605) (xy 77.81316 -26.198104) (xy 77.757398 -26.153635)
			(xy 77.706965 -26.103202) (xy 77.662496 -26.04744) (xy 77.62455 -25.987049) (xy 77.593605 -25.92279)
			(xy 77.570048 -25.85547) (xy 77.554178 -25.785935) (xy 77.546192 -25.715061) (xy 72.206484 -25.715061)
			(xy 72.204222 -25.735135) (xy 72.188352 -25.80467) (xy 72.164795 -25.87199) (xy 72.13385 -25.936249)
			(xy 72.095904 -25.99664) (xy 72.051435 -26.052402) (xy 72.001002 -26.102835) (xy 71.94524 -26.147304)
			(xy 71.884849 -26.18525) (xy 71.82059 -26.216195) (xy 71.75327 -26.239752) (xy 71.683735 -26.255622)
			(xy 71.612861 -26.263608) (xy 71.541539 -26.263608) (xy 71.470665 -26.255622) (xy 71.40113 -26.239752)
			(xy 71.33381 -26.216195) (xy 71.269551 -26.18525) (xy 71.20916 -26.147304) (xy 71.153398 -26.102835)
			(xy 71.102965 -26.052402) (xy 71.058496 -25.99664) (xy 71.02055 -25.936249) (xy 70.989605 -25.87199)
			(xy 70.966048 -25.80467) (xy 70.950178 -25.735135) (xy 70.942192 -25.664261) (xy 64.49558 -25.664261)
			(xy 64.493995 -25.66879) (xy 64.46305 -25.733049) (xy 64.425104 -25.79344) (xy 64.380635 -25.849202)
			(xy 64.330202 -25.899635) (xy 64.27444 -25.944104) (xy 64.214049 -25.98205) (xy 64.14979 -26.012995)
			(xy 64.08247 -26.036552) (xy 64.012935 -26.052422) (xy 63.942061 -26.060408) (xy 63.870739 -26.060408)
			(xy 63.799865 -26.052422) (xy 63.73033 -26.036552) (xy 63.66301 -26.012995) (xy 63.598751 -25.98205)
			(xy 63.53836 -25.944104) (xy 63.482598 -25.899635) (xy 63.432165 -25.849202) (xy 63.387696 -25.79344)
			(xy 63.34975 -25.733049) (xy 63.318805 -25.66879) (xy 63.295248 -25.60147) (xy 63.279378 -25.531935)
			(xy 63.271392 -25.461061) (xy 55.597196 -25.461061) (xy 55.600608 -25.491339) (xy 55.600608 -25.562661)
			(xy 55.592622 -25.633535) (xy 55.576752 -25.70307) (xy 55.553195 -25.77039) (xy 55.52225 -25.834649)
			(xy 55.484304 -25.89504) (xy 55.439835 -25.950802) (xy 55.389402 -26.001235) (xy 55.33364 -26.045704)
			(xy 55.273249 -26.08365) (xy 55.20899 -26.114595) (xy 55.14167 -26.138152) (xy 55.072135 -26.154022)
			(xy 55.001261 -26.162008) (xy 54.929939 -26.162008) (xy 54.859065 -26.154022) (xy 54.78953 -26.138152)
			(xy 54.72221 -26.114595) (xy 54.657951 -26.08365) (xy 54.59756 -26.045704) (xy 54.541798 -26.001235)
			(xy 54.491365 -25.950802) (xy 54.446896 -25.89504) (xy 54.40895 -25.834649) (xy 54.378005 -25.77039)
			(xy 54.354448 -25.70307) (xy 54.338578 -25.633535) (xy 54.330592 -25.562661) (xy 47.627439 -25.562661)
			(xy 37.594439 -35.595661) (xy 75.641192 -35.595661) (xy 75.641192 -35.524339) (xy 75.649178 -35.453465)
			(xy 75.665048 -35.38393) (xy 75.688605 -35.31661) (xy 75.71955 -35.252351) (xy 75.757496 -35.19196)
			(xy 75.801965 -35.136198) (xy 75.852398 -35.085765) (xy 75.90816 -35.041296) (xy 75.968551 -35.00335)
			(xy 76.03281 -34.972405) (xy 76.10013 -34.948848) (xy 76.169665 -34.932978) (xy 76.240539 -34.924992)
			(xy 76.2762 -34.924492) (xy 76.311861 -34.924992) (xy 76.382735 -34.932978) (xy 76.45227 -34.948848)
			(xy 76.51959 -34.972405) (xy 76.583849 -35.00335) (xy 76.64424 -35.041296) (xy 76.700002 -35.085765)
			(xy 76.750435 -35.136198) (xy 76.794904 -35.19196) (xy 76.83285 -35.252351) (xy 76.863795 -35.31661)
			(xy 76.887352 -35.38393) (xy 76.903222 -35.453465) (xy 76.911208 -35.524339) (xy 76.911208 -35.595661)
			(xy 76.903222 -35.666535) (xy 76.887352 -35.73607) (xy 76.863795 -35.80339) (xy 76.83285 -35.867649)
			(xy 76.794904 -35.92804) (xy 76.750435 -35.983802) (xy 76.700002 -36.034235) (xy 76.64424 -36.078704)
			(xy 76.583849 -36.11665) (xy 76.51959 -36.147595) (xy 76.45227 -36.171152) (xy 76.382735 -36.187022)
			(xy 76.311861 -36.195008) (xy 76.240539 -36.195008) (xy 76.169665 -36.187022) (xy 76.10013 -36.171152)
			(xy 76.03281 -36.147595) (xy 75.968551 -36.11665) (xy 75.90816 -36.078704) (xy 75.852398 -36.034235)
			(xy 75.801965 -35.983802) (xy 75.757496 -35.92804) (xy 75.71955 -35.867649) (xy 75.688605 -35.80339)
			(xy 75.665048 -35.73607) (xy 75.649178 -35.666535) (xy 75.641192 -35.595661) (xy 37.594439 -35.595661)
			(xy 36.273639 -36.916461) (xy 67.360792 -36.916461) (xy 67.360792 -36.845139) (xy 67.368778 -36.774265)
			(xy 67.384648 -36.70473) (xy 67.408205 -36.63741) (xy 67.43915 -36.573151) (xy 67.477096 -36.51276)
			(xy 67.521565 -36.456998) (xy 67.571998 -36.406565) (xy 67.62776 -36.362096) (xy 67.688151 -36.32415)
			(xy 67.75241 -36.293205) (xy 67.81973 -36.269648) (xy 67.889265 -36.253778) (xy 67.960139 -36.245792)
			(xy 67.9958 -36.245292) (xy 68.031461 -36.245792) (xy 68.102335 -36.253778) (xy 68.17187 -36.269648)
			(xy 68.23919 -36.293205) (xy 68.303449 -36.32415) (xy 68.36384 -36.362096) (xy 68.419602 -36.406565)
			(xy 68.470035 -36.456998) (xy 68.514504 -36.51276) (xy 68.55245 -36.573151) (xy 68.583395 -36.63741)
			(xy 68.606952 -36.70473) (xy 68.622822 -36.774265) (xy 68.630808 -36.845139) (xy 68.630808 -36.916461)
			(xy 68.622822 -36.987335) (xy 68.606952 -37.05687) (xy 68.583395 -37.12419) (xy 68.55245 -37.188449)
			(xy 68.514504 -37.24884) (xy 68.470035 -37.304602) (xy 68.419602 -37.355035) (xy 68.36384 -37.399504)
			(xy 68.303449 -37.43745) (xy 68.23919 -37.468395) (xy 68.17187 -37.491952) (xy 68.102335 -37.507822)
			(xy 68.031461 -37.515808) (xy 67.960139 -37.515808) (xy 67.889265 -37.507822) (xy 67.81973 -37.491952)
			(xy 67.75241 -37.468395) (xy 67.688151 -37.43745) (xy 67.62776 -37.399504) (xy 67.571998 -37.355035)
			(xy 67.521565 -37.304602) (xy 67.477096 -37.24884) (xy 67.43915 -37.188449) (xy 67.408205 -37.12419)
			(xy 67.384648 -37.05687) (xy 67.368778 -36.987335) (xy 67.360792 -36.916461) (xy 36.273639 -36.916461)
			(xy 31.4071 -41.783) (xy 31.4071 -51.2953) (xy 31.7246 -51.6128)
		)
		(stroke
			(width 0)
			(type solid)
		)
		(fill yes)
		(layer "F.Cu")
		(net "GND")
	)
	(gr_poly
		(pts
			(xy 20.557744 -51.7398) (xy 20.574389 -51.739252) (xy 20.606541 -51.730626) (xy 20.635367 -51.713975)
			(xy 20.658902 -51.690432) (xy 20.675543 -51.6616) (xy 20.684157 -51.629445) (xy 20.684744 -51.6128)
			(xy 20.684744 -45.449236) (xy 21.232368 -45.449236) (xy 21.232368 -51.6128) (xy 21.232911 -51.62945)
			(xy 21.241528 -51.661615) (xy 21.258176 -51.690455) (xy 21.281719 -51.714005) (xy 21.310555 -51.730659)
			(xy 21.342718 -51.739285) (xy 21.359368 -51.7398) (xy 29.8196 -51.7398) (xy 30.7086 -50.8508) (xy 30.7086 -41.0972)
			(xy 61.1886 -10.6172) (xy 70.1802 -10.6172) (xy 70.9168 -9.8806) (xy 70.9168 -2.4892) (xy 70.0024 -1.5748)
			(xy 10.2616 -1.5748) (xy 9.5758 -2.2606) (xy 9.5758 -5.166461) (xy 37.541192 -5.166461) (xy 37.541192 -5.095139)
			(xy 37.549178 -5.024265) (xy 37.565048 -4.95473) (xy 37.588605 -4.88741) (xy 37.61955 -4.823151)
			(xy 37.657496 -4.76276) (xy 37.701965 -4.706998) (xy 37.752398 -4.656565) (xy 37.80816 -4.612096)
			(xy 37.868551 -4.57415) (xy 37.93281 -4.543205) (xy 38.00013 -4.519648) (xy 38.069665 -4.503778)
			(xy 38.140539 -4.495792) (xy 38.211861 -4.495792) (xy 38.282735 -4.503778) (xy 38.35227 -4.519648)
			(xy 38.41959 -4.543205) (xy 38.483849 -4.57415) (xy 38.54424 -4.612096) (xy 38.600002 -4.656565)
			(xy 38.650435 -4.706998) (xy 38.694904 -4.76276) (xy 38.73285 -4.823151) (xy 38.763795 -4.88741)
			(xy 38.787352 -4.95473) (xy 38.803222 -5.024265) (xy 38.811208 -5.095139) (xy 38.811708 -5.1308)
			(xy 38.811208 -5.166461) (xy 45.161192 -5.166461) (xy 45.161192 -5.095139) (xy 45.169178 -5.024265)
			(xy 45.185048 -4.95473) (xy 45.208605 -4.88741) (xy 45.23955 -4.823151) (xy 45.277496 -4.76276) (xy 45.321965 -4.706998)
			(xy 45.372398 -4.656565) (xy 45.42816 -4.612096) (xy 45.488551 -4.57415) (xy 45.55281 -4.543205)
			(xy 45.62013 -4.519648) (xy 45.689665 -4.503778) (xy 45.760539 -4.495792) (xy 45.831861 -4.495792)
			(xy 45.902735 -4.503778) (xy 45.97227 -4.519648) (xy 46.03959 -4.543205) (xy 46.103849 -4.57415)
			(xy 46.16424 -4.612096) (xy 46.220002 -4.656565) (xy 46.270435 -4.706998) (xy 46.314904 -4.76276)
			(xy 46.35285 -4.823151) (xy 46.383795 -4.88741) (xy 46.407352 -4.95473) (xy 46.423222 -5.024265)
			(xy 46.431208 -5.095139) (xy 46.431708 -5.1308) (xy 46.431208 -5.166461) (xy 52.781192 -5.166461)
			(xy 52.781192 -5.095139) (xy 52.789178 -5.024265) (xy 52.805048 -4.95473) (xy 52.828605 -4.88741)
			(xy 52.85955 -4.823151) (xy 52.897496 -4.76276) (xy 52.941965 -4.706998) (xy 52.992398 -4.656565)
			(xy 53.04816 -4.612096) (xy 53.108551 -4.57415) (xy 53.17281 -4.543205) (xy 53.24013 -4.519648) (xy 53.309665 -4.503778)
			(xy 53.380539 -4.495792) (xy 53.451861 -4.495792) (xy 53.522735 -4.503778) (xy 53.59227 -4.519648)
			(xy 53.65959 -4.543205) (xy 53.723849 -4.57415) (xy 53.78424 -4.612096) (xy 53.840002 -4.656565)
			(xy 53.890435 -4.706998) (xy 53.934904 -4.76276) (xy 53.97285 -4.823151) (xy 54.003795 -4.88741)
			(xy 54.027352 -4.95473) (xy 54.043222 -5.024265) (xy 54.051208 -5.095139) (xy 54.051708 -5.1308)
			(xy 54.051208 -5.166461) (xy 60.401192 -5.166461) (xy 60.401192 -5.095139) (xy 60.409178 -5.024265)
			(xy 60.425048 -4.95473) (xy 60.448605 -4.88741) (xy 60.47955 -4.823151) (xy 60.517496 -4.76276) (xy 60.561965 -4.706998)
			(xy 60.612398 -4.656565) (xy 60.66816 -4.612096) (xy 60.728551 -4.57415) (xy 60.79281 -4.543205)
			(xy 60.86013 -4.519648) (xy 60.929665 -4.503778) (xy 61.000539 -4.495792) (xy 61.071861 -4.495792)
			(xy 61.142735 -4.503778) (xy 61.21227 -4.519648) (xy 61.27959 -4.543205) (xy 61.343849 -4.57415)
			(xy 61.40424 -4.612096) (xy 61.460002 -4.656565) (xy 61.510435 -4.706998) (xy 61.554904 -4.76276)
			(xy 61.59285 -4.823151) (xy 61.623795 -4.88741) (xy 61.647352 -4.95473) (xy 61.663222 -5.024265)
			(xy 61.671208 -5.095139) (xy 61.671708 -5.1308) (xy 61.671208 -5.166461) (xy 68.021192 -5.166461)
			(xy 68.021192 -5.095139) (xy 68.029178 -5.024265) (xy 68.045048 -4.95473) (xy 68.068605 -4.88741)
			(xy 68.09955 -4.823151) (xy 68.137496 -4.76276) (xy 68.181965 -4.706998) (xy 68.232398 -4.656565)
			(xy 68.28816 -4.612096) (xy 68.348551 -4.57415) (xy 68.41281 -4.543205) (xy 68.48013 -4.519648) (xy 68.549665 -4.503778)
			(xy 68.620539 -4.495792) (xy 68.691861 -4.495792) (xy 68.762735 -4.503778) (xy 68.83227 -4.519648)
			(xy 68.89959 -4.543205) (xy 68.963849 -4.57415) (xy 69.02424 -4.612096) (xy 69.080002 -4.656565)
			(xy 69.130435 -4.706998) (xy 69.174904 -4.76276) (xy 69.21285 -4.823151) (xy 69.243795 -4.88741)
			(xy 69.267352 -4.95473) (xy 69.283222 -5.024265) (xy 69.291208 -5.095139) (xy 69.291708 -5.1308)
			(xy 69.291208 -5.166461) (xy 69.283222 -5.237335) (xy 69.267352 -5.30687) (xy 69.243795 -5.37419)
			(xy 69.21285 -5.438449) (xy 69.174904 -5.49884) (xy 69.130435 -5.554602) (xy 69.080002 -5.605035)
			(xy 69.02424 -5.649504) (xy 68.963849 -5.68745) (xy 68.89959 -5.718395) (xy 68.83227 -5.741952) (xy 68.762735 -5.757822)
			(xy 68.691861 -5.765808) (xy 68.620539 -5.765808) (xy 68.549665 -5.757822) (xy 68.48013 -5.741952)
			(xy 68.41281 -5.718395) (xy 68.348551 -5.68745) (xy 68.28816 -5.649504) (xy 68.232398 -5.605035)
			(xy 68.181965 -5.554602) (xy 68.137496 -5.49884) (xy 68.09955 -5.438449) (xy 68.068605 -5.37419)
			(xy 68.045048 -5.30687) (xy 68.029178 -5.237335) (xy 68.021192 -5.166461) (xy 61.671208 -5.166461)
			(xy 61.663222 -5.237335) (xy 61.647352 -5.30687) (xy 61.623795 -5.37419) (xy 61.59285 -5.438449)
			(xy 61.554904 -5.49884) (xy 61.510435 -5.554602) (xy 61.460002 -5.605035) (xy 61.40424 -5.649504)
			(xy 61.343849 -5.68745) (xy 61.27959 -5.718395) (xy 61.21227 -5.741952) (xy 61.142735 -5.757822)
			(xy 61.071861 -5.765808) (xy 61.000539 -5.765808) (xy 60.929665 -5.757822) (xy 60.86013 -5.741952)
			(xy 60.79281 -5.718395) (xy 60.728551 -5.68745) (xy 60.66816 -5.649504) (xy 60.612398 -5.605035)
			(xy 60.561965 -5.554602) (xy 60.517496 -5.49884) (xy 60.47955 -5.438449) (xy 60.448605 -5.37419)
			(xy 60.425048 -5.30687) (xy 60.409178 -5.237335) (xy 60.401192 -5.166461) (xy 54.051208 -5.166461)
			(xy 54.043222 -5.237335) (xy 54.027352 -5.30687) (xy 54.003795 -5.37419) (xy 53.97285 -5.438449)
			(xy 53.934904 -5.49884) (xy 53.890435 -5.554602) (xy 53.840002 -5.605035) (xy 53.78424 -5.649504)
			(xy 53.723849 -5.68745) (xy 53.65959 -5.718395) (xy 53.59227 -5.741952) (xy 53.522735 -5.757822)
			(xy 53.451861 -5.765808) (xy 53.380539 -5.765808) (xy 53.309665 -5.757822) (xy 53.24013 -5.741952)
			(xy 53.17281 -5.718395) (xy 53.108551 -5.68745) (xy 53.04816 -5.649504) (xy 52.992398 -5.605035)
			(xy 52.941965 -5.554602) (xy 52.897496 -5.49884) (xy 52.85955 -5.438449) (xy 52.828605 -5.37419)
			(xy 52.805048 -5.30687) (xy 52.789178 -5.237335) (xy 52.781192 -5.166461) (xy 46.431208 -5.166461)
			(xy 46.423222 -5.237335) (xy 46.407352 -5.30687) (xy 46.383795 -5.37419) (xy 46.35285 -5.438449)
			(xy 46.314904 -5.49884) (xy 46.270435 -5.554602) (xy 46.220002 -5.605035) (xy 46.16424 -5.649504)
			(xy 46.103849 -5.68745) (xy 46.03959 -5.718395) (xy 45.97227 -5.741952) (xy 45.902735 -5.757822)
			(xy 45.831861 -5.765808) (xy 45.760539 -5.765808) (xy 45.689665 -5.757822) (xy 45.62013 -5.741952)
			(xy 45.55281 -5.718395) (xy 45.488551 -5.68745) (xy 45.42816 -5.649504) (xy 45.372398 -5.605035)
			(xy 45.321965 -5.554602) (xy 45.277496 -5.49884) (xy 45.23955 -5.438449) (xy 45.208605 -5.37419)
			(xy 45.185048 -5.30687) (xy 45.169178 -5.237335) (xy 45.161192 -5.166461) (xy 38.811208 -5.166461)
			(xy 38.803222 -5.237335) (xy 38.787352 -5.30687) (xy 38.763795 -5.37419) (xy 38.73285 -5.438449)
			(xy 38.694904 -5.49884) (xy 38.650435 -5.554602) (xy 38.600002 -5.605035) (xy 38.54424 -5.649504)
			(xy 38.483849 -5.68745) (xy 38.41959 -5.718395) (xy 38.35227 -5.741952) (xy 38.282735 -5.757822)
			(xy 38.211861 -5.765808) (xy 38.140539 -5.765808) (xy 38.069665 -5.757822) (xy 38.00013 -5.741952)
			(xy 37.93281 -5.718395) (xy 37.868551 -5.68745) (xy 37.80816 -5.649504) (xy 37.752398 -5.605035)
			(xy 37.701965 -5.554602) (xy 37.657496 -5.49884) (xy 37.61955 -5.438449) (xy 37.588605 -5.37419)
			(xy 37.565048 -5.30687) (xy 37.549178 -5.237335) (xy 37.541192 -5.166461) (xy 9.5758 -5.166461) (xy 9.5758 -6.406388)
			(xy 9.576345 -6.429836) (xy 9.584961 -6.475934) (xy 9.601885 -6.51967) (xy 9.626541 -6.559561) (xy 9.658095 -6.594255)
			(xy 9.695476 -6.622573) (xy 9.737416 -6.643556) (xy 9.782493 -6.656493) (xy 9.829177 -6.660943) (xy 9.875886 -6.656758)
			(xy 9.921036 -6.644077) (xy 9.942322 -6.634226) (xy 9.981596 -6.615362) (xy 10.062876 -6.583965)
			(xy 10.146655 -6.560018) (xy 10.232249 -6.543715) (xy 10.318965 -6.535189) (xy 10.406096 -6.53451)
			(xy 10.492934 -6.541682) (xy 10.578772 -6.556647) (xy 10.662914 -6.579285) (xy 10.744674 -6.60941)
			(xy 10.823388 -6.646777) (xy 10.898416 -6.691084) (xy 10.969147 -6.741969) (xy 11.035007 -6.79902)
			(xy 11.09546 -6.861771) (xy 11.150015 -6.929712) (xy 11.176684 -6.969861) (xy 35.763192 -6.969861)
			(xy 35.763192 -6.898539) (xy 35.771178 -6.827665) (xy 35.787048 -6.75813) (xy 35.810605 -6.69081)
			(xy 35.84155 -6.626551) (xy 35.879496 -6.56616) (xy 35.923965 -6.510398) (xy 35.974398 -6.459965)
			(xy 36.03016 -6.415496) (xy 36.090551 -6.37755) (xy 36.15481 -6.346605) (xy 36.22213 -6.323048) (xy 36.291665 -6.307178)
			(xy 36.362539 -6.299192) (xy 36.433861 -6.299192) (xy 36.504735 -6.307178) (xy 36.57427 -6.323048)
			(xy 36.64159 -6.346605) (xy 36.705849 -6.37755) (xy 36.76624 -6.415496) (xy 36.822002 -6.459965)
			(xy 36.872435 -6.510398) (xy 36.916904 -6.56616) (xy 36.95485 -6.626551) (xy 36.985795 -6.69081)
			(xy 37.009352 -6.75813) (xy 37.025222 -6.827665) (xy 37.033208 -6.898539) (xy 37.033708 -6.9342)
			(xy 37.033208 -6.969861) (xy 37.025222 -7.040735) (xy 37.009352 -7.11027) (xy 36.985795 -7.17759)
			(xy 36.95485 -7.241849) (xy 36.916904 -7.30224) (xy 36.872435 -7.358002) (xy 36.822002 -7.408435)
			(xy 36.76624 -7.452904) (xy 36.705849 -7.49085) (xy 36.64159 -7.521795) (xy 36.57427 -7.545352) (xy 36.504735 -7.561222)
			(xy 36.433861 -7.569208) (xy 36.362539 -7.569208) (xy 36.291665 -7.561222) (xy 36.22213 -7.545352)
			(xy 36.15481 -7.521795) (xy 36.090551 -7.49085) (xy 36.03016 -7.452904) (xy 35.974398 -7.408435)
			(xy 35.923965 -7.358002) (xy 35.879496 -7.30224) (xy 35.84155 -7.241849) (xy 35.810605 -7.17759)
			(xy 35.787048 -7.11027) (xy 35.771178 -7.040735) (xy 35.763192 -6.969861) (xy 11.176684 -6.969861)
			(xy 11.198227 -7.002292) (xy 11.239705 -7.07892) (xy 11.274111 -7.158973) (xy 11.301166 -7.2418)
			(xy 11.32065 -7.326727) (xy 11.332404 -7.413064) (xy 11.336333 -7.500109) (xy 11.332404 -7.587154)
			(xy 11.32065 -7.673491) (xy 11.301167 -7.758418) (xy 11.274112 -7.841245) (xy 11.239706 -7.921298)
			(xy 11.198228 -7.997926) (xy 11.150016 -8.070506) (xy 11.095462 -8.138448) (xy 11.035009 -8.201199)
			(xy 10.969149 -8.258249) (xy 10.898417 -8.309135) (xy 10.82339 -8.353442) (xy 10.744676 -8.39081)
			(xy 10.662916 -8.420935) (xy 10.578774 -8.443572) (xy 10.492935 -8.458538) (xy 10.406097 -8.46571)
			(xy 10.318967 -8.465031) (xy 10.232251 -8.456505) (xy 10.146656 -8.440202) (xy 10.062878 -8.416255)
			(xy 9.981598 -8.384858) (xy 9.942322 -8.365998) (xy 9.921065 -8.356094) (xy 9.875931 -8.343384) (xy 9.829231 -8.33917)
			(xy 9.78255 -8.343593) (xy 9.737473 -8.356504) (xy 9.695529 -8.377466) (xy 9.658142 -8.405765) (xy 9.626581 -8.440442)
			(xy 9.601916 -8.480321) (xy 9.584985 -8.524047) (xy 9.576362 -8.570137) (xy 9.5758 -8.593582) (xy 9.5758 -9.1694)
			(xy 8.202231 -10.542969) (xy 13.382993 -10.542969) (xy 13.382993 -10.457243) (xy 13.390903 -10.371883)
			(xy 13.406655 -10.287616) (xy 13.430115 -10.205163) (xy 13.461083 -10.125226) (xy 13.499294 -10.048487)
			(xy 13.544423 -9.975601) (xy 13.596084 -9.90719) (xy 13.653838 -9.843838) (xy 13.71719 -9.786084)
			(xy 13.785601 -9.734423) (xy 13.858487 -9.689294) (xy 13.935226 -9.651083) (xy 14.015163 -9.620115)
			(xy 14.097616 -9.596655) (xy 14.181883 -9.580903) (xy 14.267243 -9.572993) (xy 14.352969 -9.572993)
			(xy 14.438329 -9.580903) (xy 14.522596 -9.596655) (xy 14.605049 -9.620115) (xy 14.684986 -9.651083)
			(xy 14.761725 -9.689294) (xy 14.834611 -9.734423) (xy 14.903022 -9.786084) (xy 14.966374 -9.843838)
			(xy 15.024128 -9.90719) (xy 15.075789 -9.975601) (xy 15.120918 -10.048487) (xy 15.159129 -10.125226)
			(xy 15.190097 -10.205163) (xy 15.213557 -10.287616) (xy 15.229309 -10.371883) (xy 15.237219 -10.457243)
			(xy 15.237386 -10.471663) (xy 26.136341 -10.471663) (xy 26.136341 -10.356337) (xy 26.144386 -10.241291)
			(xy 26.160436 -10.127087) (xy 26.184414 -10.014281) (xy 26.216202 -9.903422) (xy 26.255646 -9.79505)
			(xy 26.302554 -9.689694) (xy 26.356696 -9.587867) (xy 26.41781 -9.490065) (xy 26.485597 -9.396764)
			(xy 26.559727 -9.308419) (xy 26.63984 -9.22546) (xy 26.725544 -9.148291) (xy 26.816423 -9.077289)
			(xy 26.912033 -9.012799) (xy 27.011908 -8.955136) (xy 27.115563 -8.90458) (xy 27.222492 -8.861378)
			(xy 27.332174 -8.82574) (xy 27.444075 -8.79784) (xy 27.557649 -8.777814) (xy 27.672344 -8.765759)
			(xy 27.7876 -8.761735) (xy 27.902856 -8.765759) (xy 28.017551 -8.777814) (xy 28.131125 -8.79784)
			(xy 28.243026 -8.82574) (xy 28.316031 -8.849461) (xy 41.655992 -8.849461) (xy 41.655992 -8.778139)
			(xy 41.663978 -8.707265) (xy 41.679848 -8.63773) (xy 41.703405 -8.57041) (xy 41.73435 -8.506151)
			(xy 41.772296 -8.44576) (xy 41.816765 -8.389998) (xy 41.867198 -8.339565) (xy 41.92296 -8.295096)
			(xy 41.983351 -8.25715) (xy 42.04761 -8.226205) (xy 42.11493 -8.202648) (xy 42.184465 -8.186778)
			(xy 42.255339 -8.178792) (xy 42.326661 -8.178792) (xy 42.397535 -8.186778) (xy 42.46707 -8.202648)
			(xy 42.53439 -8.226205) (xy 42.598649 -8.25715) (xy 42.65904 -8.295096) (xy 42.714802 -8.339565)
			(xy 42.765235 -8.389998) (xy 42.809704 -8.44576) (xy 42.84765 -8.506151) (xy 42.878595 -8.57041)
			(xy 42.902152 -8.63773) (xy 42.918022 -8.707265) (xy 42.926008 -8.778139) (xy 42.926508 -8.8138)
			(xy 42.926008 -8.849461) (xy 42.918022 -8.920335) (xy 42.902152 -8.98987) (xy 42.878595 -9.05719)
			(xy 42.84765 -9.121449) (xy 42.809704 -9.18184) (xy 42.765235 -9.237602) (xy 42.714802 -9.288035)
			(xy 42.65904 -9.332504) (xy 42.598649 -9.37045) (xy 42.53439 -9.401395) (xy 42.46707 -9.424952) (xy 42.397535 -9.440822)
			(xy 42.326661 -9.448808) (xy 42.255339 -9.448808) (xy 42.184465 -9.440822) (xy 42.11493 -9.424952)
			(xy 42.04761 -9.401395) (xy 41.983351 -9.37045) (xy 41.92296 -9.332504) (xy 41.867198 -9.288035)
			(xy 41.816765 -9.237602) (xy 41.772296 -9.18184) (xy 41.73435 -9.121449) (xy 41.703405 -9.05719)
			(xy 41.679848 -8.98987) (xy 41.663978 -8.920335) (xy 41.655992 -8.849461) (xy 28.316031 -8.849461)
			(xy 28.352708 -8.861378) (xy 28.459637 -8.90458) (xy 28.563292 -8.955136) (xy 28.663167 -9.012799)
			(xy 28.758777 -9.077289) (xy 28.849656 -9.148291) (xy 28.93536 -9.22546) (xy 29.015473 -9.308419)
			(xy 29.089603 -9.396764) (xy 29.15739 -9.490065) (xy 29.218504 -9.587867) (xy 29.272646 -9.689694)
			(xy 29.319554 -9.79505) (xy 29.358998 -9.903422) (xy 29.390786 -10.014281) (xy 29.414764 -10.127087)
			(xy 29.424401 -10.195661) (xy 36.067992 -10.195661) (xy 36.067992 -10.124339) (xy 36.075978 -10.053465)
			(xy 36.091848 -9.98393) (xy 36.115405 -9.91661) (xy 36.14635 -9.852351) (xy 36.184296 -9.79196) (xy 36.228765 -9.736198)
			(xy 36.279198 -9.685765) (xy 36.33496 -9.641296) (xy 36.395351 -9.60335) (xy 36.45961 -9.572405)
			(xy 36.52693 -9.548848) (xy 36.596465 -9.532978) (xy 36.667339 -9.524992) (xy 36.738661 -9.524992)
			(xy 36.809535 -9.532978) (xy 36.87907 -9.548848) (xy 36.94639 -9.572405) (xy 37.010649 -9.60335)
			(xy 37.07104 -9.641296) (xy 37.126802 -9.685765) (xy 37.177235 -9.736198) (xy 37.221704 -9.79196)
			(xy 37.25965 -9.852351) (xy 37.290595 -9.91661) (xy 37.314152 -9.98393) (xy 37.330022 -10.053465)
			(xy 37.338008 -10.124339) (xy 37.338508 -10.16) (xy 37.338008 -10.195661) (xy 37.330022 -10.266535)
			(xy 37.314152 -10.33607) (xy 37.290595 -10.40339) (xy 37.25965 -10.467649) (xy 37.221704 -10.52804)
			(xy 37.177235 -10.583802) (xy 37.126802 -10.634235) (xy 37.07104 -10.678704) (xy 37.010649 -10.71665)
			(xy 36.94639 -10.747595) (xy 36.87907 -10.771152) (xy 36.809535 -10.787022) (xy 36.738661 -10.795008)
			(xy 36.667339 -10.795008) (xy 36.596465 -10.787022) (xy 36.52693 -10.771152) (xy 36.45961 -10.747595)
			(xy 36.395351 -10.71665) (xy 36.33496 -10.678704) (xy 36.279198 -10.634235) (xy 36.228765 -10.583802)
			(xy 36.184296 -10.52804) (xy 36.14635 -10.467649) (xy 36.115405 -10.40339) (xy 36.091848 -10.33607)
			(xy 36.075978 -10.266535) (xy 36.067992 -10.195661) (xy 29.424401 -10.195661) (xy 29.430814 -10.241291)
			(xy 29.438859 -10.356337) (xy 29.439362 -10.414) (xy 29.438859 -10.471663) (xy 29.430814 -10.586709)
			(xy 29.414764 -10.700913) (xy 29.390786 -10.813719) (xy 29.358998 -10.924578) (xy 29.346957 -10.957661)
			(xy 57.048392 -10.957661) (xy 57.048392 -10.886339) (xy 57.056378 -10.815465) (xy 57.072248 -10.74593)
			(xy 57.095805 -10.67861) (xy 57.12675 -10.614351) (xy 57.164696 -10.55396) (xy 57.209165 -10.498198)
			(xy 57.259598 -10.447765) (xy 57.31536 -10.403296) (xy 57.375751 -10.36535) (xy 57.44001 -10.334405)
			(xy 57.50733 -10.310848) (xy 57.576865 -10.294978) (xy 57.647739 -10.286992) (xy 57.719061 -10.286992)
			(xy 57.789935 -10.294978) (xy 57.85947 -10.310848) (xy 57.92679 -10.334405) (xy 57.991049 -10.36535)
			(xy 58.05144 -10.403296) (xy 58.107202 -10.447765) (xy 58.157635 -10.498198) (xy 58.202104 -10.55396)
			(xy 58.24005 -10.614351) (xy 58.270995 -10.67861) (xy 58.294552 -10.74593) (xy 58.310422 -10.815465)
			(xy 58.318408 -10.886339) (xy 58.318908 -10.922) (xy 58.318408 -10.957661) (xy 58.310422 -11.028535)
			(xy 58.294552 -11.09807) (xy 58.270995 -11.16539) (xy 58.24005 -11.229649) (xy 58.202104 -11.29004)
			(xy 58.157635 -11.345802) (xy 58.107202 -11.396235) (xy 58.05144 -11.440704) (xy 57.991049 -11.47865)
			(xy 57.92679 -11.509595) (xy 57.85947 -11.533152) (xy 57.789935 -11.549022) (xy 57.719061 -11.557008)
			(xy 57.647739 -11.557008) (xy 57.576865 -11.549022) (xy 57.50733 -11.533152) (xy 57.44001 -11.509595)
			(xy 57.375751 -11.47865) (xy 57.31536 -11.440704) (xy 57.259598 -11.396235) (xy 57.209165 -11.345802)
			(xy 57.164696 -11.29004) (xy 57.12675 -11.229649) (xy 57.095805 -11.16539) (xy 57.072248 -11.09807)
			(xy 57.056378 -11.028535) (xy 57.048392 -10.957661) (xy 29.346957 -10.957661) (xy 29.319554 -11.03295)
			(xy 29.272646 -11.138306) (xy 29.218504 -11.240133) (xy 29.15739 -11.337935) (xy 29.089603 -11.431236)
			(xy 29.015473 -11.519581) (xy 28.93536 -11.60254) (xy 28.849656 -11.679709) (xy 28.758777 -11.750711)
			(xy 28.663167 -11.815201) (xy 28.563292 -11.872864) (xy 28.459637 -11.92342) (xy 28.352708 -11.966622)
			(xy 28.243026 -12.00226) (xy 28.131125 -12.03016) (xy 28.017551 -12.050186) (xy 27.902856 -12.062241)
			(xy 27.7876 -12.066266) (xy 27.672344 -12.062241) (xy 27.557649 -12.050186) (xy 27.444075 -12.03016)
			(xy 27.332174 -12.00226) (xy 27.222492 -11.966622) (xy 27.115563 -11.92342) (xy 27.011908 -11.872864)
			(xy 26.912033 -11.815201) (xy 26.816423 -11.750711) (xy 26.725544 -11.679709) (xy 26.63984 -11.60254)
			(xy 26.559727 -11.519581) (xy 26.485597 -11.431236) (xy 26.41781 -11.337935) (xy 26.356696 -11.240133)
			(xy 26.302554 -11.138306) (xy 26.255646 -11.03295) (xy 26.216202 -10.924578) (xy 26.184414 -10.813719)
			(xy 26.160436 -10.700913) (xy 26.144386 -10.586709) (xy 26.136341 -10.471663) (xy 15.237386 -10.471663)
			(xy 15.237714 -10.500106) (xy 15.237219 -10.542969) (xy 15.229309 -10.628329) (xy 15.213557 -10.712596)
			(xy 15.190097 -10.795049) (xy 15.159129 -10.874986) (xy 15.120918 -10.951725) (xy 15.075789 -11.024611)
			(xy 15.024128 -11.093022) (xy 14.966374 -11.156374) (xy 14.903022 -11.214128) (xy 14.834611 -11.265789)
			(xy 14.761725 -11.310918) (xy 14.684986 -11.349129) (xy 14.605049 -11.380097) (xy 14.522596 -11.403557)
			(xy 14.438329 -11.419309) (xy 14.352969 -11.427219) (xy 14.267243 -11.427219) (xy 14.181883 -11.419309)
			(xy 14.097616 -11.403557) (xy 14.015163 -11.380097) (xy 13.935226 -11.349129) (xy 13.858487 -11.310918)
			(xy 13.785601 -11.265789) (xy 13.71719 -11.214128) (xy 13.653838 -11.156374) (xy 13.596084 -11.093022)
			(xy 13.544423 -11.024611) (xy 13.499294 -10.951725) (xy 13.461083 -10.874986) (xy 13.430115 -10.795049)
			(xy 13.406655 -10.712596) (xy 13.390903 -10.628329) (xy 13.382993 -10.542969) (xy 8.202231 -10.542969)
			(xy 5.7658 -12.9794) (xy 2.8448 -12.9794) (xy 2.281237 -13.542963) (xy 13.382993 -13.542963) (xy 13.382993 -13.457237)
			(xy 13.390903 -13.371877) (xy 13.406655 -13.28761) (xy 13.430115 -13.205157) (xy 13.461083 -13.12522)
			(xy 13.499294 -13.048481) (xy 13.544423 -12.975595) (xy 13.596084 -12.907184) (xy 13.653838 -12.843832)
			(xy 13.71719 -12.786078) (xy 13.785601 -12.734417) (xy 13.858487 -12.689288) (xy 13.935226 -12.651077)
			(xy 14.015163 -12.620109) (xy 14.097616 -12.596649) (xy 14.181883 -12.580897) (xy 14.267243 -12.572987)
			(xy 14.352969 -12.572987) (xy 14.438329 -12.580897) (xy 14.522596 -12.596649) (xy 14.605049 -12.620109)
			(xy 14.641063 -12.634061) (xy 30.632392 -12.634061) (xy 30.632392 -12.562739) (xy 30.640378 -12.491865)
			(xy 30.656248 -12.42233) (xy 30.679805 -12.35501) (xy 30.71075 -12.290751) (xy 30.748696 -12.23036)
			(xy 30.793165 -12.174598) (xy 30.843598 -12.124165) (xy 30.89936 -12.079696) (xy 30.959751 -12.04175)
			(xy 31.02401 -12.010805) (xy 31.09133 -11.987248) (xy 31.160865 -11.971378) (xy 31.231739 -11.963392)
			(xy 31.303061 -11.963392) (xy 31.373935 -11.971378) (xy 31.44347 -11.987248) (xy 31.51079 -12.010805)
			(xy 31.575049 -12.04175) (xy 31.63544 -12.079696) (xy 31.691202 -12.124165) (xy 31.741635 -12.174598)
			(xy 31.786104 -12.23036) (xy 31.82405 -12.290751) (xy 31.854995 -12.35501) (xy 31.878552 -12.42233)
			(xy 31.894422 -12.491865) (xy 31.902408 -12.562739) (xy 31.902908 -12.5984) (xy 31.902408 -12.634061)
			(xy 38.252392 -12.634061) (xy 38.252392 -12.562739) (xy 38.260378 -12.491865) (xy 38.276248 -12.42233)
			(xy 38.299805 -12.35501) (xy 38.33075 -12.290751) (xy 38.368696 -12.23036) (xy 38.413165 -12.174598)
			(xy 38.463598 -12.124165) (xy 38.51936 -12.079696) (xy 38.579751 -12.04175) (xy 38.64401 -12.010805)
			(xy 38.71133 -11.987248) (xy 38.780865 -11.971378) (xy 38.851739 -11.963392) (xy 38.923061 -11.963392)
			(xy 38.993935 -11.971378) (xy 39.06347 -11.987248) (xy 39.13079 -12.010805) (xy 39.195049 -12.04175)
			(xy 39.25544 -12.079696) (xy 39.311202 -12.124165) (xy 39.361635 -12.174598) (xy 39.406104 -12.23036)
			(xy 39.44405 -12.290751) (xy 39.474995 -12.35501) (xy 39.498552 -12.42233) (xy 39.514422 -12.491865)
			(xy 39.522408 -12.562739) (xy 39.522908 -12.5984) (xy 39.522408 -12.634061) (xy 45.872392 -12.634061)
			(xy 45.872392 -12.562739) (xy 45.880378 -12.491865) (xy 45.896248 -12.42233) (xy 45.919805 -12.35501)
			(xy 45.95075 -12.290751) (xy 45.988696 -12.23036) (xy 46.033165 -12.174598) (xy 46.083598 -12.124165)
			(xy 46.13936 -12.079696) (xy 46.199751 -12.04175) (xy 46.26401 -12.010805) (xy 46.33133 -11.987248)
			(xy 46.400865 -11.971378) (xy 46.471739 -11.963392) (xy 46.543061 -11.963392) (xy 46.613935 -11.971378)
			(xy 46.68347 -11.987248) (xy 46.75079 -12.010805) (xy 46.815049 -12.04175) (xy 46.87544 -12.079696)
			(xy 46.931202 -12.124165) (xy 46.981635 -12.174598) (xy 47.026104 -12.23036) (xy 47.06405 -12.290751)
			(xy 47.094995 -12.35501) (xy 47.118552 -12.42233) (xy 47.134422 -12.491865) (xy 47.142408 -12.562739)
			(xy 47.142908 -12.5984) (xy 47.142408 -12.634061) (xy 53.492392 -12.634061) (xy 53.492392 -12.562739)
			(xy 53.500378 -12.491865) (xy 53.516248 -12.42233) (xy 53.539805 -12.35501) (xy 53.57075 -12.290751)
			(xy 53.608696 -12.23036) (xy 53.653165 -12.174598) (xy 53.703598 -12.124165) (xy 53.75936 -12.079696)
			(xy 53.819751 -12.04175) (xy 53.88401 -12.010805) (xy 53.95133 -11.987248) (xy 54.020865 -11.971378)
			(xy 54.091739 -11.963392) (xy 54.163061 -11.963392) (xy 54.233935 -11.971378) (xy 54.30347 -11.987248)
			(xy 54.37079 -12.010805) (xy 54.435049 -12.04175) (xy 54.49544 -12.079696) (xy 54.551202 -12.124165)
			(xy 54.601635 -12.174598) (xy 54.646104 -12.23036) (xy 54.68405 -12.290751) (xy 54.714995 -12.35501)
			(xy 54.738552 -12.42233) (xy 54.754422 -12.491865) (xy 54.762408 -12.562739) (xy 54.762908 -12.5984)
			(xy 54.762408 -12.634061) (xy 54.754422 -12.704935) (xy 54.738552 -12.77447) (xy 54.714995 -12.84179)
			(xy 54.68405 -12.906049) (xy 54.646104 -12.96644) (xy 54.601635 -13.022202) (xy 54.551202 -13.072635)
			(xy 54.49544 -13.117104) (xy 54.435049 -13.15505) (xy 54.37079 -13.185995) (xy 54.30347 -13.209552)
			(xy 54.233935 -13.225422) (xy 54.163061 -13.233408) (xy 54.091739 -13.233408) (xy 54.020865 -13.225422)
			(xy 53.95133 -13.209552) (xy 53.88401 -13.185995) (xy 53.819751 -13.15505) (xy 53.75936 -13.117104)
			(xy 53.703598 -13.072635) (xy 53.653165 -13.022202) (xy 53.608696 -12.96644) (xy 53.57075 -12.906049)
			(xy 53.539805 -12.84179) (xy 53.516248 -12.77447) (xy 53.500378 -12.704935) (xy 53.492392 -12.634061)
			(xy 47.142408 -12.634061) (xy 47.134422 -12.704935) (xy 47.118552 -12.77447) (xy 47.094995 -12.84179)
			(xy 47.06405 -12.906049) (xy 47.026104 -12.96644) (xy 46.981635 -13.022202) (xy 46.931202 -13.072635)
			(xy 46.87544 -13.117104) (xy 46.815049 -13.15505) (xy 46.75079 -13.185995) (xy 46.68347 -13.209552)
			(xy 46.613935 -13.225422) (xy 46.543061 -13.233408) (xy 46.471739 -13.233408) (xy 46.400865 -13.225422)
			(xy 46.33133 -13.209552) (xy 46.26401 -13.185995) (xy 46.199751 -13.15505) (xy 46.13936 -13.117104)
			(xy 46.083598 -13.072635) (xy 46.033165 -13.022202) (xy 45.988696 -12.96644) (xy 45.95075 -12.906049)
			(xy 45.919805 -12.84179) (xy 45.896248 -12.77447) (xy 45.880378 -12.704935) (xy 45.872392 -12.634061)
			(xy 39.522408 -12.634061) (xy 39.514422 -12.704935) (xy 39.498552 -12.77447) (xy 39.474995 -12.84179)
			(xy 39.44405 -12.906049) (xy 39.406104 -12.96644) (xy 39.361635 -13.022202) (xy 39.311202 -13.072635)
			(xy 39.25544 -13.117104) (xy 39.195049 -13.15505) (xy 39.13079 -13.185995) (xy 39.06347 -13.209552)
			(xy 38.993935 -13.225422) (xy 38.923061 -13.233408) (xy 38.851739 -13.233408) (xy 38.780865 -13.225422)
			(xy 38.71133 -13.209552) (xy 38.64401 -13.185995) (xy 38.579751 -13.15505) (xy 38.51936 -13.117104)
			(xy 38.463598 -13.072635) (xy 38.413165 -13.022202) (xy 38.368696 -12.96644) (xy 38.33075 -12.906049)
			(xy 38.299805 -12.84179) (xy 38.276248 -12.77447) (xy 38.260378 -12.704935) (xy 38.252392 -12.634061)
			(xy 31.902408 -12.634061) (xy 31.894422 -12.704935) (xy 31.878552 -12.77447) (xy 31.854995 -12.84179)
			(xy 31.82405 -12.906049) (xy 31.786104 -12.96644) (xy 31.741635 -13.022202) (xy 31.691202 -13.072635)
			(xy 31.63544 -13.117104) (xy 31.575049 -13.15505) (xy 31.51079 -13.185995) (xy 31.44347 -13.209552)
			(xy 31.373935 -13.225422) (xy 31.303061 -13.233408) (xy 31.231739 -13.233408) (xy 31.160865 -13.225422)
			(xy 31.09133 -13.209552) (xy 31.02401 -13.185995) (xy 30.959751 -13.15505) (xy 30.89936 -13.117104)
			(xy 30.843598 -13.072635) (xy 30.793165 -13.022202) (xy 30.748696 -12.96644) (xy 30.71075 -12.906049)
			(xy 30.679805 -12.84179) (xy 30.656248 -12.77447) (xy 30.640378 -12.704935) (xy 30.632392 -12.634061)
			(xy 14.641063 -12.634061) (xy 14.684986 -12.651077) (xy 14.761725 -12.689288) (xy 14.834611 -12.734417)
			(xy 14.903022 -12.786078) (xy 14.966374 -12.843832) (xy 15.024128 -12.907184) (xy 15.075789 -12.975595)
			(xy 15.120918 -13.048481) (xy 15.159129 -13.12522) (xy 15.190097 -13.205157) (xy 15.213557 -13.28761)
			(xy 15.229309 -13.371877) (xy 15.237219 -13.457237) (xy 15.237714 -13.5001) (xy 15.237219 -13.542963)
			(xy 15.229309 -13.628323) (xy 15.225246 -13.650061) (xy 35.890192 -13.650061) (xy 35.890192 -13.578739)
			(xy 35.898178 -13.507865) (xy 35.914048 -13.43833) (xy 35.937605 -13.37101) (xy 35.96855 -13.306751)
			(xy 36.006496 -13.24636) (xy 36.050965 -13.190598) (xy 36.101398 -13.140165) (xy 36.15716 -13.095696)
			(xy 36.217551 -13.05775) (xy 36.28181 -13.026805) (xy 36.34913 -13.003248) (xy 36.418665 -12.987378)
			(xy 36.489539 -12.979392) (xy 36.560861 -12.979392) (xy 36.631735 -12.987378) (xy 36.70127 -13.003248)
			(xy 36.76859 -13.026805) (xy 36.832849 -13.05775) (xy 36.89324 -13.095696) (xy 36.949002 -13.140165)
			(xy 36.999435 -13.190598) (xy 37.043904 -13.24636) (xy 37.08185 -13.306751) (xy 37.112795 -13.37101)
			(xy 37.136352 -13.43833) (xy 37.152222 -13.507865) (xy 37.160208 -13.578739) (xy 37.160708 -13.6144)
			(xy 37.160208 -13.650061) (xy 37.152222 -13.720935) (xy 37.136352 -13.79047) (xy 37.112795 -13.85779)
			(xy 37.08185 -13.922049) (xy 37.043904 -13.98244) (xy 36.999435 -14.038202) (xy 36.949002 -14.088635)
			(xy 36.89324 -14.133104) (xy 36.832849 -14.17105) (xy 36.76859 -14.201995) (xy 36.70127 -14.225552)
			(xy 36.631735 -14.241422) (xy 36.560861 -14.249408) (xy 36.489539 -14.249408) (xy 36.418665 -14.241422)
			(xy 36.34913 -14.225552) (xy 36.28181 -14.201995) (xy 36.217551 -14.17105) (xy 36.15716 -14.133104)
			(xy 36.101398 -14.088635) (xy 36.050965 -14.038202) (xy 36.006496 -13.98244) (xy 35.96855 -13.922049)
			(xy 35.937605 -13.85779) (xy 35.914048 -13.79047) (xy 35.898178 -13.720935) (xy 35.890192 -13.650061)
			(xy 15.225246 -13.650061) (xy 15.213557 -13.71259) (xy 15.190097 -13.795043) (xy 15.159129 -13.87498)
			(xy 15.120918 -13.951719) (xy 15.075789 -14.024605) (xy 15.024128 -14.093016) (xy 14.966374 -14.156368)
			(xy 14.903022 -14.214122) (xy 14.834611 -14.265783) (xy 14.761725 -14.310912) (xy 14.684986 -14.349123)
			(xy 14.605049 -14.380091) (xy 14.522596 -14.403551) (xy 14.438329 -14.419303) (xy 14.352969 -14.427213)
			(xy 14.267243 -14.427213) (xy 14.181883 -14.419303) (xy 14.097616 -14.403551) (xy 14.015163 -14.380091)
			(xy 13.935226 -14.349123) (xy 13.858487 -14.310912) (xy 13.785601 -14.265783) (xy 13.71719 -14.214122)
			(xy 13.653838 -14.156368) (xy 13.596084 -14.093016) (xy 13.544423 -14.024605) (xy 13.499294 -13.951719)
			(xy 13.461083 -13.87498) (xy 13.430115 -13.795043) (xy 13.406655 -13.71259) (xy 13.390903 -13.628323)
			(xy 13.382993 -13.542963) (xy 2.281237 -13.542963) (xy 1.4732 -14.351) (xy 1.4732 -16.542957) (xy 13.382993 -16.542957)
			(xy 13.382993 -16.457231) (xy 13.390903 -16.371871) (xy 13.406655 -16.287604) (xy 13.430115 -16.205151)
			(xy 13.461083 -16.125214) (xy 13.499294 -16.048475) (xy 13.544423 -15.975589) (xy 13.596084 -15.907178)
			(xy 13.653838 -15.843826) (xy 13.71719 -15.786072) (xy 13.785601 -15.734411) (xy 13.858487 -15.689282)
			(xy 13.935226 -15.651071) (xy 14.015163 -15.620103) (xy 14.097616 -15.596643) (xy 14.181883 -15.580891)
			(xy 14.267243 -15.572981) (xy 14.352969 -15.572981) (xy 14.438329 -15.580891) (xy 14.522596 -15.596643)
			(xy 14.605049 -15.620103) (xy 14.684986 -15.651071) (xy 14.761725 -15.689282) (xy 14.834611 -15.734411)
			(xy 14.903022 -15.786072) (xy 14.966374 -15.843826) (xy 15.024128 -15.907178) (xy 15.075789 -15.975589)
			(xy 15.120918 -16.048475) (xy 15.159129 -16.125214) (xy 15.190097 -16.205151) (xy 15.213557 -16.287604)
			(xy 15.229309 -16.371871) (xy 15.237219 -16.457231) (xy 15.237714 -16.500094) (xy 15.237219 -16.542957)
			(xy 15.229309 -16.628317) (xy 15.213557 -16.712584) (xy 15.190097 -16.795037) (xy 15.159129 -16.874974)
			(xy 15.120918 -16.951713) (xy 15.075789 -17.024599) (xy 15.024128 -17.09301) (xy 14.966374 -17.156362)
			(xy 14.903022 -17.214116) (xy 14.834611 -17.265777) (xy 14.761725 -17.310906) (xy 14.684986 -17.349117)
			(xy 14.605049 -17.380085) (xy 14.522596 -17.403545) (xy 14.438329 -17.419297) (xy 14.352969 -17.427207)
			(xy 14.267243 -17.427207) (xy 14.181883 -17.419297) (xy 14.097616 -17.403545) (xy 14.015163 -17.380085)
			(xy 13.935226 -17.349117) (xy 13.858487 -17.310906) (xy 13.785601 -17.265777) (xy 13.71719 -17.214116)
			(xy 13.653838 -17.156362) (xy 13.596084 -17.09301) (xy 13.544423 -17.024599) (xy 13.499294 -16.951713)
			(xy 13.461083 -16.874974) (xy 13.430115 -16.795037) (xy 13.406655 -16.712584) (xy 13.390903 -16.628317)
			(xy 13.382993 -16.542957) (xy 1.4732 -16.542957) (xy 1.4732 -19.287744) (xy 1.473654 -19.309634)
			(xy 1.481151 -19.352768) (xy 1.495933 -19.393977) (xy 1.517562 -19.432041) (xy 1.545397 -19.465833)
			(xy 1.578614 -19.494352) (xy 1.616229 -19.516753) (xy 1.657128 -19.532373) (xy 1.7001 -19.540748)
			(xy 1.743871 -19.541632) (xy 1.787146 -19.534997) (xy 1.828642 -19.52104) (xy 1.848104 -19.51101)
			(xy 1.887364 -19.490303) (xy 1.968955 -19.455343) (xy 2.05341 -19.428017) (xy 2.140016 -19.408556)
			(xy 2.228042 -19.397124) (xy 2.316746 -19.393818) (xy 2.327827 -19.394424) (xy 3.882644 -19.394424)
			(xy 5.81406 -19.394424) (xy 5.81406 -19.542951) (xy 13.382993 -19.542951) (xy 13.382993 -19.457225)
			(xy 13.390903 -19.371865) (xy 13.406655 -19.287598) (xy 13.430115 -19.205145) (xy 13.461083 -19.125208)
			(xy 13.499294 -19.048469) (xy 13.544423 -18.975583) (xy 13.596084 -18.907172) (xy 13.653838 -18.84382)
			(xy 13.71719 -18.786066) (xy 13.785601 -18.734405) (xy 13.858487 -18.689276) (xy 13.935226 -18.651065)
			(xy 14.015163 -18.620097) (xy 14.097616 -18.596637) (xy 14.181883 -18.580885) (xy 14.267243 -18.572975)
			(xy 14.352969 -18.572975) (xy 14.438329 -18.580885) (xy 14.522596 -18.596637) (xy 14.605049 -18.620097)
			(xy 14.684986 -18.651065) (xy 14.761725 -18.689276) (xy 14.834611 -18.734405) (xy 14.903022 -18.786066)
			(xy 14.966374 -18.84382) (xy 15.024128 -18.907172) (xy 15.075789 -18.975583) (xy 15.120918 -19.048469)
			(xy 15.159129 -19.125208) (xy 15.190097 -19.205145) (xy 15.213557 -19.287598) (xy 15.229309 -19.371865)
			(xy 15.237219 -19.457225) (xy 15.237714 -19.500088) (xy 15.237345 -19.532039) (xy 19.996681 -19.532039)
			(xy 19.997529 -19.451093) (xy 20.006414 -19.370631) (xy 20.023247 -19.29145) (xy 20.047863 -19.214333)
			(xy 20.080018 -19.140042) (xy 20.119394 -19.069313) (xy 20.165601 -19.002846) (xy 20.218182 -18.941297)
			(xy 20.276617 -18.885276) (xy 20.340329 -18.835337) (xy 20.408686 -18.791974) (xy 20.481012 -18.755616)
			(xy 20.556592 -18.726622) (xy 20.634679 -18.70528) (xy 20.7145 -18.6918) (xy 20.754848 -18.688558)
			(xy 20.771336 -18.686912) (xy 20.802703 -18.676276) (xy 20.830275 -18.657924) (xy 20.852194 -18.633092)
			(xy 20.866981 -18.603455) (xy 20.87364 -18.57101) (xy 20.873212 -18.554446) (xy 20.871761 -18.527225)
			(xy 20.871635 -18.472707) (xy 20.872958 -18.44548) (xy 20.873378 -18.428951) (xy 20.866724 -18.396577)
			(xy 20.851966 -18.367004) (xy 20.830099 -18.342221) (xy 20.802594 -18.323896) (xy 20.7713 -18.313263)
			(xy 20.754848 -18.311622) (xy 20.714506 -18.308351) (xy 20.634695 -18.294868) (xy 20.556618 -18.273525)
			(xy 20.481047 -18.244531) (xy 20.40873 -18.208175) (xy 20.340382 -18.164816) (xy 20.276678 -18.114881)
			(xy 20.21825 -18.058866) (xy 20.165674 -17.997325) (xy 20.119472 -17.930865) (xy 20.080099 -17.860145)
			(xy 20.047946 -17.785864) (xy 20.023329 -17.708756) (xy 20.006494 -17.629585) (xy 19.997606 -17.549133)
			(xy 19.996753 -17.468195) (xy 20.003944 -17.387574) (xy 20.019108 -17.308065) (xy 20.042094 -17.230456)
			(xy 20.072675 -17.155514) (xy 20.110549 -17.08398) (xy 20.155341 -17.016561) (xy 20.206608 -16.953926)
			(xy 20.263844 -16.896692) (xy 20.326481 -16.845427) (xy 20.3939 -16.800637) (xy 20.465435 -16.762765)
			(xy 20.540379 -16.732186) (xy 20.617989 -16.709202) (xy 20.697498 -16.694041) (xy 20.77812 -16.686852)
			(xy 20.859057 -16.687708) (xy 20.939509 -16.696598) (xy 21.01868 -16.713436) (xy 21.095787 -16.738054)
			(xy 21.170067 -16.77021) (xy 21.240786 -16.809585) (xy 21.307244 -16.855789) (xy 21.368784 -16.908367)
			(xy 21.424797 -16.966797) (xy 21.47473 -17.030502) (xy 21.518087 -17.098851) (xy 21.554441 -17.17117)
			(xy 21.583432 -17.246741) (xy 21.604773 -17.324819) (xy 21.618253 -17.40463) (xy 21.621496 -17.444974)
			(xy 21.623168 -17.461457) (xy 21.633805 -17.492818) (xy 21.652154 -17.520386) (xy 21.67698 -17.542303)
			(xy 21.706609 -17.557093) (xy 21.739047 -17.56376) (xy 21.755608 -17.563338) (xy 21.782769 -17.561958)
			(xy 21.837159 -17.561958) (xy 21.86432 -17.563338) (xy 21.880887 -17.563732) (xy 21.91334 -17.557097)
			(xy 21.942986 -17.542324) (xy 21.967825 -17.52041) (xy 21.986179 -17.492837) (xy 21.996807 -17.461465)
			(xy 21.998432 -17.444974) (xy 22.001642 -17.404554) (xy 22.015189 -17.324603) (xy 22.036623 -17.246397)
			(xy 22.065732 -17.170712) (xy 22.102227 -17.098298) (xy 22.145745 -17.029874) (xy 22.195855 -16.96612)
			(xy 22.25206 -16.907668) (xy 22.313801 -16.855098) (xy 22.380466 -16.808931) (xy 22.451394 -16.769626)
			(xy 22.52588 -16.737573) (xy 22.603186 -16.71309) (xy 22.682544 -16.69642) (xy 22.763167 -16.687728)
			(xy 22.844255 -16.687101) (xy 22.925003 -16.694544) (xy 22.964902 -16.70177) (xy 22.99589 -16.707612)
			(xy 23.056342 -16.68907) (xy 23.390098 -16.355314) (xy 25.137872 -16.355314) (xy 25.154506 -16.354713)
			(xy 25.186644 -16.346113) (xy 25.215463 -16.329493) (xy 25.239001 -16.305983) (xy 25.255655 -16.277183)
			(xy 25.264293 -16.245056) (xy 25.264325 -16.211788) (xy 25.25575 -16.179644) (xy 25.23915 -16.150813)
			(xy 25.227788 -16.138652) (xy 25.196292 -16.10741) (xy 25.196292 -14.49959) (xy 25.59939 -14.096492)
			(xy 31.60141 -14.096492) (xy 32.029908 -14.52499) (xy 32.029908 -15.859861) (xy 43.814992 -15.859861)
			(xy 43.814992 -15.788539) (xy 43.822978 -15.717665) (xy 43.838848 -15.64813) (xy 43.862405 -15.58081)
			(xy 43.89335 -15.516551) (xy 43.931296 -15.45616) (xy 43.975765 -15.400398) (xy 44.026198 -15.349965)
			(xy 44.08196 -15.305496) (xy 44.142351 -15.26755) (xy 44.20661 -15.236605) (xy 44.27393 -15.213048)
			(xy 44.343465 -15.197178) (xy 44.414339 -15.189192) (xy 44.485661 -15.189192) (xy 44.556535 -15.197178)
			(xy 44.62607 -15.213048) (xy 44.69339 -15.236605) (xy 44.757649 -15.26755) (xy 44.81804 -15.305496)
			(xy 44.873802 -15.349965) (xy 44.924235 -15.400398) (xy 44.968704 -15.45616) (xy 44.998928 -15.504261)
			(xy 52.552592 -15.504261) (xy 52.552592 -15.432939) (xy 52.560578 -15.362065) (xy 52.576448 -15.29253)
			(xy 52.600005 -15.22521) (xy 52.63095 -15.160951) (xy 52.668896 -15.10056) (xy 52.713365 -15.044798)
			(xy 52.763798 -14.994365) (xy 52.81956 -14.949896) (xy 52.879951 -14.91195) (xy 52.94421 -14.881005)
			(xy 53.01153 -14.857448) (xy 53.081065 -14.841578) (xy 53.151939 -14.833592) (xy 53.223261 -14.833592)
			(xy 53.294135 -14.841578) (xy 53.36367 -14.857448) (xy 53.43099 -14.881005) (xy 53.495249 -14.91195)
			(xy 53.55564 -14.949896) (xy 53.611402 -14.994365) (xy 53.661835 -15.044798) (xy 53.706304 -15.10056)
			(xy 53.74425 -15.160951) (xy 53.775195 -15.22521) (xy 53.798752 -15.29253) (xy 53.814622 -15.362065)
			(xy 53.822608 -15.432939) (xy 53.823108 -15.4686) (xy 53.822608 -15.504261) (xy 53.814622 -15.575135)
			(xy 53.798752 -15.64467) (xy 53.775195 -15.71199) (xy 53.74425 -15.776249) (xy 53.706304 -15.83664)
			(xy 53.661835 -15.892402) (xy 53.611402 -15.942835) (xy 53.55564 -15.987304) (xy 53.495249 -16.02525)
			(xy 53.43099 -16.056195) (xy 53.36367 -16.079752) (xy 53.294135 -16.095622) (xy 53.223261 -16.103608)
			(xy 53.151939 -16.103608) (xy 53.081065 -16.095622) (xy 53.01153 -16.079752) (xy 52.94421 -16.056195)
			(xy 52.879951 -16.02525) (xy 52.81956 -15.987304) (xy 52.763798 -15.942835) (xy 52.713365 -15.892402)
			(xy 52.668896 -15.83664) (xy 52.63095 -15.776249) (xy 52.600005 -15.71199) (xy 52.576448 -15.64467)
			(xy 52.560578 -15.575135) (xy 52.552592 -15.504261) (xy 44.998928 -15.504261) (xy 45.00665 -15.516551)
			(xy 45.037595 -15.58081) (xy 45.061152 -15.64813) (xy 45.077022 -15.717665) (xy 45.085008 -15.788539)
			(xy 45.085508 -15.8242) (xy 45.085008 -15.859861) (xy 45.077022 -15.930735) (xy 45.061152 -16.00027)
			(xy 45.037595 -16.06759) (xy 45.00665 -16.131849) (xy 44.968704 -16.19224) (xy 44.924235 -16.248002)
			(xy 44.873802 -16.298435) (xy 44.81804 -16.342904) (xy 44.757649 -16.38085) (xy 44.69339 -16.411795)
			(xy 44.62607 -16.435352) (xy 44.556535 -16.451222) (xy 44.485661 -16.459208) (xy 44.414339 -16.459208)
			(xy 44.343465 -16.451222) (xy 44.27393 -16.435352) (xy 44.20661 -16.411795) (xy 44.142351 -16.38085)
			(xy 44.08196 -16.342904) (xy 44.026198 -16.298435) (xy 43.975765 -16.248002) (xy 43.931296 -16.19224)
			(xy 43.89335 -16.131849) (xy 43.862405 -16.06759) (xy 43.838848 -16.00027) (xy 43.822978 -15.930735)
			(xy 43.814992 -15.859861) (xy 32.029908 -15.859861) (xy 32.029908 -16.00581) (xy 32.0294 -16.006064)
			(xy 32.0294 -18.145861) (xy 33.172392 -18.145861) (xy 33.172392 -18.074539) (xy 33.180378 -18.003665)
			(xy 33.196248 -17.93413) (xy 33.219805 -17.86681) (xy 33.25075 -17.802551) (xy 33.288696 -17.74216)
			(xy 33.333165 -17.686398) (xy 33.383598 -17.635965) (xy 33.43936 -17.591496) (xy 33.499751 -17.55355)
			(xy 33.56401 -17.522605) (xy 33.63133 -17.499048) (xy 33.700865 -17.483178) (xy 33.771739 -17.475192)
			(xy 33.843061 -17.475192) (xy 33.913935 -17.483178) (xy 33.98347 -17.499048) (xy 34.05079 -17.522605)
			(xy 34.115049 -17.55355) (xy 34.17544 -17.591496) (xy 34.231202 -17.635965) (xy 34.281635 -17.686398)
			(xy 34.326104 -17.74216) (xy 34.36405 -17.802551) (xy 34.394995 -17.86681) (xy 34.418552 -17.93413)
			(xy 34.434422 -18.003665) (xy 34.442408 -18.074539) (xy 34.442908 -18.1102) (xy 34.442408 -18.145861)
			(xy 34.434422 -18.216735) (xy 34.418552 -18.28627) (xy 34.394995 -18.35359) (xy 34.36405 -18.417849)
			(xy 34.326104 -18.47824) (xy 34.281635 -18.534002) (xy 34.231202 -18.584435) (xy 34.17544 -18.628904)
			(xy 34.115049 -18.66685) (xy 34.05079 -18.697795) (xy 33.98347 -18.721352) (xy 33.913935 -18.737222)
			(xy 33.843061 -18.745208) (xy 33.771739 -18.745208) (xy 33.700865 -18.737222) (xy 33.63133 -18.721352)
			(xy 33.56401 -18.697795) (xy 33.499751 -18.66685) (xy 33.43936 -18.628904) (xy 33.383598 -18.584435)
			(xy 33.333165 -18.534002) (xy 33.288696 -18.47824) (xy 33.25075 -18.417849) (xy 33.219805 -18.35359)
			(xy 33.196248 -18.28627) (xy 33.180378 -18.216735) (xy 33.172392 -18.145861) (xy 32.0294 -18.145861)
			(xy 32.0294 -19.1516) (xy 31.993739 -19.187261) (xy 48.056792 -19.187261) (xy 48.056792 -19.115939)
			(xy 48.064778 -19.045065) (xy 48.080648 -18.97553) (xy 48.104205 -18.90821) (xy 48.13515 -18.843951)
			(xy 48.173096 -18.78356) (xy 48.217565 -18.727798) (xy 48.267998 -18.677365) (xy 48.32376 -18.632896)
			(xy 48.384151 -18.59495) (xy 48.44841 -18.564005) (xy 48.51573 -18.540448) (xy 48.585265 -18.524578)
			(xy 48.656139 -18.516592) (xy 48.727461 -18.516592) (xy 48.798335 -18.524578) (xy 48.86787 -18.540448)
			(xy 48.93519 -18.564005) (xy 48.999449 -18.59495) (xy 49.05984 -18.632896) (xy 49.115602 -18.677365)
			(xy 49.166035 -18.727798) (xy 49.210504 -18.78356) (xy 49.24845 -18.843951) (xy 49.279395 -18.90821)
			(xy 49.302952 -18.97553) (xy 49.318822 -19.045065) (xy 49.326808 -19.115939) (xy 49.327308 -19.1516)
			(xy 49.326808 -19.187261) (xy 49.318822 -19.258135) (xy 49.302952 -19.32767) (xy 49.279395 -19.39499)
			(xy 49.24845 -19.459249) (xy 49.210504 -19.51964) (xy 49.166035 -19.575402) (xy 49.115602 -19.625835)
			(xy 49.05984 -19.670304) (xy 48.999449 -19.70825) (xy 48.93519 -19.739195) (xy 48.86787 -19.762752)
			(xy 48.798335 -19.778622) (xy 48.727461 -19.786608) (xy 48.656139 -19.786608) (xy 48.585265 -19.778622)
			(xy 48.51573 -19.762752) (xy 48.44841 -19.739195) (xy 48.384151 -19.70825) (xy 48.32376 -19.670304)
			(xy 48.267998 -19.625835) (xy 48.217565 -19.575402) (xy 48.173096 -19.51964) (xy 48.13515 -19.459249)
			(xy 48.104205 -19.39499) (xy 48.080648 -19.32767) (xy 48.064778 -19.258135) (xy 48.056792 -19.187261)
			(xy 31.993739 -19.187261) (xy 31.369 -19.812) (xy 26.797 -19.812) (xy 26.6446 -19.6596) (xy 26.6446 -17.6022)
			(xy 26.162 -17.1196) (xy 26.005028 -17.1196) (xy 25.983184 -17.127728) (xy 25.960509 -17.13593) (xy 25.913687 -17.147463)
			(xy 25.865817 -17.153273) (xy 25.841706 -17.153636) (xy 23.720806 -17.153636) (xy 23.620984 -17.253712)
			(xy 23.602442 -17.314164) (xy 23.608284 -17.345152) (xy 23.615472 -17.385062) (xy 23.622953 -17.465813)
			(xy 23.622359 -17.546908) (xy 23.613693 -17.627541) (xy 23.597044 -17.70691) (xy 23.572575 -17.784228)
			(xy 23.540531 -17.858725) (xy 23.50123 -17.929663) (xy 23.455062 -17.996335) (xy 23.402485 -18.05808)
			(xy 23.344023 -18.114284) (xy 23.280256 -18.164388) (xy 23.211817 -18.207896) (xy 23.139388 -18.244374)
			(xy 23.063686 -18.27346) (xy 22.985465 -18.294865) (xy 22.905502 -18.308376) (xy 22.86508 -18.311622)
			(xy 22.848612 -18.31324) (xy 22.817287 -18.323865) (xy 22.789744 -18.342184) (xy 22.767834 -18.366966)
			(xy 22.753028 -18.396546) (xy 22.746321 -18.428937) (xy 22.746716 -18.44548) (xy 22.74824 -18.50009)
			(xy 22.746716 -18.554446) (xy 22.746248 -18.571015) (xy 22.752892 -18.603476) (xy 22.767678 -18.633129)
			(xy 22.789607 -18.65797) (xy 22.817196 -18.67632) (xy 22.848583 -18.68694) (xy 22.86508 -18.688558)
			(xy 22.905431 -18.691788) (xy 22.985256 -18.705267) (xy 23.063347 -18.726608) (xy 23.138932 -18.755601)
			(xy 23.211262 -18.791959) (xy 23.279623 -18.835323) (xy 23.343339 -18.885263) (xy 23.401778 -18.941285)
			(xy 23.454363 -19.002836) (xy 23.500573 -19.069306) (xy 23.539952 -19.140037) (xy 23.57211 -19.214331)
			(xy 23.596728 -19.291452) (xy 23.613563 -19.370636) (xy 23.622449 -19.451102) (xy 23.623298 -19.532052)
			(xy 23.616101 -19.612686) (xy 23.60093 -19.692206) (xy 23.577934 -19.769826) (xy 23.547341 -19.844778)
			(xy 23.509454 -19.916319) (xy 23.464648 -19.983744) (xy 23.413365 -20.046383) (xy 23.356113 -20.103619)
			(xy 23.293459 -20.154884) (xy 23.226022 -20.199671) (xy 23.15447 -20.237538) (xy 23.07951 -20.26811)
			(xy 23.001883 -20.291084) (xy 22.922359 -20.306233) (xy 22.841723 -20.313407) (xy 22.760773 -20.312536)
			(xy 22.68031 -20.303627) (xy 22.60113 -20.286769) (xy 22.524016 -20.262129) (xy 22.449732 -20.22995)
			(xy 22.379011 -20.190552) (xy 22.312554 -20.144323) (xy 22.251019 -20.09172) (xy 22.195013 -20.033265)
			(xy 22.145091 -19.969536) (xy 22.101746 -19.901163) (xy 22.065408 -19.828822) (xy 22.036436 -19.753229)
			(xy 22.015117 -19.675132) (xy 22.001662 -19.595303) (xy 21.998432 -19.554952) (xy 21.996701 -19.538497)
			(xy 21.986024 -19.507197) (xy 21.967663 -19.479692) (xy 21.942851 -19.457828) (xy 21.913253 -19.443074)
			(xy 21.880858 -19.436422) (xy 21.86432 -19.436842) (xy 21.837159 -19.438222) (xy 21.782769 -19.438222)
			(xy 21.755608 -19.436842) (xy 21.739058 -19.436381) (xy 21.706631 -19.442996) (xy 21.677 -19.457738)
			(xy 21.652164 -19.479613) (xy 21.633798 -19.507145) (xy 21.623141 -19.538478) (xy 21.621496 -19.554952)
			(xy 21.618257 -19.595301) (xy 21.6048 -19.675125) (xy 21.58348 -19.753218) (xy 21.554508 -19.828807)
			(xy 21.51817 -19.901143) (xy 21.474827 -19.969512) (xy 21.424906 -20.033238) (xy 21.368901 -20.091689)
			(xy 21.307367 -20.144288) (xy 21.240913 -20.190514) (xy 21.170195 -20.229909) (xy 21.095914 -20.262085)
			(xy 21.018804 -20.286723) (xy 20.939627 -20.303579) (xy 20.859168 -20.312487) (xy 20.778222 -20.313358)
			(xy 20.69759 -20.306183) (xy 20.618069 -20.291035) (xy 20.540447 -20.268061) (xy 20.46549 -20.237491)
			(xy 20.393941 -20.199626) (xy 20.326508 -20.15484) (xy 20.263856 -20.103578) (xy 20.206608 -20.046345)
			(xy 20.155327 -19.983708) (xy 20.110522 -19.916288) (xy 20.072637 -19.844749) (xy 20.042045 -19.769802)
			(xy 20.01905 -19.692186) (xy 20.003879 -19.612669) (xy 19.996681 -19.532039) (xy 15.237345 -19.532039)
			(xy 15.237219 -19.542951) (xy 15.229309 -19.628311) (xy 15.213557 -19.712578) (xy 15.190097 -19.795031)
			(xy 15.159129 -19.874968) (xy 15.120918 -19.951707) (xy 15.075789 -20.024593) (xy 15.024128 -20.093004)
			(xy 14.966374 -20.156356) (xy 14.903022 -20.21411) (xy 14.834611 -20.265771) (xy 14.761725 -20.3109)
			(xy 14.684986 -20.349111) (xy 14.605049 -20.380079) (xy 14.522596 -20.403539) (xy 14.438329 -20.419291)
			(xy 14.352969 -20.427201) (xy 14.267243 -20.427201) (xy 14.181883 -20.419291) (xy 14.097616 -20.403539)
			(xy 14.015163 -20.380079) (xy 13.935226 -20.349111) (xy 13.858487 -20.3109) (xy 13.785601 -20.265771)
			(xy 13.71719 -20.21411) (xy 13.653838 -20.156356) (xy 13.596084 -20.093004) (xy 13.544423 -20.024593)
			(xy 13.499294 -19.951707) (xy 13.461083 -19.874968) (xy 13.430115 -19.795031) (xy 13.406655 -19.712578)
			(xy 13.390903 -19.628311) (xy 13.382993 -19.542951) (xy 5.81406 -19.542951) (xy 5.81406 -21.32584)
			(xy 3.882644 -21.32584) (xy 3.882644 -19.394424) (xy 2.327827 -19.394424) (xy 2.405379 -19.398665)
			(xy 2.493194 -19.411624) (xy 2.579448 -19.432587) (xy 2.663416 -19.461376) (xy 2.744387 -19.497748)
			(xy 2.82168 -19.541396) (xy 2.894641 -19.591953) (xy 2.962655 -19.648992) (xy 3.025149 -19.71203)
			(xy 3.081594 -19.780538) (xy 3.131516 -19.853935) (xy 3.174491 -19.931604) (xy 3.210159 -20.012888)
			(xy 3.238217 -20.097103) (xy 3.25843 -20.183536) (xy 3.270626 -20.27146) (xy 3.274703 -20.360132)
			(xy 3.270626 -20.448804) (xy 3.25843 -20.536728) (xy 3.238217 -20.623161) (xy 3.210159 -20.707376)
			(xy 3.174491 -20.78866) (xy 3.131516 -20.866329) (xy 3.081594 -20.939726) (xy 3.025149 -21.008234)
			(xy 2.962655 -21.071272) (xy 2.894641 -21.128311) (xy 2.82168 -21.178868) (xy 2.744387 -21.222516)
			(xy 2.663416 -21.258888) (xy 2.579448 -21.287677) (xy 2.493194 -21.30864) (xy 2.405379 -21.321599)
			(xy 2.316746 -21.326446) (xy 2.228042 -21.32314) (xy 2.140016 -21.311708) (xy 2.05341 -21.292247)
			(xy 1.968955 -21.264921) (xy 1.887364 -21.229961) (xy 1.848104 -21.209254) (xy 1.828641 -21.199239)
			(xy 1.787149 -21.185307) (xy 1.743883 -21.178692) (xy 1.700124 -21.179589) (xy 1.657166 -21.187972)
			(xy 1.61628 -21.203592) (xy 1.578676 -21.225988) (xy 1.545466 -21.254497) (xy 1.517633 -21.288276)
			(xy 1.496 -21.326325) (xy 1.481208 -21.367517) (xy 1.473694 -21.410636) (xy 1.4732 -21.43252) (xy 1.4732 -21.500084)
			(xy 19.996152 -21.500084) (xy 20.000196 -21.419054) (xy 20.012288 -21.33883) (xy 20.032307 -21.260208)
			(xy 20.060056 -21.18397) (xy 20.095257 -21.110874) (xy 20.137561 -21.041646) (xy 20.186548 -20.976974)
			(xy 20.241731 -20.917502) (xy 20.302561 -20.863819) (xy 20.368434 -20.816459) (xy 20.438695 -20.775894)
			(xy 20.512646 -20.742526) (xy 20.589552 -20.716687) (xy 20.668649 -20.698634) (xy 20.74915 -20.688546)
			(xy 20.830255 -20.686523) (xy 20.911159 -20.692586) (xy 20.991057 -20.706674) (xy 21.069155 -20.728647)
			(xy 21.144677 -20.758288) (xy 21.216873 -20.7953) (xy 21.285025 -20.839317) (xy 21.348455 -20.889902)
			(xy 21.406534 -20.94655) (xy 21.458684 -21.0087) (xy 21.504386 -21.075733) (xy 21.543187 -21.146983)
			(xy 21.574701 -21.221743) (xy 21.598615 -21.299269) (xy 21.61469 -21.378791) (xy 21.622768 -21.459519)
			(xy 21.623274 -21.500084) (xy 21.996148 -21.500084) (xy 22.000192 -21.419054) (xy 22.012284 -21.33883)
			(xy 22.032303 -21.260208) (xy 22.060052 -21.18397) (xy 22.095253 -21.110874) (xy 22.137557 -21.041646)
			(xy 22.186544 -20.976974) (xy 22.241727 -20.917502) (xy 22.302557 -20.863819) (xy 22.36843 -20.816459)
			(xy 22.438691 -20.775894) (xy 22.512642 -20.742526) (xy 22.589548 -20.716687) (xy 22.668645 -20.698634)
			(xy 22.749146 -20.688546) (xy 22.830251 -20.686523) (xy 22.911155 -20.692586) (xy 22.991053 -20.706674)
			(xy 23.069151 -20.728647) (xy 23.144673 -20.758288) (xy 23.216869 -20.7953) (xy 23.285021 -20.839317)
			(xy 23.348451 -20.889902) (xy 23.40653 -20.94655) (xy 23.45868 -21.0087) (xy 23.504382 -21.075733)
			(xy 23.543183 -21.146983) (xy 23.574697 -21.221743) (xy 23.598611 -21.299269) (xy 23.614686 -21.378791)
			(xy 23.622764 -21.459519) (xy 23.62327 -21.500084) (xy 23.622764 -21.540649) (xy 23.614686 -21.621377)
			(xy 23.61382 -21.625661) (xy 37.160192 -21.625661) (xy 37.160192 -21.554339) (xy 37.168178 -21.483465)
			(xy 37.184048 -21.41393) (xy 37.207605 -21.34661) (xy 37.23855 -21.282351) (xy 37.276496 -21.22196)
			(xy 37.320965 -21.166198) (xy 37.371398 -21.115765) (xy 37.42716 -21.071296) (xy 37.487551 -21.03335)
			(xy 37.55181 -21.002405) (xy 37.61913 -20.978848) (xy 37.688665 -20.962978) (xy 37.759539 -20.954992)
			(xy 37.830861 -20.954992) (xy 37.901735 -20.962978) (xy 37.97127 -20.978848) (xy 38.03859 -21.002405)
			(xy 38.102849 -21.03335) (xy 38.16324 -21.071296) (xy 38.219002 -21.115765) (xy 38.269435 -21.166198)
			(xy 38.313904 -21.22196) (xy 38.35185 -21.282351) (xy 38.382795 -21.34661) (xy 38.406352 -21.41393)
			(xy 38.422222 -21.483465) (xy 38.430208 -21.554339) (xy 38.430708 -21.59) (xy 38.430208 -21.625661)
			(xy 38.422222 -21.696535) (xy 38.406352 -21.76607) (xy 38.382795 -21.83339) (xy 38.35185 -21.897649)
			(xy 38.313904 -21.95804) (xy 38.269435 -22.013802) (xy 38.219002 -22.064235) (xy 38.16324 -22.108704)
			(xy 38.102849 -22.14665) (xy 38.03859 -22.177595) (xy 37.97127 -22.201152) (xy 37.901735 -22.217022)
			(xy 37.830861 -22.225008) (xy 37.759539 -22.225008) (xy 37.688665 -22.217022) (xy 37.61913 -22.201152)
			(xy 37.55181 -22.177595) (xy 37.487551 -22.14665) (xy 37.42716 -22.108704) (xy 37.371398 -22.064235)
			(xy 37.320965 -22.013802) (xy 37.276496 -21.95804) (xy 37.23855 -21.897649) (xy 37.207605 -21.83339)
			(xy 37.184048 -21.76607) (xy 37.168178 -21.696535) (xy 37.160192 -21.625661) (xy 23.61382 -21.625661)
			(xy 23.598611 -21.700899) (xy 23.574697 -21.778425) (xy 23.543183 -21.853185) (xy 23.504382 -21.924435)
			(xy 23.45868 -21.991468) (xy 23.40653 -22.053618) (xy 23.348451 -22.110266) (xy 23.285021 -22.160851)
			(xy 23.216869 -22.204868) (xy 23.144673 -22.24188) (xy 23.069151 -22.271521) (xy 22.991053 -22.293494)
			(xy 22.911155 -22.307582) (xy 22.830251 -22.313645) (xy 22.749146 -22.311622) (xy 22.668645 -22.301534)
			(xy 22.589548 -22.283481) (xy 22.512642 -22.257642) (xy 22.438691 -22.224274) (xy 22.36843 -22.183709)
			(xy 22.302557 -22.136349) (xy 22.241727 -22.082666) (xy 22.186544 -22.023194) (xy 22.137557 -21.958522)
			(xy 22.095253 -21.889294) (xy 22.060052 -21.816198) (xy 22.032303 -21.73996) (xy 22.012284 -21.661338)
			(xy 22.000192 -21.581114) (xy 21.996148 -21.500084) (xy 21.623274 -21.500084) (xy 21.622768 -21.540649)
			(xy 21.61469 -21.621377) (xy 21.598615 -21.700899) (xy 21.574701 -21.778425) (xy 21.543187 -21.853185)
			(xy 21.504386 -21.924435) (xy 21.458684 -21.991468) (xy 21.406534 -22.053618) (xy 21.348455 -22.110266)
			(xy 21.285025 -22.160851) (xy 21.216873 -22.204868) (xy 21.144677 -22.24188) (xy 21.069155 -22.271521)
			(xy 20.991057 -22.293494) (xy 20.911159 -22.307582) (xy 20.830255 -22.313645) (xy 20.74915 -22.311622)
			(xy 20.668649 -22.301534) (xy 20.589552 -22.283481) (xy 20.512646 -22.257642) (xy 20.438695 -22.224274)
			(xy 20.368434 -22.183709) (xy 20.302561 -22.136349) (xy 20.241731 -22.082666) (xy 20.186548 -22.023194)
			(xy 20.137561 -21.958522) (xy 20.095257 -21.889294) (xy 20.060056 -21.816198) (xy 20.032307 -21.73996)
			(xy 20.012288 -21.661338) (xy 20.000196 -21.581114) (xy 19.996152 -21.500084) (xy 1.4732 -21.500084)
			(xy 1.4732 -22.284944) (xy 1.473654 -22.306834) (xy 1.481151 -22.349968) (xy 1.495933 -22.391177)
			(xy 1.517562 -22.429241) (xy 1.545397 -22.463033) (xy 1.578614 -22.491552) (xy 1.616229 -22.513953)
			(xy 1.657128 -22.529573) (xy 1.7001 -22.537948) (xy 1.743871 -22.538832) (xy 1.787146 -22.532197)
			(xy 1.828642 -22.51824) (xy 1.848104 -22.50821) (xy 1.887044 -22.48766) (xy 1.967958 -22.452923)
			(xy 2.051697 -22.425696) (xy 2.137568 -22.406205) (xy 2.224856 -22.394612) (xy 2.312837 -22.391013)
			(xy 2.400781 -22.395438) (xy 2.487956 -22.40785) (xy 2.57364 -22.428147) (xy 2.65712 -22.456159)
			(xy 2.737704 -22.491654) (xy 2.814722 -22.534337) (xy 2.887535 -22.583854) (xy 2.955538 -22.639794)
			(xy 3.018166 -22.701692) (xy 3.074899 -22.769034) (xy 3.125267 -22.841261) (xy 3.168851 -22.917773)
			(xy 3.205288 -22.997935) (xy 3.234278 -23.081081) (xy 3.255577 -23.166521) (xy 3.269011 -23.253545)
			(xy 3.274467 -23.341431) (xy 3.2719 -23.429448) (xy 3.261332 -23.516866) (xy 3.242849 -23.602959)
			(xy 3.216607 -23.687013) (xy 3.182821 -23.768328) (xy 3.141774 -23.84623) (xy 3.093805 -23.920072)
			(xy 3.039314 -23.989241) (xy 3.009392 -24.021542) (xy 2.99475 -24.037675) (xy 2.97065 -24.073966)
			(xy 2.953092 -24.113836) (xy 2.942591 -24.156116) (xy 2.939454 -24.199567) (xy 2.943773 -24.242917)
			(xy 2.955422 -24.284895) (xy 2.97406 -24.324271) (xy 2.99914 -24.359892) (xy 3.014218 -24.375618)
			(xy 3.1496 -24.511) (xy 3.755644 -24.511) (xy 3.772289 -24.510452) (xy 3.804441 -24.501826) (xy 3.833267 -24.485175)
			(xy 3.856802 -24.461632) (xy 3.873443 -24.4328) (xy 3.882057 -24.400645) (xy 3.882644 -24.384) (xy 3.882644 -22.391624)
			(xy 5.81406 -22.391624) (xy 5.81406 -22.542945) (xy 13.382993 -22.542945) (xy 13.382993 -22.457219)
			(xy 13.390903 -22.371859) (xy 13.406655 -22.287592) (xy 13.430115 -22.205139) (xy 13.461083 -22.125202)
			(xy 13.499294 -22.048463) (xy 13.544423 -21.975577) (xy 13.596084 -21.907166) (xy 13.653838 -21.843814)
			(xy 13.71719 -21.78606) (xy 13.785601 -21.734399) (xy 13.858487 -21.68927) (xy 13.935226 -21.651059)
			(xy 14.015163 -21.620091) (xy 14.097616 -21.596631) (xy 14.181883 -21.580879) (xy 14.267243 -21.572969)
			(xy 14.352969 -21.572969) (xy 14.438329 -21.580879) (xy 14.522596 -21.596631) (xy 14.605049 -21.620091)
			(xy 14.684986 -21.651059) (xy 14.761725 -21.68927) (xy 14.834611 -21.734399) (xy 14.903022 -21.78606)
			(xy 14.966374 -21.843814) (xy 15.024128 -21.907166) (xy 15.075789 -21.975577) (xy 15.120918 -22.048463)
			(xy 15.159129 -22.125202) (xy 15.190097 -22.205139) (xy 15.213557 -22.287592) (xy 15.229309 -22.371859)
			(xy 15.237219 -22.457219) (xy 15.237714 -22.500082) (xy 15.237219 -22.542945) (xy 15.229309 -22.628305)
			(xy 15.213557 -22.712572) (xy 15.190097 -22.795025) (xy 15.159129 -22.874962) (xy 15.120918 -22.951701)
			(xy 15.075789 -23.024587) (xy 15.024128 -23.092998) (xy 14.966374 -23.15635) (xy 14.903022 -23.214104)
			(xy 14.834611 -23.265765) (xy 14.761725 -23.310894) (xy 14.684986 -23.349105) (xy 14.605049 -23.380073)
			(xy 14.522596 -23.403533) (xy 14.438329 -23.419285) (xy 14.352969 -23.427195) (xy 14.267243 -23.427195)
			(xy 14.181883 -23.419285) (xy 14.097616 -23.403533) (xy 14.015163 -23.380073) (xy 13.935226 -23.349105)
			(xy 13.858487 -23.310894) (xy 13.785601 -23.265765) (xy 13.71719 -23.214104) (xy 13.653838 -23.15635)
			(xy 13.596084 -23.092998) (xy 13.544423 -23.024587) (xy 13.499294 -22.951701) (xy 13.461083 -22.874962)
			(xy 13.430115 -22.795025) (xy 13.406655 -22.712572) (xy 13.390903 -22.628305) (xy 13.382993 -22.542945)
			(xy 5.81406 -22.542945) (xy 5.81406 -23.50008) (xy 19.996152 -23.50008) (xy 20.000196 -23.41905)
			(xy 20.012288 -23.338826) (xy 20.032307 -23.260204) (xy 20.060056 -23.183966) (xy 20.095257 -23.11087)
			(xy 20.137561 -23.041642) (xy 20.186548 -22.97697) (xy 20.241731 -22.917498) (xy 20.302561 -22.863815)
			(xy 20.368434 -22.816455) (xy 20.438695 -22.77589) (xy 20.512646 -22.742522) (xy 20.589552 -22.716683)
			(xy 20.668649 -22.69863) (xy 20.74915 -22.688542) (xy 20.830255 -22.686519) (xy 20.911159 -22.692582)
			(xy 20.991057 -22.70667) (xy 21.069155 -22.728643) (xy 21.144677 -22.758284) (xy 21.216873 -22.795296)
			(xy 21.285025 -22.839313) (xy 21.348455 -22.889898) (xy 21.406534 -22.946546) (xy 21.458684 -23.008696)
			(xy 21.504386 -23.075729) (xy 21.543187 -23.146979) (xy 21.574701 -23.221739) (xy 21.598615 -23.299265)
			(xy 21.61469 -23.378787) (xy 21.622768 -23.459515) (xy 21.623274 -23.50008) (xy 21.996148 -23.50008)
			(xy 22.000192 -23.41905) (xy 22.012284 -23.338826) (xy 22.032303 -23.260204) (xy 22.060052 -23.183966)
			(xy 22.095253 -23.11087) (xy 22.137557 -23.041642) (xy 22.186544 -22.97697) (xy 22.241727 -22.917498)
			(xy 22.302557 -22.863815) (xy 22.36843 -22.816455) (xy 22.438691 -22.77589) (xy 22.512642 -22.742522)
			(xy 22.589548 -22.716683) (xy 22.668645 -22.69863) (xy 22.749146 -22.688542) (xy 22.830251 -22.686519)
			(xy 22.911155 -22.692582) (xy 22.991053 -22.70667) (xy 23.069151 -22.728643) (xy 23.144673 -22.758284)
			(xy 23.216869 -22.795296) (xy 23.285021 -22.839313) (xy 23.348451 -22.889898) (xy 23.40653 -22.946546)
			(xy 23.45868 -23.008696) (xy 23.504382 -23.075729) (xy 23.543183 -23.146979) (xy 23.574697 -23.221739)
			(xy 23.598611 -23.299265) (xy 23.614686 -23.378787) (xy 23.622764 -23.459515) (xy 23.623074 -23.484332)
			(xy 26.792943 -23.484332) (xy 26.796946 -23.39647) (xy 26.808922 -23.309336) (xy 26.828773 -23.223652)
			(xy 26.856332 -23.140128) (xy 26.891373 -23.059456) (xy 26.933604 -22.982305) (xy 26.982676 -22.909314)
			(xy 27.038183 -22.841088) (xy 27.099663 -22.778192) (xy 27.166608 -22.721147) (xy 27.238463 -22.670426)
			(xy 27.314633 -22.626449) (xy 27.394486 -22.589581) (xy 27.477361 -22.560128) (xy 27.562571 -22.538332)
			(xy 27.64941 -22.524376) (xy 27.737158 -22.518373) (xy 27.748182 -22.518624) (xy 29.333444 -22.518624)
			(xy 31.26486 -22.518624) (xy 31.26486 -24.45004) (xy 29.333444 -24.45004) (xy 29.333444 -22.518624)
			(xy 27.748182 -22.518624) (xy 27.825088 -22.520375) (xy 27.912473 -22.530365) (xy 27.998586 -22.54826)
			(xy 28.082716 -22.573911) (xy 28.164164 -22.607106) (xy 28.242257 -22.64757) (xy 28.316346 -22.694968)
			(xy 28.385818 -22.748907) (xy 28.450097 -22.80894) (xy 28.508651 -22.874569) (xy 28.560995 -22.945251)
			(xy 28.606694 -23.0204) (xy 28.64537 -23.099393) (xy 28.676702 -23.181576) (xy 28.700432 -23.266268)
			(xy 28.716362 -23.352767) (xy 28.72436 -23.440355) (xy 28.72486 -23.484332) (xy 28.72436 -23.528309)
			(xy 28.716362 -23.615897) (xy 28.700432 -23.702396) (xy 28.676702 -23.787088) (xy 28.64537 -23.869271)
			(xy 28.606694 -23.948264) (xy 28.560995 -24.023413) (xy 28.508651 -24.094095) (xy 28.450097 -24.159724)
			(xy 28.385818 -24.219757) (xy 28.316346 -24.273696) (xy 28.242257 -24.321094) (xy 28.164164 -24.361558)
			(xy 28.082716 -24.394753) (xy 27.998586 -24.420404) (xy 27.912473 -24.438299) (xy 27.825088 -24.448289)
			(xy 27.737158 -24.450291) (xy 27.64941 -24.444288) (xy 27.562571 -24.430332) (xy 27.477361 -24.408536)
			(xy 27.394486 -24.379083) (xy 27.314633 -24.342215) (xy 27.238463 -24.298238) (xy 27.166608 -24.247517)
			(xy 27.099663 -24.190472) (xy 27.038183 -24.127576) (xy 26.982676 -24.05935) (xy 26.933604 -23.986359)
			(xy 26.891373 -23.909208) (xy 26.856332 -23.828536) (xy 26.828773 -23.745012) (xy 26.808922 -23.659328)
			(xy 26.796946 -23.572194) (xy 26.792943 -23.484332) (xy 23.623074 -23.484332) (xy 23.62327 -23.50008)
			(xy 23.622764 -23.540645) (xy 23.614686 -23.621373) (xy 23.598611 -23.700895) (xy 23.574697 -23.778421)
			(xy 23.543183 -23.853181) (xy 23.504382 -23.924431) (xy 23.45868 -23.991464) (xy 23.40653 -24.053614)
			(xy 23.348451 -24.110262) (xy 23.285021 -24.160847) (xy 23.216869 -24.204864) (xy 23.144673 -24.241876)
			(xy 23.069151 -24.271517) (xy 22.991053 -24.29349) (xy 22.911155 -24.307578) (xy 22.830251 -24.313641)
			(xy 22.749146 -24.311618) (xy 22.668645 -24.30153) (xy 22.589548 -24.283477) (xy 22.512642 -24.257638)
			(xy 22.438691 -24.22427) (xy 22.36843 -24.183705) (xy 22.302557 -24.136345) (xy 22.241727 -24.082662)
			(xy 22.186544 -24.02319) (xy 22.137557 -23.958518) (xy 22.095253 -23.88929) (xy 22.060052 -23.816194)
			(xy 22.032303 -23.739956) (xy 22.012284 -23.661334) (xy 22.000192 -23.58111) (xy 21.996148 -23.50008)
			(xy 21.623274 -23.50008) (xy 21.622768 -23.540645) (xy 21.61469 -23.621373) (xy 21.598615 -23.700895)
			(xy 21.574701 -23.778421) (xy 21.543187 -23.853181) (xy 21.504386 -23.924431) (xy 21.458684 -23.991464)
			(xy 21.406534 -24.053614) (xy 21.348455 -24.110262) (xy 21.285025 -24.160847) (xy 21.216873 -24.204864)
			(xy 21.144677 -24.241876) (xy 21.069155 -24.271517) (xy 20.991057 -24.29349) (xy 20.911159 -24.307578)
			(xy 20.830255 -24.313641) (xy 20.74915 -24.311618) (xy 20.668649 -24.30153) (xy 20.589552 -24.283477)
			(xy 20.512646 -24.257638) (xy 20.438695 -24.22427) (xy 20.368434 -24.183705) (xy 20.302561 -24.136345)
			(xy 20.241731 -24.082662) (xy 20.186548 -24.02319) (xy 20.137561 -23.958518) (xy 20.095257 -23.88929)
			(xy 20.060056 -23.816194) (xy 20.032307 -23.739956) (xy 20.012288 -23.661334) (xy 20.000196 -23.58111)
			(xy 19.996152 -23.50008) (xy 5.81406 -23.50008) (xy 5.81406 -24.384) (xy 5.814603 -24.40065) (xy 5.82322 -24.432817)
			(xy 5.839867 -24.461657) (xy 5.863411 -24.485208) (xy 5.881854 -24.495861) (xy 35.991792 -24.495861)
			(xy 35.991792 -24.424539) (xy 35.999778 -24.353665) (xy 36.015648 -24.28413) (xy 36.039205 -24.21681)
			(xy 36.07015 -24.152551) (xy 36.108096 -24.09216) (xy 36.152565 -24.036398) (xy 36.202998 -23.985965)
			(xy 36.25876 -23.941496) (xy 36.319151 -23.90355) (xy 36.38341 -23.872605) (xy 36.45073 -23.849048)
			(xy 36.520265 -23.833178) (xy 36.591139 -23.825192) (xy 36.662461 -23.825192) (xy 36.733335 -23.833178)
			(xy 36.80287 -23.849048) (xy 36.87019 -23.872605) (xy 36.934449 -23.90355) (xy 36.99484 -23.941496)
			(xy 37.050602 -23.985965) (xy 37.101035 -24.036398) (xy 37.145504 -24.09216) (xy 37.18345 -24.152551)
			(xy 37.214395 -24.21681) (xy 37.237952 -24.28413) (xy 37.253822 -24.353665) (xy 37.261808 -24.424539)
			(xy 37.262308 -24.4602) (xy 37.261808 -24.495861) (xy 43.611792 -24.495861) (xy 43.611792 -24.424539)
			(xy 43.619778 -24.353665) (xy 43.635648 -24.28413) (xy 43.659205 -24.21681) (xy 43.69015 -24.152551)
			(xy 43.728096 -24.09216) (xy 43.772565 -24.036398) (xy 43.822998 -23.985965) (xy 43.87876 -23.941496)
			(xy 43.939151 -23.90355) (xy 44.00341 -23.872605) (xy 44.07073 -23.849048) (xy 44.140265 -23.833178)
			(xy 44.211139 -23.825192) (xy 44.282461 -23.825192) (xy 44.353335 -23.833178) (xy 44.42287 -23.849048)
			(xy 44.49019 -23.872605) (xy 44.554449 -23.90355) (xy 44.61484 -23.941496) (xy 44.670602 -23.985965)
			(xy 44.721035 -24.036398) (xy 44.765504 -24.09216) (xy 44.80345 -24.152551) (xy 44.834395 -24.21681)
			(xy 44.857952 -24.28413) (xy 44.873822 -24.353665) (xy 44.881808 -24.424539) (xy 44.882308 -24.4602)
			(xy 44.881808 -24.495861) (xy 44.873822 -24.566735) (xy 44.857952 -24.63627) (xy 44.834395 -24.70359)
			(xy 44.80345 -24.767849) (xy 44.765504 -24.82824) (xy 44.721035 -24.884002) (xy 44.670602 -24.934435)
			(xy 44.61484 -24.978904) (xy 44.554449 -25.01685) (xy 44.49019 -25.047795) (xy 44.42287 -25.071352)
			(xy 44.353335 -25.087222) (xy 44.282461 -25.095208) (xy 44.211139 -25.095208) (xy 44.140265 -25.087222)
			(xy 44.07073 -25.071352) (xy 44.00341 -25.047795) (xy 43.939151 -25.01685) (xy 43.87876 -24.978904)
			(xy 43.822998 -24.934435) (xy 43.772565 -24.884002) (xy 43.728096 -24.82824) (xy 43.69015 -24.767849)
			(xy 43.659205 -24.70359) (xy 43.635648 -24.63627) (xy 43.619778 -24.566735) (xy 43.611792 -24.495861)
			(xy 37.261808 -24.495861) (xy 37.253822 -24.566735) (xy 37.237952 -24.63627) (xy 37.214395 -24.70359)
			(xy 37.18345 -24.767849) (xy 37.145504 -24.82824) (xy 37.101035 -24.884002) (xy 37.050602 -24.934435)
			(xy 36.99484 -24.978904) (xy 36.934449 -25.01685) (xy 36.87019 -25.047795) (xy 36.80287 -25.071352)
			(xy 36.733335 -25.087222) (xy 36.662461 -25.095208) (xy 36.591139 -25.095208) (xy 36.520265 -25.087222)
			(xy 36.45073 -25.071352) (xy 36.38341 -25.047795) (xy 36.319151 -25.01685) (xy 36.25876 -24.978904)
			(xy 36.202998 -24.934435) (xy 36.152565 -24.884002) (xy 36.108096 -24.82824) (xy 36.07015 -24.767849)
			(xy 36.039205 -24.70359) (xy 36.015648 -24.63627) (xy 35.999778 -24.566735) (xy 35.991792 -24.495861)
			(xy 5.881854 -24.495861) (xy 5.892246 -24.501864) (xy 5.92441 -24.510492) (xy 5.94106 -24.511) (xy 6.7564 -24.511)
			(xy 7.788339 -25.542939) (xy 13.382993 -25.542939) (xy 13.382993 -25.457213) (xy 13.390903 -25.371853)
			(xy 13.406655 -25.287586) (xy 13.430115 -25.205133) (xy 13.461083 -25.125196) (xy 13.499294 -25.048457)
			(xy 13.544423 -24.975571) (xy 13.596084 -24.90716) (xy 13.653838 -24.843808) (xy 13.71719 -24.786054)
			(xy 13.785601 -24.734393) (xy 13.858487 -24.689264) (xy 13.935226 -24.651053) (xy 14.015163 -24.620085)
			(xy 14.097616 -24.596625) (xy 14.181883 -24.580873) (xy 14.267243 -24.572963) (xy 14.352969 -24.572963)
			(xy 14.438329 -24.580873) (xy 14.522596 -24.596625) (xy 14.605049 -24.620085) (xy 14.684986 -24.651053)
			(xy 14.761725 -24.689264) (xy 14.834611 -24.734393) (xy 14.903022 -24.786054) (xy 14.966374 -24.843808)
			(xy 15.024128 -24.90716) (xy 15.075789 -24.975571) (xy 15.120918 -25.048457) (xy 15.159129 -25.125196)
			(xy 15.190097 -25.205133) (xy 15.213557 -25.287586) (xy 15.229309 -25.371853) (xy 15.237219 -25.457213)
			(xy 15.237714 -25.500076) (xy 15.237219 -25.542939) (xy 15.229309 -25.628299) (xy 15.213557 -25.712566)
			(xy 15.190097 -25.795019) (xy 15.159129 -25.874956) (xy 15.120918 -25.951695) (xy 15.075789 -26.024581)
			(xy 15.024128 -26.092992) (xy 14.966374 -26.156344) (xy 14.903022 -26.214098) (xy 14.834611 -26.265759)
			(xy 14.761725 -26.310888) (xy 14.684986 -26.349099) (xy 14.605049 -26.380067) (xy 14.522596 -26.403527)
			(xy 14.438329 -26.419279) (xy 14.352969 -26.427189) (xy 14.267243 -26.427189) (xy 14.181883 -26.419279)
			(xy 14.097616 -26.403527) (xy 14.015163 -26.380067) (xy 13.935226 -26.349099) (xy 13.858487 -26.310888)
			(xy 13.785601 -26.265759) (xy 13.71719 -26.214098) (xy 13.653838 -26.156344) (xy 13.596084 -26.092992)
			(xy 13.544423 -26.024581) (xy 13.499294 -25.951695) (xy 13.461083 -25.874956) (xy 13.430115 -25.795019)
			(xy 13.406655 -25.712566) (xy 13.390903 -25.628299) (xy 13.382993 -25.542939) (xy 7.788339 -25.542939)
			(xy 8.8646 -26.6192) (xy 8.8646 -27.532031) (xy 19.996675 -27.532031) (xy 19.997523 -27.451084) (xy 20.006408 -27.370622)
			(xy 20.023241 -27.29144) (xy 20.047857 -27.214322) (xy 20.080012 -27.14003) (xy 20.119388 -27.069301)
			(xy 20.165596 -27.002833) (xy 20.218177 -26.941283) (xy 20.276613 -26.885262) (xy 20.340325 -26.835322)
			(xy 20.408682 -26.791959) (xy 20.481009 -26.7556) (xy 20.55659 -26.726606) (xy 20.634678 -26.705264)
			(xy 20.714499 -26.691784) (xy 20.754848 -26.688542) (xy 20.771338 -26.686913) (xy 20.802708 -26.676275)
			(xy 20.830281 -26.65792) (xy 20.8522 -26.633085) (xy 20.866986 -26.603444) (xy 20.873642 -26.570995)
			(xy 20.873212 -26.55443) (xy 20.871759 -26.527209) (xy 20.871634 -26.472691) (xy 20.872958 -26.445464)
			(xy 20.873393 -26.428936) (xy 20.866735 -26.396561) (xy 20.851974 -26.366987) (xy 20.830104 -26.342204)
			(xy 20.802596 -26.32388) (xy 20.771301 -26.313247) (xy 20.754848 -26.311606) (xy 20.714505 -26.308352)
			(xy 20.634695 -26.294869) (xy 20.556618 -26.273526) (xy 20.481047 -26.244533) (xy 20.40873 -26.208177)
			(xy 20.340382 -26.164817) (xy 20.276679 -26.114883) (xy 20.21825 -26.058868) (xy 20.165675 -25.997327)
			(xy 20.119472 -25.930868) (xy 20.080099 -25.860148) (xy 20.047946 -25.785867) (xy 20.023329 -25.70876)
			(xy 20.006494 -25.629589) (xy 19.997605 -25.549137) (xy 19.996752 -25.4682) (xy 20.003942 -25.387579)
			(xy 20.019105 -25.30807) (xy 20.042091 -25.230461) (xy 20.072671 -25.155519) (xy 20.110545 -25.083985)
			(xy 20.155336 -25.016566) (xy 20.206603 -24.95393) (xy 20.263837 -24.896696) (xy 20.326474 -24.845431)
			(xy 20.393893 -24.80064) (xy 20.465427 -24.762767) (xy 20.54037 -24.732188) (xy 20.617979 -24.709203)
			(xy 20.697488 -24.694041) (xy 20.778109 -24.686852) (xy 20.859046 -24.687706) (xy 20.939498 -24.696595)
			(xy 21.018669 -24.713432) (xy 21.095776 -24.738049) (xy 21.170057 -24.770203) (xy 21.240776 -24.809577)
			(xy 21.307235 -24.855781) (xy 21.368775 -24.908357) (xy 21.424789 -24.966786) (xy 21.474722 -25.03049)
			(xy 21.518081 -25.098838) (xy 21.554436 -25.171156) (xy 21.583429 -25.246727) (xy 21.604771 -25.324804)
			(xy 21.618253 -25.404614) (xy 21.621496 -25.444958) (xy 21.623181 -25.46144) (xy 21.633814 -25.492801)
			(xy 21.65216 -25.520368) (xy 21.676984 -25.542286) (xy 21.706611 -25.557077) (xy 21.739048 -25.563744)
			(xy 21.755608 -25.563322) (xy 21.782769 -25.561942) (xy 21.837159 -25.561942) (xy 21.86432 -25.563322)
			(xy 21.880888 -25.563731) (xy 21.913342 -25.557095) (xy 21.942991 -25.54232) (xy 21.96783 -25.520403)
			(xy 21.986183 -25.492826) (xy 21.996809 -25.46145) (xy 21.998432 -25.444958) (xy 22.001677 -25.404612)
			(xy 22.015157 -25.324797) (xy 22.036498 -25.246716) (xy 22.06549 -25.171141) (xy 22.101846 -25.098819)
			(xy 22.145205 -25.030466) (xy 22.19514 -24.966758) (xy 22.251156 -24.908325) (xy 22.312699 -24.855745)
			(xy 22.37916 -24.809539) (xy 22.449882 -24.770162) (xy 22.524166 -24.738005) (xy 22.601277 -24.713386)
			(xy 22.680452 -24.696548) (xy 22.760907 -24.687658) (xy 22.841848 -24.686803) (xy 22.922474 -24.693993)
			(xy 23.001987 -24.709155) (xy 23.0796 -24.732141) (xy 23.154546 -24.762722) (xy 23.226084 -24.800597)
			(xy 23.293506 -24.84539) (xy 23.356146 -24.896659) (xy 23.413383 -24.953896) (xy 23.464651 -25.016535)
			(xy 23.509444 -25.083957) (xy 23.547319 -25.155495) (xy 23.5779 -25.230442) (xy 23.600885 -25.308055)
			(xy 23.616048 -25.387568) (xy 23.623237 -25.468193) (xy 23.622382 -25.549134) (xy 23.613492 -25.62959)
			(xy 23.596654 -25.708765) (xy 23.572034 -25.785875) (xy 23.539877 -25.860159) (xy 23.5005 -25.930882)
			(xy 23.454294 -25.997343) (xy 23.401714 -26.058886) (xy 23.343281 -26.114901) (xy 23.279573 -26.164836)
			(xy 23.21122 -26.208195) (xy 23.138898 -26.24455) (xy 23.063322 -26.273542) (xy 22.985241 -26.294884)
			(xy 22.905426 -26.308364) (xy 22.86508 -26.311606) (xy 22.848615 -26.313241) (xy 22.817291 -26.323864)
			(xy 22.78975 -26.34218) (xy 22.76784 -26.366958) (xy 22.753033 -26.396534) (xy 22.75121 -26.405332)
			(xy 26.792943 -26.405332) (xy 26.796946 -26.31747) (xy 26.808922 -26.230336) (xy 26.828773 -26.144652)
			(xy 26.856332 -26.061128) (xy 26.891373 -25.980456) (xy 26.933604 -25.903305) (xy 26.982676 -25.830314)
			(xy 27.038183 -25.762088) (xy 27.099663 -25.699192) (xy 27.166608 -25.642147) (xy 27.238463 -25.591426)
			(xy 27.314633 -25.547449) (xy 27.394486 -25.510581) (xy 27.477361 -25.481128) (xy 27.562571 -25.459332)
			(xy 27.64941 -25.445376) (xy 27.737158 -25.439373) (xy 27.748182 -25.439624) (xy 29.333444 -25.439624)
			(xy 31.26486 -25.439624) (xy 31.26486 -26.883461) (xy 35.686992 -26.883461) (xy 35.686992 -26.812139)
			(xy 35.694978 -26.741265) (xy 35.710848 -26.67173) (xy 35.734405 -26.60441) (xy 35.76535 -26.540151)
			(xy 35.803296 -26.47976) (xy 35.847765 -26.423998) (xy 35.898198 -26.373565) (xy 35.95396 -26.329096)
			(xy 36.014351 -26.29115) (xy 36.07861 -26.260205) (xy 36.14593 -26.236648) (xy 36.215465 -26.220778)
			(xy 36.286339 -26.212792) (xy 36.357661 -26.212792) (xy 36.428535 -26.220778) (xy 36.49807 -26.236648)
			(xy 36.56539 -26.260205) (xy 36.629649 -26.29115) (xy 36.69004 -26.329096) (xy 36.745802 -26.373565)
			(xy 36.796235 -26.423998) (xy 36.840704 -26.47976) (xy 36.87865 -26.540151) (xy 36.909595 -26.60441)
			(xy 36.933152 -26.67173) (xy 36.949022 -26.741265) (xy 36.957008 -26.812139) (xy 36.957508 -26.8478)
			(xy 36.957008 -26.883461) (xy 36.949022 -26.954335) (xy 36.933152 -27.02387) (xy 36.909595 -27.09119)
			(xy 36.87865 -27.155449) (xy 36.840704 -27.21584) (xy 36.796235 -27.271602) (xy 36.745802 -27.322035)
			(xy 36.69004 -27.366504) (xy 36.629649 -27.40445) (xy 36.56539 -27.435395) (xy 36.49807 -27.458952)
			(xy 36.428535 -27.474822) (xy 36.357661 -27.482808) (xy 36.286339 -27.482808) (xy 36.215465 -27.474822)
			(xy 36.14593 -27.458952) (xy 36.07861 -27.435395) (xy 36.014351 -27.40445) (xy 35.95396 -27.366504)
			(xy 35.898198 -27.322035) (xy 35.847765 -27.271602) (xy 35.803296 -27.21584) (xy 35.76535 -27.155449)
			(xy 35.734405 -27.09119) (xy 35.710848 -27.02387) (xy 35.694978 -26.954335) (xy 35.686992 -26.883461)
			(xy 31.26486 -26.883461) (xy 31.26486 -27.37104) (xy 29.333444 -27.37104) (xy 29.333444 -25.439624)
			(xy 27.748182 -25.439624) (xy 27.825088 -25.441375) (xy 27.912473 -25.451365) (xy 27.998586 -25.46926)
			(xy 28.082716 -25.494911) (xy 28.164164 -25.528106) (xy 28.242257 -25.56857) (xy 28.316346 -25.615968)
			(xy 28.385818 -25.669907) (xy 28.450097 -25.72994) (xy 28.508651 -25.795569) (xy 28.560995 -25.866251)
			(xy 28.606694 -25.9414) (xy 28.64537 -26.020393) (xy 28.676702 -26.102576) (xy 28.700432 -26.187268)
			(xy 28.716362 -26.273767) (xy 28.72436 -26.361355) (xy 28.72486 -26.405332) (xy 28.72436 -26.449309)
			(xy 28.716362 -26.536897) (xy 28.700432 -26.623396) (xy 28.676702 -26.708088) (xy 28.64537 -26.790271)
			(xy 28.606694 -26.869264) (xy 28.560995 -26.944413) (xy 28.508651 -27.015095) (xy 28.450097 -27.080724)
			(xy 28.385818 -27.140757) (xy 28.316346 -27.194696) (xy 28.242257 -27.242094) (xy 28.164164 -27.282558)
			(xy 28.082716 -27.315753) (xy 27.998586 -27.341404) (xy 27.912473 -27.359299) (xy 27.825088 -27.369289)
			(xy 27.737158 -27.371291) (xy 27.64941 -27.365288) (xy 27.562571 -27.351332) (xy 27.477361 -27.329536)
			(xy 27.394486 -27.300083) (xy 27.314633 -27.263215) (xy 27.238463 -27.219238) (xy 27.166608 -27.168517)
			(xy 27.099663 -27.111472) (xy 27.038183 -27.048576) (xy 26.982676 -26.98035) (xy 26.933604 -26.907359)
			(xy 26.891373 -26.830208) (xy 26.856332 -26.749536) (xy 26.828773 -26.666012) (xy 26.808922 -26.580328)
			(xy 26.796946 -26.493194) (xy 26.792943 -26.405332) (xy 22.75121 -26.405332) (xy 22.746323 -26.428922)
			(xy 22.746716 -26.445464) (xy 22.74824 -26.500074) (xy 22.746716 -26.55443) (xy 22.746263 -26.570999)
			(xy 22.752903 -26.60346) (xy 22.767686 -26.633112) (xy 22.789612 -26.657953) (xy 22.817199 -26.676303)
			(xy 22.848584 -26.686923) (xy 22.86508 -26.688542) (xy 22.90543 -26.691789) (xy 22.985255 -26.705268)
			(xy 23.063346 -26.726609) (xy 23.138931 -26.755602) (xy 23.211262 -26.79196) (xy 23.279624 -26.835324)
			(xy 23.343339 -26.885265) (xy 23.401778 -26.941287) (xy 23.454363 -27.002838) (xy 23.500573 -27.069309)
			(xy 23.539952 -27.14004) (xy 23.57211 -27.214334) (xy 23.596728 -27.291455) (xy 23.613563 -27.37064)
			(xy 23.622449 -27.451106) (xy 23.623297 -27.532057) (xy 23.616099 -27.612691) (xy 23.600927 -27.692211)
			(xy 23.577931 -27.769831) (xy 23.547338 -27.844783) (xy 23.50945 -27.916325) (xy 23.464643 -27.983749)
			(xy 23.413359 -28.046388) (xy 23.356107 -28.103623) (xy 23.293452 -28.154888) (xy 23.226015 -28.199675)
			(xy 23.154462 -28.237541) (xy 23.079501 -28.268112) (xy 23.001874 -28.291085) (xy 22.922349 -28.306233)
			(xy 22.841713 -28.313406) (xy 22.760762 -28.312534) (xy 22.680299 -28.303624) (xy 22.601119 -28.286765)
			(xy 22.524006 -28.262124) (xy 22.449721 -28.229944) (xy 22.379001 -28.190544) (xy 22.312545 -28.144314)
			(xy 22.25101 -28.09171) (xy 22.195005 -28.033254) (xy 22.145083 -27.969524) (xy 22.10174 -27.90115)
			(xy 22.065403 -27.828808) (xy 22.036433 -27.753214) (xy 22.015115 -27.675117) (xy 22.001661 -27.595288)
			(xy 21.998432 -27.554936) (xy 21.996714 -27.538479) (xy 21.986034 -27.507179) (xy 21.96767 -27.479674)
			(xy 21.942855 -27.457811) (xy 21.913255 -27.443058) (xy 21.880859 -27.436405) (xy 21.86432 -27.436826)
			(xy 21.837159 -27.438206) (xy 21.782769 -27.438206) (xy 21.755608 -27.436826) (xy 21.739059 -27.43638)
			(xy 21.706633 -27.442994) (xy 21.677004 -27.457734) (xy 21.652169 -27.479605) (xy 21.633802 -27.507134)
			(xy 21.623143 -27.538463) (xy 21.621496 -27.554936) (xy 21.618264 -27.595286) (xy 21.604807 -27.675111)
			(xy 21.583488 -27.753204) (xy 21.554516 -27.828794) (xy 21.518178 -27.901132) (xy 21.474834 -27.969502)
			(xy 21.424913 -28.033228) (xy 21.368909 -28.09168) (xy 21.307375 -28.144279) (xy 21.24092 -28.190506)
			(xy 21.170202 -28.229903) (xy 21.09592 -28.262079) (xy 21.018809 -28.286718) (xy 20.939632 -28.303575)
			(xy 20.859172 -28.312483) (xy 20.778226 -28.313354) (xy 20.697593 -28.30618) (xy 20.618071 -28.291031)
			(xy 20.540448 -28.268058) (xy 20.465491 -28.237488) (xy 20.393941 -28.199623) (xy 20.326506 -28.154837)
			(xy 20.263855 -28.103574) (xy 20.206605 -28.046341) (xy 20.155324 -27.983704) (xy 20.110519 -27.916283)
			(xy 20.072632 -27.844744) (xy 20.04204 -27.769796) (xy 20.019045 -27.692179) (xy 20.003873 -27.612662)
			(xy 19.996675 -27.532031) (xy 8.8646 -27.532031) (xy 8.8646 -28.542933) (xy 13.382993 -28.542933)
			(xy 13.382993 -28.457207) (xy 13.390903 -28.371847) (xy 13.406655 -28.28758) (xy 13.430115 -28.205127)
			(xy 13.461083 -28.12519) (xy 13.499294 -28.048451) (xy 13.544423 -27.975565) (xy 13.596084 -27.907154)
			(xy 13.653838 -27.843802) (xy 13.71719 -27.786048) (xy 13.785601 -27.734387) (xy 13.858487 -27.689258)
			(xy 13.935226 -27.651047) (xy 14.015163 -27.620079) (xy 14.097616 -27.596619) (xy 14.181883 -27.580867)
			(xy 14.267243 -27.572957) (xy 14.352969 -27.572957) (xy 14.438329 -27.580867) (xy 14.522596 -27.596619)
			(xy 14.605049 -27.620079) (xy 14.684986 -27.651047) (xy 14.761725 -27.689258) (xy 14.834611 -27.734387)
			(xy 14.903022 -27.786048) (xy 14.966374 -27.843802) (xy 15.024128 -27.907154) (xy 15.075789 -27.975565)
			(xy 15.120918 -28.048451) (xy 15.159129 -28.12519) (xy 15.190097 -28.205127) (xy 15.213557 -28.28758)
			(xy 15.229309 -28.371847) (xy 15.237219 -28.457207) (xy 15.237714 -28.50007) (xy 15.237219 -28.542933)
			(xy 15.229309 -28.628293) (xy 15.213557 -28.71256) (xy 15.190097 -28.795013) (xy 15.159129 -28.87495)
			(xy 15.120918 -28.951689) (xy 15.075789 -29.024575) (xy 15.024128 -29.092986) (xy 14.966374 -29.156338)
			(xy 14.903022 -29.214092) (xy 14.834611 -29.265753) (xy 14.761725 -29.310882) (xy 14.684986 -29.349093)
			(xy 14.605049 -29.380061) (xy 14.522596 -29.403521) (xy 14.438329 -29.419273) (xy 14.352969 -29.427183)
			(xy 14.267243 -29.427183) (xy 14.181883 -29.419273) (xy 14.097616 -29.403521) (xy 14.015163 -29.380061)
			(xy 13.935226 -29.349093) (xy 13.858487 -29.310882) (xy 13.785601 -29.265753) (xy 13.71719 -29.214092)
			(xy 13.653838 -29.156338) (xy 13.596084 -29.092986) (xy 13.544423 -29.024575) (xy 13.499294 -28.951689)
			(xy 13.461083 -28.87495) (xy 13.430115 -28.795013) (xy 13.406655 -28.71256) (xy 13.390903 -28.628293)
			(xy 13.382993 -28.542933) (xy 8.8646 -28.542933) (xy 8.8646 -31.542927) (xy 13.382993 -31.542927)
			(xy 13.382993 -31.457201) (xy 13.390903 -31.371841) (xy 13.406655 -31.287574) (xy 13.430115 -31.205121)
			(xy 13.461083 -31.125184) (xy 13.499294 -31.048445) (xy 13.544423 -30.975559) (xy 13.596084 -30.907148)
			(xy 13.653838 -30.843796) (xy 13.71719 -30.786042) (xy 13.785601 -30.734381) (xy 13.858487 -30.689252)
			(xy 13.935226 -30.651041) (xy 14.015163 -30.620073) (xy 14.097616 -30.596613) (xy 14.181883 -30.580861)
			(xy 14.267243 -30.572951) (xy 14.352969 -30.572951) (xy 14.438329 -30.580861) (xy 14.522596 -30.596613)
			(xy 14.605049 -30.620073) (xy 14.684986 -30.651041) (xy 14.761725 -30.689252) (xy 14.834611 -30.734381)
			(xy 14.903022 -30.786042) (xy 14.966374 -30.843796) (xy 15.024128 -30.907148) (xy 15.075789 -30.975559)
			(xy 15.120918 -31.048445) (xy 15.159129 -31.125184) (xy 15.190097 -31.205121) (xy 15.213557 -31.287574)
			(xy 15.229309 -31.371841) (xy 15.237219 -31.457201) (xy 15.237714 -31.500064) (xy 15.237219 -31.542927)
			(xy 15.229309 -31.628287) (xy 15.213557 -31.712554) (xy 15.190097 -31.795007) (xy 15.159129 -31.874944)
			(xy 15.120918 -31.951683) (xy 15.075789 -32.024569) (xy 15.024128 -32.09298) (xy 14.966374 -32.156332)
			(xy 14.903022 -32.214086) (xy 14.834611 -32.265747) (xy 14.761725 -32.310876) (xy 14.684986 -32.349087)
			(xy 14.605049 -32.380055) (xy 14.522596 -32.403515) (xy 14.438329 -32.419267) (xy 14.352969 -32.427177)
			(xy 14.267243 -32.427177) (xy 14.181883 -32.419267) (xy 14.097616 -32.403515) (xy 14.015163 -32.380055)
			(xy 13.935226 -32.349087) (xy 13.858487 -32.310876) (xy 13.785601 -32.265747) (xy 13.71719 -32.214086)
			(xy 13.653838 -32.156332) (xy 13.596084 -32.09298) (xy 13.544423 -32.024569) (xy 13.499294 -31.951683)
			(xy 13.461083 -31.874944) (xy 13.430115 -31.795007) (xy 13.406655 -31.712554) (xy 13.390903 -31.628287)
			(xy 13.382993 -31.542927) (xy 8.8646 -31.542927) (xy 8.8646 -33.0708) (xy 9.8806 -34.0868) (xy 10.437876 -34.0868)
			(xy 10.496296 -34.05378) (xy 10.513568 -34.024824) (xy 10.53631 -33.987674) (xy 10.58776 -33.917381)
			(xy 10.645573 -33.85222) (xy 10.709241 -33.792767) (xy 10.778202 -33.739546) (xy 10.85185 -33.693025)
			(xy 10.929536 -33.653614) (xy 11.010574 -33.62166) (xy 11.094251 -33.597445) (xy 11.17983 -33.581182)
			(xy 11.266557 -33.573015) (xy 11.353667 -33.573015) (xy 11.440394 -33.581182) (xy 11.525973 -33.597445)
			(xy 11.60965 -33.62166) (xy 11.690688 -33.653614) (xy 11.768374 -33.693025) (xy 11.842022 -33.739546)
			(xy 11.910983 -33.792767) (xy 11.974651 -33.85222) (xy 12.032464 -33.917381) (xy 12.083914 -33.987674)
			(xy 12.106656 -34.024824) (xy 12.123928 -34.05378) (xy 12.182348 -34.0868) (xy 13.255752 -34.0868)
			(xy 13.272411 -34.086311) (xy 13.304596 -34.077698) (xy 13.333454 -34.061047) (xy 13.357017 -34.037492)
			(xy 13.37368 -34.00864) (xy 13.382305 -33.976459) (xy 13.382752 -33.9598) (xy 13.382752 -33.572704)
			(xy 15.23746 -33.572704) (xy 15.23746 -33.9598) (xy 15.238003 -33.97645) (xy 15.24662 -34.008617)
			(xy 15.263267 -34.037457) (xy 15.286811 -34.061008) (xy 15.315646 -34.077664) (xy 15.34781 -34.086292)
			(xy 15.36446 -34.0868) (xy 16.9926 -34.0868) (xy 17.05229 -34.074862) (xy 22.143466 -28.983432) (xy 26.05786 -28.983432)
			(xy 26.087435 -28.983973) (xy 26.145936 -28.99271) (xy 26.202507 -29.009985) (xy 26.255909 -29.035419)
			(xy 26.304974 -29.068455) (xy 26.348626 -29.108369) (xy 26.38591 -29.154289) (xy 26.416009 -29.205207)
			(xy 26.438265 -29.26001) (xy 26.45219 -29.317498) (xy 26.45537 -29.346906) (xy 26.458017 -29.370274)
			(xy 26.470836 -29.415517) (xy 26.491757 -29.45763) (xy 26.520068 -29.495176) (xy 26.554802 -29.526875)
			(xy 26.594773 -29.551644) (xy 26.638619 -29.568638) (xy 26.684842 -29.577278) (xy 26.708354 -29.577792)
			(xy 27.467306 -29.577792) (xy 28.358846 -28.686252) (xy 32.6644 -28.686252) (xy 32.691503 -28.686706)
			(xy 32.74521 -28.694042) (xy 32.797431 -28.708578) (xy 32.847204 -28.730049) (xy 32.870648 -28.743656)
			(xy 32.890054 -28.754795) (xy 32.931831 -28.770813) (xy 32.975767 -28.779268) (xy 33.020505 -28.779897)
			(xy 33.064662 -28.772681) (xy 33.106872 -28.757844) (xy 33.145832 -28.735843) (xy 33.180337 -28.70736)
			(xy 33.20932 -28.673274) (xy 33.231886 -28.634639) (xy 33.247337 -28.59265) (xy 33.255195 -28.548603)
			(xy 33.255712 -28.526232) (xy 33.255712 -27.9654) (xy 33.256221 -27.936879) (xy 33.264339 -27.880417)
			(xy 33.280409 -27.825685) (xy 33.304106 -27.773797) (xy 33.334945 -27.72581) (xy 33.3723 -27.6827)
			(xy 33.41541 -27.645345) (xy 33.463397 -27.614506) (xy 33.515285 -27.590809) (xy 33.570017 -27.574739)
			(xy 33.626479 -27.566621) (xy 33.683521 -27.566621) (xy 33.739983 -27.574739) (xy 33.794715 -27.590809)
			(xy 33.846603 -27.614506) (xy 33.89459 -27.645345) (xy 33.9377 -27.6827) (xy 33.975055 -27.72581)
			(xy 34.005894 -27.773797) (xy 34.029591 -27.825685) (xy 34.045661 -27.880417) (xy 34.053779 -27.936879)
			(xy 34.054288 -27.9654) (xy 34.054288 -29.25953) (xy 32.99333 -30.320488) (xy 29.964126 -30.320488)
			(xy 29.942511 -30.320921) (xy 29.899905 -30.328236) (xy 29.859152 -30.342659) (xy 29.82143 -30.363775)
			(xy 29.787827 -30.390972) (xy 29.759315 -30.423466) (xy 29.736716 -30.460319) (xy 29.720684 -30.500466)
			(xy 29.71168 -30.542748) (xy 29.71038 -30.564328) (xy 29.708654 -30.594066) (xy 29.697484 -30.652576)
			(xy 29.677738 -30.708774) (xy 29.649858 -30.761413) (xy 29.614461 -30.809321) (xy 29.593794 -30.830774)
			(xy 28.859734 -31.565088) (xy 27.928824 -31.565088) (xy 27.904868 -31.565638) (xy 27.857803 -31.57461)
			(xy 27.813252 -31.592242) (xy 27.80881 -31.59506) (xy 30.047182 -31.59506) (xy 30.051253 -31.539438)
			(xy 30.063379 -31.485001) (xy 30.083302 -31.43291) (xy 30.110598 -31.384275) (xy 30.144684 -31.340132)
			(xy 30.184833 -31.301423) (xy 30.230191 -31.268972) (xy 30.279791 -31.243471) (xy 30.332575 -31.225464)
			(xy 30.387418 -31.215334) (xy 30.443152 -31.213297) (xy 30.498589 -31.219397) (xy 30.552546 -31.233503)
			(xy 30.603875 -31.255315) (xy 30.651481 -31.284369) (xy 30.694349 -31.320044) (xy 30.731566 -31.361581)
			(xy 30.762339 -31.408094) (xy 30.786011 -31.458591) (xy 30.802079 -31.511998) (xy 30.810199 -31.567174)
			(xy 30.810708 -31.59506) (xy 30.810199 -31.622946) (xy 30.802079 -31.678122) (xy 30.786011 -31.731529)
			(xy 30.762339 -31.782026) (xy 30.731566 -31.828539) (xy 30.694349 -31.870076) (xy 30.651481 -31.905751)
			(xy 30.603875 -31.934805) (xy 30.552546 -31.956617) (xy 30.498589 -31.970723) (xy 30.443152 -31.976823)
			(xy 30.387418 -31.974786) (xy 30.332575 -31.964656) (xy 30.279791 -31.946649) (xy 30.230191 -31.921148)
			(xy 30.184833 -31.888697) (xy 30.144684 -31.849988) (xy 30.110598 -31.805845) (xy 30.083302 -31.75721)
			(xy 30.063379 -31.705119) (xy 30.051253 -31.650682) (xy 30.047182 -31.59506) (xy 27.80881 -31.59506)
			(xy 27.772794 -31.617909) (xy 27.737862 -31.650701) (xy 27.709691 -31.689457) (xy 27.689282 -31.732805)
			(xy 27.677355 -31.77921) (xy 27.675332 -31.803086) (xy 27.673174 -31.830376) (xy 27.662323 -31.884031)
			(xy 27.644239 -31.9357) (xy 27.619261 -31.984411) (xy 27.587858 -32.02925) (xy 27.550621 -32.069376)
			(xy 27.508247 -32.104034) (xy 27.505684 -32.1056) (xy 31.367982 -32.1056) (xy 31.372053 -32.049978)
			(xy 31.384179 -31.995541) (xy 31.404102 -31.94345) (xy 31.431398 -31.894815) (xy 31.465484 -31.850672)
			(xy 31.505633 -31.811963) (xy 31.550991 -31.779512) (xy 31.600591 -31.754011) (xy 31.653375 -31.736004)
			(xy 31.708218 -31.725874) (xy 31.763952 -31.723837) (xy 31.819389 -31.729937) (xy 31.873346 -31.744043)
			(xy 31.924675 -31.765855) (xy 31.972281 -31.794909) (xy 32.015149 -31.830584) (xy 32.052366 -31.872121)
			(xy 32.083139 -31.918634) (xy 32.106811 -31.969131) (xy 32.122879 -32.022538) (xy 32.130999 -32.077714)
			(xy 32.131508 -32.1056) (xy 32.130999 -32.133486) (xy 32.122879 -32.188662) (xy 32.106811 -32.242069)
			(xy 32.083139 -32.292566) (xy 32.052366 -32.339079) (xy 32.015149 -32.380616) (xy 31.972281 -32.416291)
			(xy 31.924675 -32.445345) (xy 31.873346 -32.467157) (xy 31.819389 -32.481263) (xy 31.763952 -32.487363)
			(xy 31.708218 -32.485326) (xy 31.653375 -32.475196) (xy 31.600591 -32.457189) (xy 31.550991 -32.431688)
			(xy 31.505633 -32.399237) (xy 31.465484 -32.360528) (xy 31.431398 -32.316385) (xy 31.404102 -32.26775)
			(xy 31.384179 -32.215659) (xy 31.372053 -32.161222) (xy 31.367982 -32.1056) (xy 27.505684 -32.1056)
			(xy 27.461534 -32.132574) (xy 27.411357 -32.15446) (xy 27.35866 -32.169282) (xy 27.304431 -32.17676)
			(xy 27.27706 -32.177228) (xy 25.822402 -32.177228) (xy 25.798748 -32.177716) (xy 25.752245 -32.186403)
			(xy 25.708156 -32.203551) (xy 25.668005 -32.228567) (xy 25.633181 -32.260586) (xy 25.604888 -32.298501)
			(xy 25.584107 -32.340998) (xy 25.571554 -32.386609) (xy 25.569164 -32.410146) (xy 25.566518 -32.437046)
			(xy 25.55489 -32.489834) (xy 25.53624 -32.540568) (xy 25.510913 -32.588319) (xy 25.47937 -32.632214)
			(xy 25.44219 -32.671449) (xy 25.400053 -32.705305) (xy 25.353731 -32.733162) (xy 25.304073 -32.75451)
			(xy 25.251987 -32.768959) (xy 25.198427 -32.776243) (xy 25.1714 -32.776668) (xy 23.683468 -32.776668)
			(xy 23.465536 -32.9946) (xy 27.938982 -32.9946) (xy 27.943053 -32.938978) (xy 27.955179 -32.884541)
			(xy 27.975102 -32.83245) (xy 28.002398 -32.783815) (xy 28.036484 -32.739672) (xy 28.076633 -32.700963)
			(xy 28.121991 -32.668512) (xy 28.171591 -32.643011) (xy 28.224375 -32.625004) (xy 28.279218 -32.614874)
			(xy 28.334952 -32.612837) (xy 28.390389 -32.618937) (xy 28.444346 -32.633043) (xy 28.495675 -32.654855)
			(xy 28.543281 -32.683909) (xy 28.586149 -32.719584) (xy 28.623366 -32.761121) (xy 28.654139 -32.807634)
			(xy 28.677811 -32.858131) (xy 28.693879 -32.911538) (xy 28.701999 -32.966714) (xy 28.702508 -32.9946)
			(xy 28.701999 -33.022486) (xy 28.693879 -33.077662) (xy 28.677811 -33.131069) (xy 28.654139 -33.181566)
			(xy 28.623366 -33.228079) (xy 28.586149 -33.269616) (xy 28.543281 -33.305291) (xy 28.495675 -33.334345)
			(xy 28.444346 -33.356157) (xy 28.390389 -33.370263) (xy 28.334952 -33.376363) (xy 28.279218 -33.374326)
			(xy 28.224375 -33.364196) (xy 28.171591 -33.346189) (xy 28.121991 -33.320688) (xy 28.076633 -33.288237)
			(xy 28.036484 -33.249528) (xy 28.002398 -33.205385) (xy 27.975102 -33.15675) (xy 27.955179 -33.104659)
			(xy 27.943053 -33.050222) (xy 27.938982 -32.9946) (xy 23.465536 -32.9946) (xy 22.830536 -33.6296)
			(xy 30.021782 -33.6296) (xy 30.025853 -33.573978) (xy 30.037979 -33.519541) (xy 30.057902 -33.46745)
			(xy 30.085198 -33.418815) (xy 30.119284 -33.374672) (xy 30.159433 -33.335963) (xy 30.204791 -33.303512)
			(xy 30.254391 -33.278011) (xy 30.307175 -33.260004) (xy 30.362018 -33.249874) (xy 30.417752 -33.247837)
			(xy 30.473189 -33.253937) (xy 30.527146 -33.268043) (xy 30.578475 -33.289855) (xy 30.626081 -33.318909)
			(xy 30.668949 -33.354584) (xy 30.706166 -33.396121) (xy 30.736939 -33.442634) (xy 30.760611 -33.493131)
			(xy 30.776679 -33.546538) (xy 30.784799 -33.601714) (xy 30.785308 -33.6296) (xy 30.784799 -33.657486)
			(xy 30.776679 -33.712662) (xy 30.760611 -33.766069) (xy 30.736939 -33.816566) (xy 30.706166 -33.863079)
			(xy 30.668949 -33.904616) (xy 30.626081 -33.940291) (xy 30.578475 -33.969345) (xy 30.527146 -33.991157)
			(xy 30.473189 -34.005263) (xy 30.417752 -34.011363) (xy 30.362018 -34.009326) (xy 30.307175 -33.999196)
			(xy 30.254391 -33.981189) (xy 30.204791 -33.955688) (xy 30.159433 -33.923237) (xy 30.119284 -33.884528)
			(xy 30.085198 -33.840385) (xy 30.057902 -33.79175) (xy 30.037979 -33.739659) (xy 30.025853 -33.685222)
			(xy 30.021782 -33.6296) (xy 22.830536 -33.6296) (xy 22.195536 -34.2646) (xy 28.650182 -34.2646) (xy 28.654253 -34.208978)
			(xy 28.666379 -34.154541) (xy 28.686302 -34.10245) (xy 28.713598 -34.053815) (xy 28.747684 -34.009672)
			(xy 28.787833 -33.970963) (xy 28.833191 -33.938512) (xy 28.882791 -33.913011) (xy 28.935575 -33.895004)
			(xy 28.990418 -33.884874) (xy 29.046152 -33.882837) (xy 29.101589 -33.888937) (xy 29.155546 -33.903043)
			(xy 29.206875 -33.924855) (xy 29.254481 -33.953909) (xy 29.297349 -33.989584) (xy 29.334566 -34.031121)
			(xy 29.365339 -34.077634) (xy 29.389011 -34.128131) (xy 29.405079 -34.181538) (xy 29.413199 -34.236714)
			(xy 29.413708 -34.2646) (xy 29.413199 -34.292486) (xy 29.405079 -34.347662) (xy 29.389011 -34.401069)
			(xy 29.365339 -34.451566) (xy 29.334566 -34.498079) (xy 29.297349 -34.539616) (xy 29.254481 -34.575291)
			(xy 29.206875 -34.604345) (xy 29.155546 -34.626157) (xy 29.101589 -34.640263) (xy 29.046152 -34.646363)
			(xy 28.990418 -34.644326) (xy 28.935575 -34.634196) (xy 28.882791 -34.616189) (xy 28.833191 -34.590688)
			(xy 28.787833 -34.558237) (xy 28.747684 -34.519528) (xy 28.713598 -34.475385) (xy 28.686302 -34.42675)
			(xy 28.666379 -34.374659) (xy 28.654253 -34.320222) (xy 28.650182 -34.2646) (xy 22.195536 -34.2646)
			(xy 21.585936 -34.8742) (xy 27.278582 -34.8742) (xy 27.282653 -34.818578) (xy 27.294779 -34.764141)
			(xy 27.314702 -34.71205) (xy 27.341998 -34.663415) (xy 27.376084 -34.619272) (xy 27.416233 -34.580563)
			(xy 27.461591 -34.548112) (xy 27.511191 -34.522611) (xy 27.563975 -34.504604) (xy 27.618818 -34.494474)
			(xy 27.674552 -34.492437) (xy 27.729989 -34.498537) (xy 27.783946 -34.512643) (xy 27.835275 -34.534455)
			(xy 27.882881 -34.563509) (xy 27.925749 -34.599184) (xy 27.962966 -34.640721) (xy 27.993739 -34.687234)
			(xy 28.017411 -34.737731) (xy 28.033479 -34.791138) (xy 28.041599 -34.846314) (xy 28.042108 -34.8742)
			(xy 28.041599 -34.902086) (xy 28.033479 -34.957262) (xy 28.017411 -35.010669) (xy 27.993739 -35.061166)
			(xy 27.962966 -35.107679) (xy 27.925749 -35.149216) (xy 27.882881 -35.184891) (xy 27.835275 -35.213945)
			(xy 27.783946 -35.235757) (xy 27.729989 -35.249863) (xy 27.674552 -35.255963) (xy 27.618818 -35.253926)
			(xy 27.563975 -35.243796) (xy 27.511191 -35.225789) (xy 27.461591 -35.200288) (xy 27.416233 -35.167837)
			(xy 27.376084 -35.129128) (xy 27.341998 -35.084985) (xy 27.314702 -35.03635) (xy 27.294779 -34.984259)
			(xy 27.282653 -34.929822) (xy 27.278582 -34.8742) (xy 21.585936 -34.8742) (xy 17.247108 -39.213028)
			(xy 14.655546 -39.213028) (xy 12.316206 -41.552368) (xy 12.065 -41.552368) (xy 12.04835 -41.552911)
			(xy 12.016185 -41.561528) (xy 11.987345 -41.578176) (xy 11.963795 -41.601719) (xy 11.947141 -41.630555)
			(xy 11.938515 -41.662718) (xy 11.938 -41.679368) (xy 11.938 -51.054) (xy 12.6238 -51.7398)
		)
		(stroke
			(width 0)
			(type solid)
		)
		(fill yes)
		(layer "F.Cu")
		(net "P12V")
	)
	(gr_poly
		(pts
			(xy 297.101514 -50.3174) (xy 297.124564 -50.316906) (xy 297.16991 -50.308603) (xy 297.213014 -50.292255)
			(xy 297.25246 -50.268397) (xy 297.286955 -50.237814) (xy 297.315365 -50.201509) (xy 297.336758 -50.160673)
			(xy 297.350431 -50.116648) (xy 297.355937 -50.070878) (xy 297.353094 -50.024865) (xy 297.341995 -49.980122)
			(xy 297.323005 -49.938115) (xy 297.310302 -49.918874) (xy 297.258458 -49.843003) (xy 297.160587 -49.687448)
			(xy 297.069524 -49.527813) (xy 296.985441 -49.364393) (xy 296.908493 -49.197495) (xy 296.838825 -49.02743)
			(xy 296.776566 -48.854514) (xy 296.721832 -48.679071) (xy 296.674727 -48.501428) (xy 296.635337 -48.321917)
			(xy 296.603736 -48.140872) (xy 296.579984 -47.958631) (xy 296.564124 -47.775534) (xy 296.556185 -47.591923)
			(xy 296.555668 -47.500032) (xy 296.555668 -41.500044) (xy 296.556174 -41.407222) (xy 296.564272 -41.221753)
			(xy 296.580452 -41.036815) (xy 296.604683 -40.852758) (xy 296.63692 -40.669933) (xy 296.677101 -40.488689)
			(xy 296.72515 -40.30937) (xy 296.780974 -40.132317) (xy 296.844468 -39.957868) (xy 296.915512 -39.786354)
			(xy 296.993969 -39.618103) (xy 297.07969 -39.453434) (xy 297.172512 -39.29266) (xy 297.272259 -39.136089)
			(xy 297.378741 -38.984018) (xy 297.491754 -38.836736) (xy 297.611085 -38.694523) (xy 297.736505 -38.557651)
			(xy 297.867775 -38.426381) (xy 298.004647 -38.300961) (xy 298.14686 -38.18163) (xy 298.294142 -38.068617)
			(xy 298.446213 -37.962135) (xy 298.602784 -37.862388) (xy 298.763558 -37.769566) (xy 298.928227 -37.683845)
			(xy 299.096478 -37.605388) (xy 299.267992 -37.534344) (xy 299.442441 -37.47085) (xy 299.619494 -37.415026)
			(xy 299.798813 -37.366977) (xy 299.980057 -37.326796) (xy 300.162882 -37.294559) (xy 300.346939 -37.270328)
			(xy 300.531877 -37.254148) (xy 300.717346 -37.24605) (xy 300.90299 -37.24605) (xy 301.088459 -37.254148)
			(xy 301.273397 -37.270328) (xy 301.457454 -37.294559) (xy 301.640279 -37.326796) (xy 301.821523 -37.366977)
			(xy 302.000842 -37.415026) (xy 302.177895 -37.47085) (xy 302.352344 -37.534344) (xy 302.523858 -37.605388)
			(xy 302.692109 -37.683845) (xy 302.856778 -37.769566) (xy 303.017552 -37.862388) (xy 303.174123 -37.962135)
			(xy 303.326194 -38.068617) (xy 303.473476 -38.18163) (xy 303.615689 -38.300961) (xy 303.752561 -38.426381)
			(xy 303.883831 -38.557651) (xy 304.009251 -38.694523) (xy 304.128582 -38.836736) (xy 304.241595 -38.984018)
			(xy 304.348077 -39.136089) (xy 304.447824 -39.29266) (xy 304.540646 -39.453434) (xy 304.626367 -39.618103)
			(xy 304.704824 -39.786354) (xy 304.775868 -39.957868) (xy 304.839362 -40.132317) (xy 304.895186 -40.30937)
			(xy 304.943235 -40.488689) (xy 304.983416 -40.669933) (xy 305.015653 -40.852758) (xy 305.039884 -41.036815)
			(xy 305.056064 -41.221753) (xy 305.064162 -41.407222) (xy 305.064668 -41.500044) (xy 305.064668 -47.500032)
			(xy 305.064168 -47.591923) (xy 305.056219 -47.775533) (xy 305.040349 -47.958628) (xy 305.016588 -48.140867)
			(xy 304.984981 -48.321911) (xy 304.945587 -48.50142) (xy 304.898478 -48.679062) (xy 304.843744 -48.854504)
			(xy 304.781485 -49.027419) (xy 304.711819 -49.197484) (xy 304.634874 -49.364383) (xy 304.550796 -49.527805)
			(xy 304.459739 -49.687443) (xy 304.361875 -49.843001) (xy 304.310034 -49.918874) (xy 304.297334 -49.938109)
			(xy 304.278373 -49.980117) (xy 304.267298 -50.024855) (xy 304.264472 -50.070857) (xy 304.269987 -50.116614)
			(xy 304.283663 -50.160627) (xy 304.305052 -50.201452) (xy 304.333452 -50.237751) (xy 304.367932 -50.268334)
			(xy 304.407361 -50.292198) (xy 304.450447 -50.30856) (xy 304.495778 -50.316885) (xy 304.518822 -50.3174)
			(xy 313.3344 -50.3174) (xy 316.4713 -47.1805) (xy 316.4713 -41.3258) (xy 315.7347 -40.5892) (xy 309.6514 -40.5892)
			(xy 305.3461 -36.2839) (xy 305.3461 -32.0421) (xy 306.5272 -30.861) (xy 306.5272 -24.3586) (xy 307.848 -23.0378)
			(xy 314.7314 -23.0378) (xy 316.992 -20.7772) (xy 316.992 -3.8354) (xy 314.9346 -1.778) (xy 305.8414 -1.778)
			(xy 305.1556 -2.4638) (xy 305.1556 -2.99974) (xy 305.607723 -2.99974) (xy 305.611758 -2.924036) (xy 305.623817 -2.849191)
			(xy 305.643763 -2.77605) (xy 305.67137 -2.705445) (xy 305.706326 -2.638174) (xy 305.748234 -2.574999)
			(xy 305.79662 -2.516637) (xy 305.850936 -2.463749) (xy 305.910565 -2.416934) (xy 305.974833 -2.376722)
			(xy 306.04301 -2.34357) (xy 306.114326 -2.317852) (xy 306.187971 -2.29986) (xy 306.263111 -2.289798)
			(xy 306.338895 -2.287779) (xy 306.414465 -2.293828) (xy 306.488963 -2.307875) (xy 306.561546 -2.329761)
			(xy 306.631392 -2.359238) (xy 306.697709 -2.395973) (xy 306.759745 -2.439548) (xy 306.816798 -2.48947)
			(xy 306.868222 -2.545174) (xy 306.913433 -2.606029) (xy 306.95192 -2.671344) (xy 306.983246 -2.74038)
			(xy 307.007056 -2.812355) (xy 307.023081 -2.886453) (xy 307.03114 -2.961834) (xy 307.031644 -2.99974)
			(xy 307.607719 -2.99974) (xy 307.611754 -2.924036) (xy 307.623813 -2.849191) (xy 307.643759 -2.77605)
			(xy 307.671366 -2.705445) (xy 307.706322 -2.638174) (xy 307.74823 -2.574999) (xy 307.796616 -2.516637)
			(xy 307.850932 -2.463749) (xy 307.910561 -2.416934) (xy 307.974829 -2.376722) (xy 308.043006 -2.34357)
			(xy 308.114322 -2.317852) (xy 308.187967 -2.29986) (xy 308.263107 -2.289798) (xy 308.338891 -2.287779)
			(xy 308.414461 -2.293828) (xy 308.488959 -2.307875) (xy 308.561542 -2.329761) (xy 308.631388 -2.359238)
			(xy 308.697705 -2.395973) (xy 308.759741 -2.439548) (xy 308.816794 -2.48947) (xy 308.868218 -2.545174)
			(xy 308.913429 -2.606029) (xy 308.951916 -2.671344) (xy 308.983242 -2.74038) (xy 309.007052 -2.812355)
			(xy 309.023077 -2.886453) (xy 309.031136 -2.961834) (xy 309.03164 -2.99974) (xy 309.031136 -3.037646)
			(xy 309.023077 -3.113027) (xy 309.007052 -3.187125) (xy 308.983242 -3.2591) (xy 308.951916 -3.328136)
			(xy 308.913429 -3.393451) (xy 308.868218 -3.454306) (xy 308.816794 -3.51001) (xy 308.759741 -3.559932)
			(xy 308.697705 -3.603507) (xy 308.631388 -3.640242) (xy 308.561542 -3.669719) (xy 308.488959 -3.691605)
			(xy 308.414461 -3.705652) (xy 308.338891 -3.711701) (xy 308.263107 -3.709682) (xy 308.187967 -3.69962)
			(xy 308.114322 -3.681628) (xy 308.043006 -3.65591) (xy 307.974829 -3.622758) (xy 307.910561 -3.582546)
			(xy 307.850932 -3.535731) (xy 307.796616 -3.482843) (xy 307.74823 -3.424481) (xy 307.706322 -3.361306)
			(xy 307.671366 -3.294035) (xy 307.643759 -3.22343) (xy 307.623813 -3.150289) (xy 307.611754 -3.075444)
			(xy 307.607719 -2.99974) (xy 307.031644 -2.99974) (xy 307.03114 -3.037646) (xy 307.023081 -3.113027)
			(xy 307.007056 -3.187125) (xy 306.983246 -3.2591) (xy 306.95192 -3.328136) (xy 306.913433 -3.393451)
			(xy 306.868222 -3.454306) (xy 306.816798 -3.51001) (xy 306.759745 -3.559932) (xy 306.697709 -3.603507)
			(xy 306.631392 -3.640242) (xy 306.561546 -3.669719) (xy 306.488963 -3.691605) (xy 306.414465 -3.705652)
			(xy 306.338895 -3.711701) (xy 306.263111 -3.709682) (xy 306.187971 -3.69962) (xy 306.114326 -3.681628)
			(xy 306.04301 -3.65591) (xy 305.974833 -3.622758) (xy 305.910565 -3.582546) (xy 305.850936 -3.535731)
			(xy 305.79662 -3.482843) (xy 305.748234 -3.424481) (xy 305.706326 -3.361306) (xy 305.67137 -3.294035)
			(xy 305.643763 -3.22343) (xy 305.623817 -3.150289) (xy 305.611758 -3.075444) (xy 305.607723 -2.99974)
			(xy 305.1556 -2.99974) (xy 305.1556 -4.999736) (xy 305.607723 -4.999736) (xy 305.611758 -4.924032)
			(xy 305.623817 -4.849187) (xy 305.643763 -4.776046) (xy 305.67137 -4.705441) (xy 305.706326 -4.63817)
			(xy 305.748234 -4.574995) (xy 305.79662 -4.516633) (xy 305.850936 -4.463745) (xy 305.910565 -4.41693)
			(xy 305.974833 -4.376718) (xy 306.04301 -4.343566) (xy 306.114326 -4.317848) (xy 306.187971 -4.299856)
			(xy 306.263111 -4.289794) (xy 306.338895 -4.287775) (xy 306.414465 -4.293824) (xy 306.488963 -4.307871)
			(xy 306.561546 -4.329757) (xy 306.631392 -4.359234) (xy 306.697709 -4.395969) (xy 306.759745 -4.439544)
			(xy 306.816798 -4.489466) (xy 306.868222 -4.54517) (xy 306.913433 -4.606025) (xy 306.95192 -4.67134)
			(xy 306.983246 -4.740376) (xy 307.007056 -4.812351) (xy 307.023081 -4.886449) (xy 307.03114 -4.96183)
			(xy 307.031644 -4.999736) (xy 307.607719 -4.999736) (xy 307.611754 -4.924032) (xy 307.623813 -4.849187)
			(xy 307.643759 -4.776046) (xy 307.671366 -4.705441) (xy 307.706322 -4.63817) (xy 307.74823 -4.574995)
			(xy 307.796616 -4.516633) (xy 307.850932 -4.463745) (xy 307.910561 -4.41693) (xy 307.974829 -4.376718)
			(xy 308.043006 -4.343566) (xy 308.114322 -4.317848) (xy 308.187967 -4.299856) (xy 308.263107 -4.289794)
			(xy 308.338891 -4.287775) (xy 308.414461 -4.293824) (xy 308.488959 -4.307871) (xy 308.561542 -4.329757)
			(xy 308.631388 -4.359234) (xy 308.697705 -4.395969) (xy 308.759741 -4.439544) (xy 308.816794 -4.489466)
			(xy 308.868218 -4.54517) (xy 308.913429 -4.606025) (xy 308.951916 -4.67134) (xy 308.983242 -4.740376)
			(xy 309.007052 -4.812351) (xy 309.023077 -4.886449) (xy 309.031136 -4.96183) (xy 309.03164 -4.999736)
			(xy 309.031136 -5.037642) (xy 309.023077 -5.113023) (xy 309.007052 -5.187121) (xy 308.983242 -5.259096)
			(xy 308.951916 -5.328132) (xy 308.913429 -5.393447) (xy 308.868218 -5.454302) (xy 308.816794 -5.510006)
			(xy 308.759741 -5.559928) (xy 308.697705 -5.603503) (xy 308.631388 -5.640238) (xy 308.561542 -5.669715)
			(xy 308.488959 -5.691601) (xy 308.414461 -5.705648) (xy 308.338891 -5.711697) (xy 308.263107 -5.709678)
			(xy 308.187967 -5.699616) (xy 308.114322 -5.681624) (xy 308.043006 -5.655906) (xy 307.974829 -5.622754)
			(xy 307.910561 -5.582542) (xy 307.850932 -5.535727) (xy 307.796616 -5.482839) (xy 307.74823 -5.424477)
			(xy 307.706322 -5.361302) (xy 307.671366 -5.294031) (xy 307.643759 -5.223426) (xy 307.623813 -5.150285)
			(xy 307.611754 -5.07544) (xy 307.607719 -4.999736) (xy 307.031644 -4.999736) (xy 307.03114 -5.037642)
			(xy 307.023081 -5.113023) (xy 307.007056 -5.187121) (xy 306.983246 -5.259096) (xy 306.95192 -5.328132)
			(xy 306.913433 -5.393447) (xy 306.868222 -5.454302) (xy 306.816798 -5.510006) (xy 306.759745 -5.559928)
			(xy 306.697709 -5.603503) (xy 306.631392 -5.640238) (xy 306.561546 -5.669715) (xy 306.488963 -5.691601)
			(xy 306.414465 -5.705648) (xy 306.338895 -5.711697) (xy 306.263111 -5.709678) (xy 306.187971 -5.699616)
			(xy 306.114326 -5.681624) (xy 306.04301 -5.655906) (xy 305.974833 -5.622754) (xy 305.910565 -5.582542)
			(xy 305.850936 -5.535727) (xy 305.79662 -5.482839) (xy 305.748234 -5.424477) (xy 305.706326 -5.361302)
			(xy 305.67137 -5.294031) (xy 305.643763 -5.223426) (xy 305.623817 -5.150285) (xy 305.611758 -5.07544)
			(xy 305.607723 -4.999736) (xy 305.1556 -4.999736) (xy 305.1556 -6.999732) (xy 305.607723 -6.999732)
			(xy 305.611758 -6.924028) (xy 305.623817 -6.849183) (xy 305.643763 -6.776042) (xy 305.67137 -6.705437)
			(xy 305.706326 -6.638166) (xy 305.748234 -6.574991) (xy 305.79662 -6.516629) (xy 305.850936 -6.463741)
			(xy 305.910565 -6.416926) (xy 305.974833 -6.376714) (xy 306.04301 -6.343562) (xy 306.114326 -6.317844)
			(xy 306.187971 -6.299852) (xy 306.263111 -6.28979) (xy 306.338895 -6.287771) (xy 306.414465 -6.29382)
			(xy 306.488963 -6.307867) (xy 306.561546 -6.329753) (xy 306.631392 -6.35923) (xy 306.697709 -6.395965)
			(xy 306.759745 -6.43954) (xy 306.816798 -6.489462) (xy 306.868222 -6.545166) (xy 306.913433 -6.606021)
			(xy 306.95192 -6.671336) (xy 306.983246 -6.740372) (xy 307.007056 -6.812347) (xy 307.023081 -6.886445)
			(xy 307.03114 -6.961826) (xy 307.031644 -6.999732) (xy 307.607719 -6.999732) (xy 307.611754 -6.924028)
			(xy 307.623813 -6.849183) (xy 307.643759 -6.776042) (xy 307.671366 -6.705437) (xy 307.706322 -6.638166)
			(xy 307.74823 -6.574991) (xy 307.796616 -6.516629) (xy 307.850932 -6.463741) (xy 307.910561 -6.416926)
			(xy 307.974829 -6.376714) (xy 308.043006 -6.343562) (xy 308.114322 -6.317844) (xy 308.187967 -6.299852)
			(xy 308.263107 -6.28979) (xy 308.338891 -6.287771) (xy 308.414461 -6.29382) (xy 308.488959 -6.307867)
			(xy 308.561542 -6.329753) (xy 308.631388 -6.35923) (xy 308.697705 -6.395965) (xy 308.759741 -6.43954)
			(xy 308.816794 -6.489462) (xy 308.868218 -6.545166) (xy 308.913429 -6.606021) (xy 308.951916 -6.671336)
			(xy 308.983242 -6.740372) (xy 309.007052 -6.812347) (xy 309.023077 -6.886445) (xy 309.031136 -6.961826)
			(xy 309.03164 -6.999732) (xy 309.031136 -7.037638) (xy 309.023077 -7.113019) (xy 309.007052 -7.187117)
			(xy 308.983242 -7.259092) (xy 308.951916 -7.328128) (xy 308.913429 -7.393443) (xy 308.868218 -7.454298)
			(xy 308.816794 -7.510002) (xy 308.759741 -7.559924) (xy 308.697705 -7.603499) (xy 308.631388 -7.640234)
			(xy 308.561542 -7.669711) (xy 308.488959 -7.691597) (xy 308.414461 -7.705644) (xy 308.338891 -7.711693)
			(xy 308.263107 -7.709674) (xy 308.187967 -7.699612) (xy 308.114322 -7.68162) (xy 308.043006 -7.655902)
			(xy 307.974829 -7.62275) (xy 307.910561 -7.582538) (xy 307.850932 -7.535723) (xy 307.796616 -7.482835)
			(xy 307.74823 -7.424473) (xy 307.706322 -7.361298) (xy 307.671366 -7.294027) (xy 307.643759 -7.223422)
			(xy 307.623813 -7.150281) (xy 307.611754 -7.075436) (xy 307.607719 -6.999732) (xy 307.031644 -6.999732)
			(xy 307.03114 -7.037638) (xy 307.023081 -7.113019) (xy 307.007056 -7.187117) (xy 306.983246 -7.259092)
			(xy 306.95192 -7.328128) (xy 306.913433 -7.393443) (xy 306.868222 -7.454298) (xy 306.816798 -7.510002)
			(xy 306.759745 -7.559924) (xy 306.697709 -7.603499) (xy 306.631392 -7.640234) (xy 306.561546 -7.669711)
			(xy 306.488963 -7.691597) (xy 306.414465 -7.705644) (xy 306.338895 -7.711693) (xy 306.263111 -7.709674)
			(xy 306.187971 -7.699612) (xy 306.114326 -7.68162) (xy 306.04301 -7.655902) (xy 305.974833 -7.62275)
			(xy 305.910565 -7.582538) (xy 305.850936 -7.535723) (xy 305.79662 -7.482835) (xy 305.748234 -7.424473)
			(xy 305.706326 -7.361298) (xy 305.67137 -7.294027) (xy 305.643763 -7.223422) (xy 305.623817 -7.150281)
			(xy 305.611758 -7.075436) (xy 305.607723 -6.999732) (xy 305.1556 -6.999732) (xy 305.1556 -9.553905)
			(xy 308.834016 -9.553905) (xy 308.834016 -9.445295) (xy 308.841944 -9.336976) (xy 308.857758 -9.229523)
			(xy 308.881373 -9.123512) (xy 308.912663 -9.019508) (xy 308.951462 -8.918065) (xy 308.997562 -8.819725)
			(xy 309.050717 -8.725012) (xy 309.110644 -8.634432) (xy 309.177023 -8.548468) (xy 309.249501 -8.467578)
			(xy 309.327689 -8.392195) (xy 309.411171 -8.322721) (xy 309.499502 -8.259525) (xy 309.592211 -8.202946)
			(xy 309.688802 -8.153285) (xy 309.78876 -8.110808) (xy 309.891552 -8.07574) (xy 309.99663 -8.048269)
			(xy 310.103433 -8.028541) (xy 310.211391 -8.016663) (xy 310.319928 -8.012696) (xy 310.428465 -8.016663)
			(xy 310.536423 -8.028541) (xy 310.643226 -8.048269) (xy 310.748304 -8.07574) (xy 310.851096 -8.110808)
			(xy 310.951054 -8.153285) (xy 311.047645 -8.202946) (xy 311.140354 -8.259525) (xy 311.228685 -8.322721)
			(xy 311.312167 -8.392195) (xy 311.390355 -8.467578) (xy 311.462833 -8.548468) (xy 311.529212 -8.634432)
			(xy 311.589139 -8.725012) (xy 311.642294 -8.819725) (xy 311.688394 -8.918065) (xy 311.727193 -9.019508)
			(xy 311.758483 -9.123512) (xy 311.782098 -9.229523) (xy 311.797912 -9.336976) (xy 311.80584 -9.445295)
			(xy 311.806336 -9.4996) (xy 311.80584 -9.553905) (xy 311.797912 -9.662224) (xy 311.782098 -9.769677)
			(xy 311.758483 -9.875688) (xy 311.727193 -9.979692) (xy 311.688394 -10.081135) (xy 311.642294 -10.179475)
			(xy 311.589139 -10.274188) (xy 311.529212 -10.364768) (xy 311.462833 -10.450732) (xy 311.390355 -10.531622)
			(xy 311.312167 -10.607005) (xy 311.228685 -10.676479) (xy 311.140354 -10.739675) (xy 311.047645 -10.796254)
			(xy 310.951054 -10.845915) (xy 310.851096 -10.888392) (xy 310.748304 -10.92346) (xy 310.643226 -10.950931)
			(xy 310.536423 -10.970659) (xy 310.428465 -10.982537) (xy 310.319928 -10.986504) (xy 310.211391 -10.982537)
			(xy 310.103433 -10.970659) (xy 309.99663 -10.950931) (xy 309.891552 -10.92346) (xy 309.78876 -10.888392)
			(xy 309.688802 -10.845915) (xy 309.592211 -10.796254) (xy 309.499502 -10.739675) (xy 309.411171 -10.676479)
			(xy 309.327689 -10.607005) (xy 309.249501 -10.531622) (xy 309.177023 -10.450732) (xy 309.110644 -10.364768)
			(xy 309.050717 -10.274188) (xy 308.997562 -10.179475) (xy 308.951462 -10.081135) (xy 308.912663 -9.979692)
			(xy 308.881373 -9.875688) (xy 308.857758 -9.769677) (xy 308.841944 -9.662224) (xy 308.834016 -9.553905)
			(xy 305.1556 -9.553905) (xy 305.1556 -10.999724) (xy 305.607723 -10.999724) (xy 305.611758 -10.92402)
			(xy 305.623817 -10.849175) (xy 305.643763 -10.776034) (xy 305.67137 -10.705429) (xy 305.706326 -10.638158)
			(xy 305.748234 -10.574983) (xy 305.79662 -10.516621) (xy 305.850936 -10.463733) (xy 305.910565 -10.416918)
			(xy 305.974833 -10.376706) (xy 306.04301 -10.343554) (xy 306.114326 -10.317836) (xy 306.187971 -10.299844)
			(xy 306.263111 -10.289782) (xy 306.338895 -10.287763) (xy 306.414465 -10.293812) (xy 306.488963 -10.307859)
			(xy 306.561546 -10.329745) (xy 306.631392 -10.359222) (xy 306.697709 -10.395957) (xy 306.759745 -10.439532)
			(xy 306.816798 -10.489454) (xy 306.868222 -10.545158) (xy 306.913433 -10.606013) (xy 306.95192 -10.671328)
			(xy 306.983246 -10.740364) (xy 307.007056 -10.812339) (xy 307.023081 -10.886437) (xy 307.03114 -10.961818)
			(xy 307.031644 -10.999724) (xy 307.607719 -10.999724) (xy 307.611754 -10.92402) (xy 307.623813 -10.849175)
			(xy 307.643759 -10.776034) (xy 307.671366 -10.705429) (xy 307.706322 -10.638158) (xy 307.74823 -10.574983)
			(xy 307.796616 -10.516621) (xy 307.850932 -10.463733) (xy 307.910561 -10.416918) (xy 307.974829 -10.376706)
			(xy 308.043006 -10.343554) (xy 308.114322 -10.317836) (xy 308.187967 -10.299844) (xy 308.263107 -10.289782)
			(xy 308.338891 -10.287763) (xy 308.414461 -10.293812) (xy 308.488959 -10.307859) (xy 308.561542 -10.329745)
			(xy 308.631388 -10.359222) (xy 308.697705 -10.395957) (xy 308.759741 -10.439532) (xy 308.816794 -10.489454)
			(xy 308.868218 -10.545158) (xy 308.913429 -10.606013) (xy 308.951916 -10.671328) (xy 308.983242 -10.740364)
			(xy 309.007052 -10.812339) (xy 309.023077 -10.886437) (xy 309.031136 -10.961818) (xy 309.03164 -10.999724)
			(xy 309.031136 -11.03763) (xy 309.023077 -11.113011) (xy 309.007052 -11.187109) (xy 308.983242 -11.259084)
			(xy 308.951916 -11.32812) (xy 308.913429 -11.393435) (xy 308.868218 -11.45429) (xy 308.816794 -11.509994)
			(xy 308.759741 -11.559916) (xy 308.697705 -11.603491) (xy 308.631388 -11.640226) (xy 308.561542 -11.669703)
			(xy 308.488959 -11.691589) (xy 308.414461 -11.705636) (xy 308.338891 -11.711685) (xy 308.263107 -11.709666)
			(xy 308.187967 -11.699604) (xy 308.114322 -11.681612) (xy 308.043006 -11.655894) (xy 307.974829 -11.622742)
			(xy 307.910561 -11.58253) (xy 307.850932 -11.535715) (xy 307.796616 -11.482827) (xy 307.74823 -11.424465)
			(xy 307.706322 -11.36129) (xy 307.671366 -11.294019) (xy 307.643759 -11.223414) (xy 307.623813 -11.150273)
			(xy 307.611754 -11.075428) (xy 307.607719 -10.999724) (xy 307.031644 -10.999724) (xy 307.03114 -11.03763)
			(xy 307.023081 -11.113011) (xy 307.007056 -11.187109) (xy 306.983246 -11.259084) (xy 306.95192 -11.32812)
			(xy 306.913433 -11.393435) (xy 306.868222 -11.45429) (xy 306.816798 -11.509994) (xy 306.759745 -11.559916)
			(xy 306.697709 -11.603491) (xy 306.631392 -11.640226) (xy 306.561546 -11.669703) (xy 306.488963 -11.691589)
			(xy 306.414465 -11.705636) (xy 306.338895 -11.711685) (xy 306.263111 -11.709666) (xy 306.187971 -11.699604)
			(xy 306.114326 -11.681612) (xy 306.04301 -11.655894) (xy 305.974833 -11.622742) (xy 305.910565 -11.58253)
			(xy 305.850936 -11.535715) (xy 305.79662 -11.482827) (xy 305.748234 -11.424465) (xy 305.706326 -11.36129)
			(xy 305.67137 -11.294019) (xy 305.643763 -11.223414) (xy 305.623817 -11.150273) (xy 305.611758 -11.075428)
			(xy 305.607723 -10.999724) (xy 305.1556 -10.999724) (xy 305.1556 -12.99972) (xy 305.607723 -12.99972)
			(xy 305.611758 -12.924016) (xy 305.623817 -12.849171) (xy 305.643763 -12.77603) (xy 305.67137 -12.705425)
			(xy 305.706326 -12.638154) (xy 305.748234 -12.574979) (xy 305.79662 -12.516617) (xy 305.850936 -12.463729)
			(xy 305.910565 -12.416914) (xy 305.974833 -12.376702) (xy 306.04301 -12.34355) (xy 306.114326 -12.317832)
			(xy 306.187971 -12.29984) (xy 306.263111 -12.289778) (xy 306.338895 -12.287759) (xy 306.414465 -12.293808)
			(xy 306.488963 -12.307855) (xy 306.561546 -12.329741) (xy 306.631392 -12.359218) (xy 306.697709 -12.395953)
			(xy 306.759745 -12.439528) (xy 306.816798 -12.48945) (xy 306.868222 -12.545154) (xy 306.913433 -12.606009)
			(xy 306.95192 -12.671324) (xy 306.983246 -12.74036) (xy 307.007056 -12.812335) (xy 307.023081 -12.886433)
			(xy 307.03114 -12.961814) (xy 307.031644 -12.99972) (xy 307.607719 -12.99972) (xy 307.611754 -12.924016)
			(xy 307.623813 -12.849171) (xy 307.643759 -12.77603) (xy 307.671366 -12.705425) (xy 307.706322 -12.638154)
			(xy 307.74823 -12.574979) (xy 307.796616 -12.516617) (xy 307.850932 -12.463729) (xy 307.910561 -12.416914)
			(xy 307.974829 -12.376702) (xy 308.043006 -12.34355) (xy 308.114322 -12.317832) (xy 308.187967 -12.29984)
			(xy 308.263107 -12.289778) (xy 308.338891 -12.287759) (xy 308.414461 -12.293808) (xy 308.488959 -12.307855)
			(xy 308.561542 -12.329741) (xy 308.631388 -12.359218) (xy 308.697705 -12.395953) (xy 308.759741 -12.439528)
			(xy 308.816794 -12.48945) (xy 308.868218 -12.545154) (xy 308.913429 -12.606009) (xy 308.951916 -12.671324)
			(xy 308.983242 -12.74036) (xy 309.007052 -12.812335) (xy 309.023077 -12.886433) (xy 309.031136 -12.961814)
			(xy 309.03164 -12.99972) (xy 309.031136 -13.037626) (xy 309.023077 -13.113007) (xy 309.007052 -13.187105)
			(xy 308.983242 -13.25908) (xy 308.951916 -13.328116) (xy 308.913429 -13.393431) (xy 308.868218 -13.454286)
			(xy 308.816794 -13.50999) (xy 308.759741 -13.559912) (xy 308.697705 -13.603487) (xy 308.631388 -13.640222)
			(xy 308.561542 -13.669699) (xy 308.488959 -13.691585) (xy 308.414461 -13.705632) (xy 308.338891 -13.711681)
			(xy 308.263107 -13.709662) (xy 308.187967 -13.6996) (xy 308.114322 -13.681608) (xy 308.043006 -13.65589)
			(xy 307.974829 -13.622738) (xy 307.910561 -13.582526) (xy 307.850932 -13.535711) (xy 307.796616 -13.482823)
			(xy 307.74823 -13.424461) (xy 307.706322 -13.361286) (xy 307.671366 -13.294015) (xy 307.643759 -13.22341)
			(xy 307.623813 -13.150269) (xy 307.611754 -13.075424) (xy 307.607719 -12.99972) (xy 307.031644 -12.99972)
			(xy 307.03114 -13.037626) (xy 307.023081 -13.113007) (xy 307.007056 -13.187105) (xy 306.983246 -13.25908)
			(xy 306.95192 -13.328116) (xy 306.913433 -13.393431) (xy 306.868222 -13.454286) (xy 306.816798 -13.50999)
			(xy 306.759745 -13.559912) (xy 306.697709 -13.603487) (xy 306.631392 -13.640222) (xy 306.561546 -13.669699)
			(xy 306.488963 -13.691585) (xy 306.414465 -13.705632) (xy 306.338895 -13.711681) (xy 306.263111 -13.709662)
			(xy 306.187971 -13.6996) (xy 306.114326 -13.681608) (xy 306.04301 -13.65589) (xy 305.974833 -13.622738)
			(xy 305.910565 -13.582526) (xy 305.850936 -13.535711) (xy 305.79662 -13.482823) (xy 305.748234 -13.424461)
			(xy 305.706326 -13.361286) (xy 305.67137 -13.294015) (xy 305.643763 -13.22341) (xy 305.623817 -13.150269)
			(xy 305.611758 -13.075424) (xy 305.607723 -12.99972) (xy 305.1556 -12.99972) (xy 305.1556 -14.288008)
			(xy 305.608228 -14.288008) (xy 307.031644 -14.288008) (xy 307.031644 -14.999716) (xy 307.607719 -14.999716)
			(xy 307.611754 -14.924012) (xy 307.623813 -14.849167) (xy 307.643759 -14.776026) (xy 307.671366 -14.705421)
			(xy 307.706322 -14.63815) (xy 307.74823 -14.574975) (xy 307.796616 -14.516613) (xy 307.850932 -14.463725)
			(xy 307.910561 -14.41691) (xy 307.974829 -14.376698) (xy 308.043006 -14.343546) (xy 308.114322 -14.317828)
			(xy 308.187967 -14.299836) (xy 308.263107 -14.289774) (xy 308.338891 -14.287755) (xy 308.414461 -14.293804)
			(xy 308.488959 -14.307851) (xy 308.561542 -14.329737) (xy 308.631388 -14.359214) (xy 308.697705 -14.395949)
			(xy 308.759741 -14.439524) (xy 308.816794 -14.489446) (xy 308.868218 -14.54515) (xy 308.913429 -14.606005)
			(xy 308.951916 -14.67132) (xy 308.983242 -14.740356) (xy 309.007052 -14.812331) (xy 309.023077 -14.886429)
			(xy 309.031136 -14.96181) (xy 309.03164 -14.999716) (xy 309.031136 -15.037622) (xy 309.023077 -15.113003)
			(xy 309.007052 -15.187101) (xy 308.983242 -15.259076) (xy 308.951916 -15.328112) (xy 308.913429 -15.393427)
			(xy 308.868218 -15.454282) (xy 308.816794 -15.509986) (xy 308.759741 -15.559908) (xy 308.697705 -15.603483)
			(xy 308.631388 -15.640218) (xy 308.561542 -15.669695) (xy 308.488959 -15.691581) (xy 308.414461 -15.705628)
			(xy 308.338891 -15.711677) (xy 308.263107 -15.709658) (xy 308.187967 -15.699596) (xy 308.114322 -15.681604)
			(xy 308.043006 -15.655886) (xy 307.974829 -15.622734) (xy 307.910561 -15.582522) (xy 307.850932 -15.535707)
			(xy 307.796616 -15.482819) (xy 307.74823 -15.424457) (xy 307.706322 -15.361282) (xy 307.671366 -15.294011)
			(xy 307.643759 -15.223406) (xy 307.623813 -15.150265) (xy 307.611754 -15.07542) (xy 307.607719 -14.999716)
			(xy 307.031644 -14.999716) (xy 307.031644 -15.711424) (xy 305.608228 -15.711424) (xy 305.608228 -14.288008)
			(xy 305.1556 -14.288008) (xy 305.1556 -21.4884) (xy 303.4538 -23.1902) (xy 301.4726 -23.1902) (xy 292.7858 -23.1902)
			(xy 291.2364 -21.6408) (xy 290.6014 -21.0058) (xy 290.6014 -2.6416) (xy 289.7378 -1.778) (xy 283.444442 -1.778)
			(xy 283.421093 -1.778525) (xy 283.37518 -1.787048) (xy 283.331597 -1.803816) (xy 283.29181 -1.828263)
			(xy 283.257159 -1.859566) (xy 283.228809 -1.896674) (xy 283.207715 -1.938336) (xy 283.194587 -1.98315)
			(xy 283.189867 -2.029608) (xy 283.193714 -2.076147) (xy 283.205997 -2.1212) (xy 283.226304 -2.16325)
			(xy 283.239718 -2.182368) (xy 283.292483 -2.255041) (xy 283.392562 -2.404188) (xy 283.486257 -2.557427)
			(xy 283.573401 -2.714484) (xy 283.653839 -2.875079) (xy 283.727426 -3.038926) (xy 283.794032 -3.205732)
			(xy 283.853538 -3.375202) (xy 283.905839 -3.547032) (xy 283.95084 -3.720916) (xy 283.988462 -3.896545)
			(xy 284.018638 -4.073605) (xy 284.041314 -4.251781) (xy 284.056449 -4.430756) (xy 284.064017 -4.610209)
			(xy 284.064456 -4.700016) (xy 284.064456 -5.039461) (xy 288.061392 -5.039461) (xy 288.061392 -4.968139)
			(xy 288.069378 -4.897265) (xy 288.085248 -4.82773) (xy 288.108805 -4.76041) (xy 288.13975 -4.696151)
			(xy 288.177696 -4.63576) (xy 288.222165 -4.579998) (xy 288.272598 -4.529565) (xy 288.32836 -4.485096)
			(xy 288.388751 -4.44715) (xy 288.45301 -4.416205) (xy 288.52033 -4.392648) (xy 288.589865 -4.376778)
			(xy 288.660739 -4.368792) (xy 288.732061 -4.368792) (xy 288.802935 -4.376778) (xy 288.87247 -4.392648)
			(xy 288.93979 -4.416205) (xy 289.004049 -4.44715) (xy 289.06444 -4.485096) (xy 289.120202 -4.529565)
			(xy 289.170635 -4.579998) (xy 289.215104 -4.63576) (xy 289.25305 -4.696151) (xy 289.283995 -4.76041)
			(xy 289.307552 -4.82773) (xy 289.323422 -4.897265) (xy 289.331408 -4.968139) (xy 289.331908 -5.0038)
			(xy 289.331408 -5.039461) (xy 289.323422 -5.110335) (xy 289.307552 -5.17987) (xy 289.283995 -5.24719)
			(xy 289.25305 -5.311449) (xy 289.215104 -5.37184) (xy 289.170635 -5.427602) (xy 289.120202 -5.478035)
			(xy 289.06444 -5.522504) (xy 289.004049 -5.56045) (xy 288.93979 -5.591395) (xy 288.87247 -5.614952)
			(xy 288.802935 -5.630822) (xy 288.732061 -5.638808) (xy 288.660739 -5.638808) (xy 288.589865 -5.630822)
			(xy 288.52033 -5.614952) (xy 288.45301 -5.591395) (xy 288.388751 -5.56045) (xy 288.32836 -5.522504)
			(xy 288.272598 -5.478035) (xy 288.222165 -5.427602) (xy 288.177696 -5.37184) (xy 288.13975 -5.311449)
			(xy 288.108805 -5.24719) (xy 288.085248 -5.17987) (xy 288.069378 -5.110335) (xy 288.061392 -5.039461)
			(xy 284.064456 -5.039461) (xy 284.064456 -10.449661) (xy 287.756592 -10.449661) (xy 287.756592 -10.378339)
			(xy 287.764578 -10.307465) (xy 287.780448 -10.23793) (xy 287.804005 -10.17061) (xy 287.83495 -10.106351)
			(xy 287.872896 -10.04596) (xy 287.917365 -9.990198) (xy 287.967798 -9.939765) (xy 288.02356 -9.895296)
			(xy 288.083951 -9.85735) (xy 288.14821 -9.826405) (xy 288.21553 -9.802848) (xy 288.285065 -9.786978)
			(xy 288.355939 -9.778992) (xy 288.427261 -9.778992) (xy 288.498135 -9.786978) (xy 288.56767 -9.802848)
			(xy 288.63499 -9.826405) (xy 288.699249 -9.85735) (xy 288.75964 -9.895296) (xy 288.815402 -9.939765)
			(xy 288.865835 -9.990198) (xy 288.910304 -10.04596) (xy 288.94825 -10.106351) (xy 288.979195 -10.17061)
			(xy 289.002752 -10.23793) (xy 289.018622 -10.307465) (xy 289.026608 -10.378339) (xy 289.027108 -10.414)
			(xy 289.026608 -10.449661) (xy 289.018622 -10.520535) (xy 289.002752 -10.59007) (xy 288.979195 -10.65739)
			(xy 288.94825 -10.721649) (xy 288.910304 -10.78204) (xy 288.865835 -10.837802) (xy 288.815402 -10.888235)
			(xy 288.75964 -10.932704) (xy 288.699249 -10.97065) (xy 288.63499 -11.001595) (xy 288.56767 -11.025152)
			(xy 288.498135 -11.041022) (xy 288.427261 -11.049008) (xy 288.355939 -11.049008) (xy 288.285065 -11.041022)
			(xy 288.21553 -11.025152) (xy 288.14821 -11.001595) (xy 288.083951 -10.97065) (xy 288.02356 -10.932704)
			(xy 287.967798 -10.888235) (xy 287.917365 -10.837802) (xy 287.872896 -10.78204) (xy 287.83495 -10.721649)
			(xy 287.804005 -10.65739) (xy 287.780448 -10.59007) (xy 287.764578 -10.520535) (xy 287.756592 -10.449661)
			(xy 284.064456 -10.449661) (xy 284.064456 -10.700004) (xy 284.06395 -10.792821) (xy 284.055853 -10.978278)
			(xy 284.039674 -11.163206) (xy 284.015444 -11.347251) (xy 283.983209 -11.530065) (xy 283.94303 -11.711299)
			(xy 283.894985 -11.890607) (xy 283.839163 -12.067649) (xy 283.775673 -12.242088) (xy 283.704634 -12.413591)
			(xy 283.626182 -12.581833) (xy 283.540465 -12.746492) (xy 283.447648 -12.907256) (xy 283.347907 -13.063818)
			(xy 283.241432 -13.21588) (xy 283.128425 -13.363153) (xy 283.009102 -13.505357) (xy 282.88369 -13.642221)
			(xy 282.752427 -13.773484) (xy 282.615563 -13.898896) (xy 282.473359 -14.018219) (xy 282.326086 -14.131226)
			(xy 282.174024 -14.237701) (xy 282.017462 -14.337442) (xy 281.856698 -14.430259) (xy 281.692039 -14.515976)
			(xy 281.523797 -14.594428) (xy 281.352294 -14.665467) (xy 281.177855 -14.728957) (xy 281.000813 -14.784779)
			(xy 280.821505 -14.832824) (xy 280.640271 -14.873003) (xy 280.457457 -14.905238) (xy 280.273412 -14.929468)
			(xy 280.088484 -14.945647) (xy 279.903027 -14.953744) (xy 279.717393 -14.953744) (xy 279.531936 -14.945647)
			(xy 279.347008 -14.929468) (xy 279.162963 -14.905238) (xy 278.980149 -14.873003) (xy 278.798915 -14.832824)
			(xy 278.619607 -14.784779) (xy 278.442565 -14.728957) (xy 278.268126 -14.665467) (xy 278.096623 -14.594428)
			(xy 277.928381 -14.515976) (xy 277.763722 -14.430259) (xy 277.602958 -14.337442) (xy 277.446396 -14.237701)
			(xy 277.294334 -14.131226) (xy 277.147061 -14.018219) (xy 277.004857 -13.898896) (xy 276.867993 -13.773484)
			(xy 276.73673 -13.642221) (xy 276.611318 -13.505357) (xy 276.491995 -13.363153) (xy 276.378988 -13.21588)
			(xy 276.272513 -13.063818) (xy 276.172772 -12.907256) (xy 276.079955 -12.746492) (xy 275.994238 -12.581833)
			(xy 275.915786 -12.413591) (xy 275.844747 -12.242088) (xy 275.781257 -12.067649) (xy 275.725435 -11.890607)
			(xy 275.67739 -11.711299) (xy 275.637211 -11.530065) (xy 275.604976 -11.347251) (xy 275.580746 -11.163206)
			(xy 275.564567 -10.978278) (xy 275.55647 -10.792821) (xy 275.555964 -10.700004) (xy 275.55571 -4.700016)
			(xy 275.556176 -4.610207) (xy 275.563753 -4.430748) (xy 275.578899 -4.251769) (xy 275.601587 -4.073589)
			(xy 275.631775 -3.896525) (xy 275.669411 -3.720894) (xy 275.714428 -3.547008) (xy 275.766744 -3.375177)
			(xy 275.826267 -3.205707) (xy 275.892891 -3.038902) (xy 275.966497 -2.875057) (xy 276.046953 -2.714466)
			(xy 276.134116 -2.557413) (xy 276.227832 -2.404181) (xy 276.327932 -2.25504) (xy 276.380702 -2.182368)
			(xy 276.394097 -2.163239) (xy 276.414401 -2.12119) (xy 276.426682 -2.076141) (xy 276.430528 -2.029605)
			(xy 276.425808 -1.983151) (xy 276.412681 -1.93834) (xy 276.39159 -1.896681) (xy 276.363243 -1.859576)
			(xy 276.328596 -1.828273) (xy 276.288813 -1.803826) (xy 276.245234 -1.787058) (xy 276.199325 -1.778532)
			(xy 276.175978 -1.778) (xy 204.9018 -1.778) (xy 203.8477 -2.8321) (xy 203.8477 -6.817461) (xy 204.292192 -6.817461)
			(xy 204.292192 -6.746139) (xy 204.300178 -6.675265) (xy 204.316048 -6.60573) (xy 204.339605 -6.53841)
			(xy 204.37055 -6.474151) (xy 204.408496 -6.41376) (xy 204.452965 -6.357998) (xy 204.503398 -6.307565)
			(xy 204.55916 -6.263096) (xy 204.619551 -6.22515) (xy 204.68381 -6.194205) (xy 204.75113 -6.170648)
			(xy 204.820665 -6.154778) (xy 204.891539 -6.146792) (xy 204.962861 -6.146792) (xy 205.033735 -6.154778)
			(xy 205.10327 -6.170648) (xy 205.17059 -6.194205) (xy 205.234849 -6.22515) (xy 205.29524 -6.263096)
			(xy 205.351002 -6.307565) (xy 205.401435 -6.357998) (xy 205.445904 -6.41376) (xy 205.48385 -6.474151)
			(xy 205.514795 -6.53841) (xy 205.538352 -6.60573) (xy 205.554222 -6.675265) (xy 205.562208 -6.746139)
			(xy 205.562708 -6.7818) (xy 205.562208 -6.817461) (xy 211.912192 -6.817461) (xy 211.912192 -6.746139)
			(xy 211.920178 -6.675265) (xy 211.936048 -6.60573) (xy 211.959605 -6.53841) (xy 211.99055 -6.474151)
			(xy 212.028496 -6.41376) (xy 212.072965 -6.357998) (xy 212.123398 -6.307565) (xy 212.17916 -6.263096)
			(xy 212.239551 -6.22515) (xy 212.30381 -6.194205) (xy 212.37113 -6.170648) (xy 212.440665 -6.154778)
			(xy 212.511539 -6.146792) (xy 212.582861 -6.146792) (xy 212.653735 -6.154778) (xy 212.72327 -6.170648)
			(xy 212.79059 -6.194205) (xy 212.854849 -6.22515) (xy 212.91524 -6.263096) (xy 212.971002 -6.307565)
			(xy 213.021435 -6.357998) (xy 213.065904 -6.41376) (xy 213.10385 -6.474151) (xy 213.134795 -6.53841)
			(xy 213.158352 -6.60573) (xy 213.174222 -6.675265) (xy 213.182208 -6.746139) (xy 213.182708 -6.7818)
			(xy 213.182208 -6.817461) (xy 219.532192 -6.817461) (xy 219.532192 -6.746139) (xy 219.540178 -6.675265)
			(xy 219.556048 -6.60573) (xy 219.579605 -6.53841) (xy 219.61055 -6.474151) (xy 219.648496 -6.41376)
			(xy 219.692965 -6.357998) (xy 219.743398 -6.307565) (xy 219.79916 -6.263096) (xy 219.859551 -6.22515)
			(xy 219.92381 -6.194205) (xy 219.99113 -6.170648) (xy 220.060665 -6.154778) (xy 220.131539 -6.146792)
			(xy 220.202861 -6.146792) (xy 220.273735 -6.154778) (xy 220.34327 -6.170648) (xy 220.41059 -6.194205)
			(xy 220.474849 -6.22515) (xy 220.53524 -6.263096) (xy 220.591002 -6.307565) (xy 220.641435 -6.357998)
			(xy 220.685904 -6.41376) (xy 220.72385 -6.474151) (xy 220.754795 -6.53841) (xy 220.778352 -6.60573)
			(xy 220.794222 -6.675265) (xy 220.802208 -6.746139) (xy 220.802708 -6.7818) (xy 220.802208 -6.817461)
			(xy 227.152192 -6.817461) (xy 227.152192 -6.746139) (xy 227.160178 -6.675265) (xy 227.176048 -6.60573)
			(xy 227.199605 -6.53841) (xy 227.23055 -6.474151) (xy 227.268496 -6.41376) (xy 227.312965 -6.357998)
			(xy 227.363398 -6.307565) (xy 227.41916 -6.263096) (xy 227.479551 -6.22515) (xy 227.54381 -6.194205)
			(xy 227.61113 -6.170648) (xy 227.680665 -6.154778) (xy 227.751539 -6.146792) (xy 227.822861 -6.146792)
			(xy 227.893735 -6.154778) (xy 227.96327 -6.170648) (xy 228.03059 -6.194205) (xy 228.094849 -6.22515)
			(xy 228.15524 -6.263096) (xy 228.211002 -6.307565) (xy 228.261435 -6.357998) (xy 228.305904 -6.41376)
			(xy 228.34385 -6.474151) (xy 228.374795 -6.53841) (xy 228.398352 -6.60573) (xy 228.414222 -6.675265)
			(xy 228.422208 -6.746139) (xy 228.422708 -6.7818) (xy 228.422208 -6.817461) (xy 234.772192 -6.817461)
			(xy 234.772192 -6.746139) (xy 234.780178 -6.675265) (xy 234.796048 -6.60573) (xy 234.819605 -6.53841)
			(xy 234.85055 -6.474151) (xy 234.888496 -6.41376) (xy 234.932965 -6.357998) (xy 234.983398 -6.307565)
			(xy 235.03916 -6.263096) (xy 235.099551 -6.22515) (xy 235.16381 -6.194205) (xy 235.23113 -6.170648)
			(xy 235.300665 -6.154778) (xy 235.371539 -6.146792) (xy 235.442861 -6.146792) (xy 235.513735 -6.154778)
			(xy 235.58327 -6.170648) (xy 235.65059 -6.194205) (xy 235.714849 -6.22515) (xy 235.77524 -6.263096)
			(xy 235.831002 -6.307565) (xy 235.881435 -6.357998) (xy 235.925904 -6.41376) (xy 235.96385 -6.474151)
			(xy 235.994795 -6.53841) (xy 236.018352 -6.60573) (xy 236.034222 -6.675265) (xy 236.042208 -6.746139)
			(xy 236.042708 -6.7818) (xy 236.042208 -6.817461) (xy 242.392192 -6.817461) (xy 242.392192 -6.746139)
			(xy 242.400178 -6.675265) (xy 242.416048 -6.60573) (xy 242.439605 -6.53841) (xy 242.47055 -6.474151)
			(xy 242.508496 -6.41376) (xy 242.552965 -6.357998) (xy 242.603398 -6.307565) (xy 242.65916 -6.263096)
			(xy 242.719551 -6.22515) (xy 242.78381 -6.194205) (xy 242.85113 -6.170648) (xy 242.920665 -6.154778)
			(xy 242.991539 -6.146792) (xy 243.062861 -6.146792) (xy 243.133735 -6.154778) (xy 243.20327 -6.170648)
			(xy 243.27059 -6.194205) (xy 243.334849 -6.22515) (xy 243.39524 -6.263096) (xy 243.451002 -6.307565)
			(xy 243.501435 -6.357998) (xy 243.545904 -6.41376) (xy 243.58385 -6.474151) (xy 243.614795 -6.53841)
			(xy 243.638352 -6.60573) (xy 243.654222 -6.675265) (xy 243.662208 -6.746139) (xy 243.662708 -6.7818)
			(xy 243.662208 -6.817461) (xy 250.012192 -6.817461) (xy 250.012192 -6.746139) (xy 250.020178 -6.675265)
			(xy 250.036048 -6.60573) (xy 250.059605 -6.53841) (xy 250.09055 -6.474151) (xy 250.128496 -6.41376)
			(xy 250.172965 -6.357998) (xy 250.223398 -6.307565) (xy 250.27916 -6.263096) (xy 250.339551 -6.22515)
			(xy 250.40381 -6.194205) (xy 250.47113 -6.170648) (xy 250.540665 -6.154778) (xy 250.611539 -6.146792)
			(xy 250.682861 -6.146792) (xy 250.753735 -6.154778) (xy 250.82327 -6.170648) (xy 250.89059 -6.194205)
			(xy 250.954849 -6.22515) (xy 251.01524 -6.263096) (xy 251.071002 -6.307565) (xy 251.121435 -6.357998)
			(xy 251.165904 -6.41376) (xy 251.20385 -6.474151) (xy 251.234795 -6.53841) (xy 251.258352 -6.60573)
			(xy 251.274222 -6.675265) (xy 251.278796 -6.715861) (xy 258.140192 -6.715861) (xy 258.140192 -6.644539)
			(xy 258.148178 -6.573665) (xy 258.164048 -6.50413) (xy 258.187605 -6.43681) (xy 258.21855 -6.372551)
			(xy 258.256496 -6.31216) (xy 258.300965 -6.256398) (xy 258.351398 -6.205965) (xy 258.40716 -6.161496)
			(xy 258.467551 -6.12355) (xy 258.53181 -6.092605) (xy 258.59913 -6.069048) (xy 258.668665 -6.053178)
			(xy 258.739539 -6.045192) (xy 258.810861 -6.045192) (xy 258.881735 -6.053178) (xy 258.95127 -6.069048)
			(xy 259.01859 -6.092605) (xy 259.082849 -6.12355) (xy 259.14324 -6.161496) (xy 259.199002 -6.205965)
			(xy 259.249435 -6.256398) (xy 259.293904 -6.31216) (xy 259.33185 -6.372551) (xy 259.362795 -6.43681)
			(xy 259.386352 -6.50413) (xy 259.402222 -6.573665) (xy 259.410208 -6.644539) (xy 259.410708 -6.6802)
			(xy 259.410208 -6.715861) (xy 265.760192 -6.715861) (xy 265.760192 -6.644539) (xy 265.768178 -6.573665)
			(xy 265.784048 -6.50413) (xy 265.807605 -6.43681) (xy 265.83855 -6.372551) (xy 265.876496 -6.31216)
			(xy 265.920965 -6.256398) (xy 265.971398 -6.205965) (xy 266.02716 -6.161496) (xy 266.087551 -6.12355)
			(xy 266.15181 -6.092605) (xy 266.21913 -6.069048) (xy 266.288665 -6.053178) (xy 266.359539 -6.045192)
			(xy 266.430861 -6.045192) (xy 266.501735 -6.053178) (xy 266.57127 -6.069048) (xy 266.63859 -6.092605)
			(xy 266.702849 -6.12355) (xy 266.76324 -6.161496) (xy 266.819002 -6.205965) (xy 266.869435 -6.256398)
			(xy 266.913904 -6.31216) (xy 266.95185 -6.372551) (xy 266.982795 -6.43681) (xy 267.006352 -6.50413)
			(xy 267.022222 -6.573665) (xy 267.030208 -6.644539) (xy 267.030708 -6.6802) (xy 267.030208 -6.715861)
			(xy 273.380192 -6.715861) (xy 273.380192 -6.644539) (xy 273.388178 -6.573665) (xy 273.404048 -6.50413)
			(xy 273.427605 -6.43681) (xy 273.45855 -6.372551) (xy 273.496496 -6.31216) (xy 273.540965 -6.256398)
			(xy 273.591398 -6.205965) (xy 273.64716 -6.161496) (xy 273.707551 -6.12355) (xy 273.77181 -6.092605)
			(xy 273.83913 -6.069048) (xy 273.908665 -6.053178) (xy 273.979539 -6.045192) (xy 274.050861 -6.045192)
			(xy 274.121735 -6.053178) (xy 274.19127 -6.069048) (xy 274.25859 -6.092605) (xy 274.322849 -6.12355)
			(xy 274.38324 -6.161496) (xy 274.439002 -6.205965) (xy 274.489435 -6.256398) (xy 274.533904 -6.31216)
			(xy 274.57185 -6.372551) (xy 274.602795 -6.43681) (xy 274.626352 -6.50413) (xy 274.642222 -6.573665)
			(xy 274.650208 -6.644539) (xy 274.650708 -6.6802) (xy 274.650208 -6.715861) (xy 274.642222 -6.786735)
			(xy 274.626352 -6.85627) (xy 274.602795 -6.92359) (xy 274.57185 -6.987849) (xy 274.533904 -7.04824)
			(xy 274.489435 -7.104002) (xy 274.439002 -7.154435) (xy 274.38324 -7.198904) (xy 274.322849 -7.23685)
			(xy 274.25859 -7.267795) (xy 274.19127 -7.291352) (xy 274.121735 -7.307222) (xy 274.050861 -7.315208)
			(xy 273.979539 -7.315208) (xy 273.908665 -7.307222) (xy 273.83913 -7.291352) (xy 273.77181 -7.267795)
			(xy 273.707551 -7.23685) (xy 273.64716 -7.198904) (xy 273.591398 -7.154435) (xy 273.540965 -7.104002)
			(xy 273.496496 -7.04824) (xy 273.45855 -6.987849) (xy 273.427605 -6.92359) (xy 273.404048 -6.85627)
			(xy 273.388178 -6.786735) (xy 273.380192 -6.715861) (xy 267.030208 -6.715861) (xy 267.022222 -6.786735)
			(xy 267.006352 -6.85627) (xy 266.982795 -6.92359) (xy 266.95185 -6.987849) (xy 266.913904 -7.04824)
			(xy 266.869435 -7.104002) (xy 266.819002 -7.154435) (xy 266.76324 -7.198904) (xy 266.702849 -7.23685)
			(xy 266.63859 -7.267795) (xy 266.57127 -7.291352) (xy 266.501735 -7.307222) (xy 266.430861 -7.315208)
			(xy 266.359539 -7.315208) (xy 266.288665 -7.307222) (xy 266.21913 -7.291352) (xy 266.15181 -7.267795)
			(xy 266.087551 -7.23685) (xy 266.02716 -7.198904) (xy 265.971398 -7.154435) (xy 265.920965 -7.104002)
			(xy 265.876496 -7.04824) (xy 265.83855 -6.987849) (xy 265.807605 -6.92359) (xy 265.784048 -6.85627)
			(xy 265.768178 -6.786735) (xy 265.760192 -6.715861) (xy 259.410208 -6.715861) (xy 259.402222 -6.786735)
			(xy 259.386352 -6.85627) (xy 259.362795 -6.92359) (xy 259.33185 -6.987849) (xy 259.293904 -7.04824)
			(xy 259.249435 -7.104002) (xy 259.199002 -7.154435) (xy 259.14324 -7.198904) (xy 259.082849 -7.23685)
			(xy 259.01859 -7.267795) (xy 258.95127 -7.291352) (xy 258.881735 -7.307222) (xy 258.810861 -7.315208)
			(xy 258.739539 -7.315208) (xy 258.668665 -7.307222) (xy 258.59913 -7.291352) (xy 258.53181 -7.267795)
			(xy 258.467551 -7.23685) (xy 258.40716 -7.198904) (xy 258.351398 -7.154435) (xy 258.300965 -7.104002)
			(xy 258.256496 -7.04824) (xy 258.21855 -6.987849) (xy 258.187605 -6.92359) (xy 258.164048 -6.85627)
			(xy 258.148178 -6.786735) (xy 258.140192 -6.715861) (xy 251.278796 -6.715861) (xy 251.282208 -6.746139)
			(xy 251.282708 -6.7818) (xy 251.282208 -6.817461) (xy 251.274222 -6.888335) (xy 251.258352 -6.95787)
			(xy 251.234795 -7.02519) (xy 251.20385 -7.089449) (xy 251.165904 -7.14984) (xy 251.121435 -7.205602)
			(xy 251.071002 -7.256035) (xy 251.01524 -7.300504) (xy 250.954849 -7.33845) (xy 250.89059 -7.369395)
			(xy 250.82327 -7.392952) (xy 250.753735 -7.408822) (xy 250.682861 -7.416808) (xy 250.611539 -7.416808)
			(xy 250.540665 -7.408822) (xy 250.47113 -7.392952) (xy 250.40381 -7.369395) (xy 250.339551 -7.33845)
			(xy 250.27916 -7.300504) (xy 250.223398 -7.256035) (xy 250.172965 -7.205602) (xy 250.128496 -7.14984)
			(xy 250.09055 -7.089449) (xy 250.059605 -7.02519) (xy 250.036048 -6.95787) (xy 250.020178 -6.888335)
			(xy 250.012192 -6.817461) (xy 243.662208 -6.817461) (xy 243.654222 -6.888335) (xy 243.638352 -6.95787)
			(xy 243.614795 -7.02519) (xy 243.58385 -7.089449) (xy 243.545904 -7.14984) (xy 243.501435 -7.205602)
			(xy 243.451002 -7.256035) (xy 243.39524 -7.300504) (xy 243.334849 -7.33845) (xy 243.27059 -7.369395)
			(xy 243.20327 -7.392952) (xy 243.133735 -7.408822) (xy 243.062861 -7.416808) (xy 242.991539 -7.416808)
			(xy 242.920665 -7.408822) (xy 242.85113 -7.392952) (xy 242.78381 -7.369395) (xy 242.719551 -7.33845)
			(xy 242.65916 -7.300504) (xy 242.603398 -7.256035) (xy 242.552965 -7.205602) (xy 242.508496 -7.14984)
			(xy 242.47055 -7.089449) (xy 242.439605 -7.02519) (xy 242.416048 -6.95787) (xy 242.400178 -6.888335)
			(xy 242.392192 -6.817461) (xy 236.042208 -6.817461) (xy 236.034222 -6.888335) (xy 236.018352 -6.95787)
			(xy 235.994795 -7.02519) (xy 235.96385 -7.089449) (xy 235.925904 -7.14984) (xy 235.881435 -7.205602)
			(xy 235.831002 -7.256035) (xy 235.77524 -7.300504) (xy 235.714849 -7.33845) (xy 235.65059 -7.369395)
			(xy 235.58327 -7.392952) (xy 235.513735 -7.408822) (xy 235.442861 -7.416808) (xy 235.371539 -7.416808)
			(xy 235.300665 -7.408822) (xy 235.23113 -7.392952) (xy 235.16381 -7.369395) (xy 235.099551 -7.33845)
			(xy 235.03916 -7.300504) (xy 234.983398 -7.256035) (xy 234.932965 -7.205602) (xy 234.888496 -7.14984)
			(xy 234.85055 -7.089449) (xy 234.819605 -7.02519) (xy 234.796048 -6.95787) (xy 234.780178 -6.888335)
			(xy 234.772192 -6.817461) (xy 228.422208 -6.817461) (xy 228.414222 -6.888335) (xy 228.398352 -6.95787)
			(xy 228.374795 -7.02519) (xy 228.34385 -7.089449) (xy 228.305904 -7.14984) (xy 228.261435 -7.205602)
			(xy 228.211002 -7.256035) (xy 228.15524 -7.300504) (xy 228.094849 -7.33845) (xy 228.03059 -7.369395)
			(xy 227.96327 -7.392952) (xy 227.893735 -7.408822) (xy 227.822861 -7.416808) (xy 227.751539 -7.416808)
			(xy 227.680665 -7.408822) (xy 227.61113 -7.392952) (xy 227.54381 -7.369395) (xy 227.479551 -7.33845)
			(xy 227.41916 -7.300504) (xy 227.363398 -7.256035) (xy 227.312965 -7.205602) (xy 227.268496 -7.14984)
			(xy 227.23055 -7.089449) (xy 227.199605 -7.02519) (xy 227.176048 -6.95787) (xy 227.160178 -6.888335)
			(xy 227.152192 -6.817461) (xy 220.802208 -6.817461) (xy 220.794222 -6.888335) (xy 220.778352 -6.95787)
			(xy 220.754795 -7.02519) (xy 220.72385 -7.089449) (xy 220.685904 -7.14984) (xy 220.641435 -7.205602)
			(xy 220.591002 -7.256035) (xy 220.53524 -7.300504) (xy 220.474849 -7.33845) (xy 220.41059 -7.369395)
			(xy 220.34327 -7.392952) (xy 220.273735 -7.408822) (xy 220.202861 -7.416808) (xy 220.131539 -7.416808)
			(xy 220.060665 -7.408822) (xy 219.99113 -7.392952) (xy 219.92381 -7.369395) (xy 219.859551 -7.33845)
			(xy 219.79916 -7.300504) (xy 219.743398 -7.256035) (xy 219.692965 -7.205602) (xy 219.648496 -7.14984)
			(xy 219.61055 -7.089449) (xy 219.579605 -7.02519) (xy 219.556048 -6.95787) (xy 219.540178 -6.888335)
			(xy 219.532192 -6.817461) (xy 213.182208 -6.817461) (xy 213.174222 -6.888335) (xy 213.158352 -6.95787)
			(xy 213.134795 -7.02519) (xy 213.10385 -7.089449) (xy 213.065904 -7.14984) (xy 213.021435 -7.205602)
			(xy 212.971002 -7.256035) (xy 212.91524 -7.300504) (xy 212.854849 -7.33845) (xy 212.79059 -7.369395)
			(xy 212.72327 -7.392952) (xy 212.653735 -7.408822) (xy 212.582861 -7.416808) (xy 212.511539 -7.416808)
			(xy 212.440665 -7.408822) (xy 212.37113 -7.392952) (xy 212.30381 -7.369395) (xy 212.239551 -7.33845)
			(xy 212.17916 -7.300504) (xy 212.123398 -7.256035) (xy 212.072965 -7.205602) (xy 212.028496 -7.14984)
			(xy 211.99055 -7.089449) (xy 211.959605 -7.02519) (xy 211.936048 -6.95787) (xy 211.920178 -6.888335)
			(xy 211.912192 -6.817461) (xy 205.562208 -6.817461) (xy 205.554222 -6.888335) (xy 205.538352 -6.95787)
			(xy 205.514795 -7.02519) (xy 205.48385 -7.089449) (xy 205.445904 -7.14984) (xy 205.401435 -7.205602)
			(xy 205.351002 -7.256035) (xy 205.29524 -7.300504) (xy 205.234849 -7.33845) (xy 205.17059 -7.369395)
			(xy 205.10327 -7.392952) (xy 205.033735 -7.408822) (xy 204.962861 -7.416808) (xy 204.891539 -7.416808)
			(xy 204.820665 -7.408822) (xy 204.75113 -7.392952) (xy 204.68381 -7.369395) (xy 204.619551 -7.33845)
			(xy 204.55916 -7.300504) (xy 204.503398 -7.256035) (xy 204.452965 -7.205602) (xy 204.408496 -7.14984)
			(xy 204.37055 -7.089449) (xy 204.339605 -7.02519) (xy 204.316048 -6.95787) (xy 204.300178 -6.888335)
			(xy 204.292192 -6.817461) (xy 203.8477 -6.817461) (xy 203.8477 -16.596461) (xy 205.282792 -16.596461)
			(xy 205.282792 -16.525139) (xy 205.290778 -16.454265) (xy 205.306648 -16.38473) (xy 205.330205 -16.31741)
			(xy 205.36115 -16.253151) (xy 205.399096 -16.19276) (xy 205.443565 -16.136998) (xy 205.493998 -16.086565)
			(xy 205.54976 -16.042096) (xy 205.610151 -16.00415) (xy 205.67441 -15.973205) (xy 205.74173 -15.949648)
			(xy 205.811265 -15.933778) (xy 205.882139 -15.925792) (xy 205.953461 -15.925792) (xy 206.024335 -15.933778)
			(xy 206.09387 -15.949648) (xy 206.16119 -15.973205) (xy 206.225449 -16.00415) (xy 206.28584 -16.042096)
			(xy 206.341602 -16.086565) (xy 206.392035 -16.136998) (xy 206.436504 -16.19276) (xy 206.47445 -16.253151)
			(xy 206.505395 -16.31741) (xy 206.528952 -16.38473) (xy 206.544822 -16.454265) (xy 206.552808 -16.525139)
			(xy 206.553308 -16.5608) (xy 206.552808 -16.596461) (xy 212.902792 -16.596461) (xy 212.902792 -16.525139)
			(xy 212.910778 -16.454265) (xy 212.926648 -16.38473) (xy 212.950205 -16.31741) (xy 212.98115 -16.253151)
			(xy 213.019096 -16.19276) (xy 213.063565 -16.136998) (xy 213.113998 -16.086565) (xy 213.16976 -16.042096)
			(xy 213.230151 -16.00415) (xy 213.29441 -15.973205) (xy 213.36173 -15.949648) (xy 213.431265 -15.933778)
			(xy 213.502139 -15.925792) (xy 213.573461 -15.925792) (xy 213.644335 -15.933778) (xy 213.71387 -15.949648)
			(xy 213.78119 -15.973205) (xy 213.845449 -16.00415) (xy 213.90584 -16.042096) (xy 213.961602 -16.086565)
			(xy 214.012035 -16.136998) (xy 214.056504 -16.19276) (xy 214.09445 -16.253151) (xy 214.125395 -16.31741)
			(xy 214.148952 -16.38473) (xy 214.164822 -16.454265) (xy 214.172808 -16.525139) (xy 214.173308 -16.5608)
			(xy 214.172808 -16.596461) (xy 220.522792 -16.596461) (xy 220.522792 -16.525139) (xy 220.530778 -16.454265)
			(xy 220.546648 -16.38473) (xy 220.570205 -16.31741) (xy 220.60115 -16.253151) (xy 220.639096 -16.19276)
			(xy 220.683565 -16.136998) (xy 220.733998 -16.086565) (xy 220.78976 -16.042096) (xy 220.850151 -16.00415)
			(xy 220.91441 -15.973205) (xy 220.98173 -15.949648) (xy 221.051265 -15.933778) (xy 221.122139 -15.925792)
			(xy 221.193461 -15.925792) (xy 221.264335 -15.933778) (xy 221.33387 -15.949648) (xy 221.40119 -15.973205)
			(xy 221.465449 -16.00415) (xy 221.52584 -16.042096) (xy 221.581602 -16.086565) (xy 221.632035 -16.136998)
			(xy 221.676504 -16.19276) (xy 221.71445 -16.253151) (xy 221.745395 -16.31741) (xy 221.768952 -16.38473)
			(xy 221.784822 -16.454265) (xy 221.792808 -16.525139) (xy 221.793308 -16.5608) (xy 221.792808 -16.596461)
			(xy 228.142792 -16.596461) (xy 228.142792 -16.525139) (xy 228.150778 -16.454265) (xy 228.166648 -16.38473)
			(xy 228.190205 -16.31741) (xy 228.22115 -16.253151) (xy 228.259096 -16.19276) (xy 228.303565 -16.136998)
			(xy 228.353998 -16.086565) (xy 228.40976 -16.042096) (xy 228.470151 -16.00415) (xy 228.53441 -15.973205)
			(xy 228.60173 -15.949648) (xy 228.671265 -15.933778) (xy 228.742139 -15.925792) (xy 228.813461 -15.925792)
			(xy 228.884335 -15.933778) (xy 228.95387 -15.949648) (xy 229.02119 -15.973205) (xy 229.085449 -16.00415)
			(xy 229.14584 -16.042096) (xy 229.201602 -16.086565) (xy 229.252035 -16.136998) (xy 229.296504 -16.19276)
			(xy 229.33445 -16.253151) (xy 229.365395 -16.31741) (xy 229.388952 -16.38473) (xy 229.404822 -16.454265)
			(xy 229.412808 -16.525139) (xy 229.413308 -16.5608) (xy 229.412808 -16.596461) (xy 235.762792 -16.596461)
			(xy 235.762792 -16.525139) (xy 235.770778 -16.454265) (xy 235.786648 -16.38473) (xy 235.810205 -16.31741)
			(xy 235.84115 -16.253151) (xy 235.879096 -16.19276) (xy 235.923565 -16.136998) (xy 235.973998 -16.086565)
			(xy 236.02976 -16.042096) (xy 236.090151 -16.00415) (xy 236.15441 -15.973205) (xy 236.22173 -15.949648)
			(xy 236.291265 -15.933778) (xy 236.362139 -15.925792) (xy 236.433461 -15.925792) (xy 236.504335 -15.933778)
			(xy 236.57387 -15.949648) (xy 236.64119 -15.973205) (xy 236.705449 -16.00415) (xy 236.76584 -16.042096)
			(xy 236.821602 -16.086565) (xy 236.872035 -16.136998) (xy 236.916504 -16.19276) (xy 236.95445 -16.253151)
			(xy 236.985395 -16.31741) (xy 237.008952 -16.38473) (xy 237.024822 -16.454265) (xy 237.032808 -16.525139)
			(xy 237.033308 -16.5608) (xy 237.032808 -16.596461) (xy 243.382792 -16.596461) (xy 243.382792 -16.525139)
			(xy 243.390778 -16.454265) (xy 243.406648 -16.38473) (xy 243.430205 -16.31741) (xy 243.46115 -16.253151)
			(xy 243.499096 -16.19276) (xy 243.543565 -16.136998) (xy 243.593998 -16.086565) (xy 243.64976 -16.042096)
			(xy 243.710151 -16.00415) (xy 243.77441 -15.973205) (xy 243.84173 -15.949648) (xy 243.911265 -15.933778)
			(xy 243.982139 -15.925792) (xy 244.053461 -15.925792) (xy 244.124335 -15.933778) (xy 244.19387 -15.949648)
			(xy 244.26119 -15.973205) (xy 244.325449 -16.00415) (xy 244.38584 -16.042096) (xy 244.441602 -16.086565)
			(xy 244.492035 -16.136998) (xy 244.536504 -16.19276) (xy 244.57445 -16.253151) (xy 244.605395 -16.31741)
			(xy 244.628952 -16.38473) (xy 244.644822 -16.454265) (xy 244.652808 -16.525139) (xy 244.653308 -16.5608)
			(xy 244.652808 -16.596461) (xy 251.002792 -16.596461) (xy 251.002792 -16.525139) (xy 251.010778 -16.454265)
			(xy 251.026648 -16.38473) (xy 251.050205 -16.31741) (xy 251.08115 -16.253151) (xy 251.119096 -16.19276)
			(xy 251.163565 -16.136998) (xy 251.213998 -16.086565) (xy 251.26976 -16.042096) (xy 251.330151 -16.00415)
			(xy 251.39441 -15.973205) (xy 251.46173 -15.949648) (xy 251.531265 -15.933778) (xy 251.602139 -15.925792)
			(xy 251.673461 -15.925792) (xy 251.744335 -15.933778) (xy 251.81387 -15.949648) (xy 251.88119 -15.973205)
			(xy 251.945449 -16.00415) (xy 252.00584 -16.042096) (xy 252.061602 -16.086565) (xy 252.112035 -16.136998)
			(xy 252.156504 -16.19276) (xy 252.19445 -16.253151) (xy 252.225395 -16.31741) (xy 252.248952 -16.38473)
			(xy 252.264822 -16.454265) (xy 252.269396 -16.494861) (xy 259.130792 -16.494861) (xy 259.130792 -16.423539)
			(xy 259.138778 -16.352665) (xy 259.154648 -16.28313) (xy 259.178205 -16.21581) (xy 259.20915 -16.151551)
			(xy 259.247096 -16.09116) (xy 259.291565 -16.035398) (xy 259.341998 -15.984965) (xy 259.39776 -15.940496)
			(xy 259.458151 -15.90255) (xy 259.52241 -15.871605) (xy 259.58973 -15.848048) (xy 259.659265 -15.832178)
			(xy 259.730139 -15.824192) (xy 259.801461 -15.824192) (xy 259.872335 -15.832178) (xy 259.94187 -15.848048)
			(xy 260.00919 -15.871605) (xy 260.073449 -15.90255) (xy 260.13384 -15.940496) (xy 260.189602 -15.984965)
			(xy 260.240035 -16.035398) (xy 260.284504 -16.09116) (xy 260.32245 -16.151551) (xy 260.353395 -16.21581)
			(xy 260.376952 -16.28313) (xy 260.392822 -16.352665) (xy 260.400808 -16.423539) (xy 260.401308 -16.4592)
			(xy 260.400808 -16.494861) (xy 266.750792 -16.494861) (xy 266.750792 -16.423539) (xy 266.758778 -16.352665)
			(xy 266.774648 -16.28313) (xy 266.798205 -16.21581) (xy 266.82915 -16.151551) (xy 266.867096 -16.09116)
			(xy 266.911565 -16.035398) (xy 266.961998 -15.984965) (xy 267.01776 -15.940496) (xy 267.078151 -15.90255)
			(xy 267.14241 -15.871605) (xy 267.20973 -15.848048) (xy 267.279265 -15.832178) (xy 267.350139 -15.824192)
			(xy 267.421461 -15.824192) (xy 267.492335 -15.832178) (xy 267.56187 -15.848048) (xy 267.62919 -15.871605)
			(xy 267.693449 -15.90255) (xy 267.75384 -15.940496) (xy 267.809602 -15.984965) (xy 267.860035 -16.035398)
			(xy 267.904504 -16.09116) (xy 267.94245 -16.151551) (xy 267.973395 -16.21581) (xy 267.996952 -16.28313)
			(xy 268.012822 -16.352665) (xy 268.020808 -16.423539) (xy 268.021308 -16.4592) (xy 268.020808 -16.494861)
			(xy 274.370792 -16.494861) (xy 274.370792 -16.423539) (xy 274.378778 -16.352665) (xy 274.394648 -16.28313)
			(xy 274.418205 -16.21581) (xy 274.44915 -16.151551) (xy 274.487096 -16.09116) (xy 274.531565 -16.035398)
			(xy 274.581998 -15.984965) (xy 274.63776 -15.940496) (xy 274.698151 -15.90255) (xy 274.76241 -15.871605)
			(xy 274.82973 -15.848048) (xy 274.899265 -15.832178) (xy 274.970139 -15.824192) (xy 275.041461 -15.824192)
			(xy 275.112335 -15.832178) (xy 275.18187 -15.848048) (xy 275.24919 -15.871605) (xy 275.313449 -15.90255)
			(xy 275.37384 -15.940496) (xy 275.429602 -15.984965) (xy 275.480035 -16.035398) (xy 275.524504 -16.09116)
			(xy 275.56245 -16.151551) (xy 275.593395 -16.21581) (xy 275.616952 -16.28313) (xy 275.632822 -16.352665)
			(xy 275.640808 -16.423539) (xy 275.641308 -16.4592) (xy 275.640808 -16.494861) (xy 275.632822 -16.565735)
			(xy 275.616952 -16.63527) (xy 275.593395 -16.70259) (xy 275.56245 -16.766849) (xy 275.524504 -16.82724)
			(xy 275.480035 -16.883002) (xy 275.429602 -16.933435) (xy 275.37384 -16.977904) (xy 275.313449 -17.01585)
			(xy 275.24919 -17.046795) (xy 275.18187 -17.070352) (xy 275.112335 -17.086222) (xy 275.041461 -17.094208)
			(xy 274.970139 -17.094208) (xy 274.899265 -17.086222) (xy 274.82973 -17.070352) (xy 274.76241 -17.046795)
			(xy 274.698151 -17.01585) (xy 274.63776 -16.977904) (xy 274.581998 -16.933435) (xy 274.531565 -16.883002)
			(xy 274.487096 -16.82724) (xy 274.44915 -16.766849) (xy 274.418205 -16.70259) (xy 274.394648 -16.63527)
			(xy 274.378778 -16.565735) (xy 274.370792 -16.494861) (xy 268.020808 -16.494861) (xy 268.012822 -16.565735)
			(xy 267.996952 -16.63527) (xy 267.973395 -16.70259) (xy 267.94245 -16.766849) (xy 267.904504 -16.82724)
			(xy 267.860035 -16.883002) (xy 267.809602 -16.933435) (xy 267.75384 -16.977904) (xy 267.693449 -17.01585)
			(xy 267.62919 -17.046795) (xy 267.56187 -17.070352) (xy 267.492335 -17.086222) (xy 267.421461 -17.094208)
			(xy 267.350139 -17.094208) (xy 267.279265 -17.086222) (xy 267.20973 -17.070352) (xy 267.14241 -17.046795)
			(xy 267.078151 -17.01585) (xy 267.01776 -16.977904) (xy 266.961998 -16.933435) (xy 266.911565 -16.883002)
			(xy 266.867096 -16.82724) (xy 266.82915 -16.766849) (xy 266.798205 -16.70259) (xy 266.774648 -16.63527)
			(xy 266.758778 -16.565735) (xy 266.750792 -16.494861) (xy 260.400808 -16.494861) (xy 260.392822 -16.565735)
			(xy 260.376952 -16.63527) (xy 260.353395 -16.70259) (xy 260.32245 -16.766849) (xy 260.284504 -16.82724)
			(xy 260.240035 -16.883002) (xy 260.189602 -16.933435) (xy 260.13384 -16.977904) (xy 260.073449 -17.01585)
			(xy 260.00919 -17.046795) (xy 259.94187 -17.070352) (xy 259.872335 -17.086222) (xy 259.801461 -17.094208)
			(xy 259.730139 -17.094208) (xy 259.659265 -17.086222) (xy 259.58973 -17.070352) (xy 259.52241 -17.046795)
			(xy 259.458151 -17.01585) (xy 259.39776 -16.977904) (xy 259.341998 -16.933435) (xy 259.291565 -16.883002)
			(xy 259.247096 -16.82724) (xy 259.20915 -16.766849) (xy 259.178205 -16.70259) (xy 259.154648 -16.63527)
			(xy 259.138778 -16.565735) (xy 259.130792 -16.494861) (xy 252.269396 -16.494861) (xy 252.272808 -16.525139)
			(xy 252.273308 -16.5608) (xy 252.272808 -16.596461) (xy 252.264822 -16.667335) (xy 252.248952 -16.73687)
			(xy 252.225395 -16.80419) (xy 252.19445 -16.868449) (xy 252.156504 -16.92884) (xy 252.112035 -16.984602)
			(xy 252.061602 -17.035035) (xy 252.00584 -17.079504) (xy 251.945449 -17.11745) (xy 251.88119 -17.148395)
			(xy 251.81387 -17.171952) (xy 251.744335 -17.187822) (xy 251.673461 -17.195808) (xy 251.602139 -17.195808)
			(xy 251.531265 -17.187822) (xy 251.46173 -17.171952) (xy 251.39441 -17.148395) (xy 251.330151 -17.11745)
			(xy 251.26976 -17.079504) (xy 251.213998 -17.035035) (xy 251.163565 -16.984602) (xy 251.119096 -16.92884)
			(xy 251.08115 -16.868449) (xy 251.050205 -16.80419) (xy 251.026648 -16.73687) (xy 251.010778 -16.667335)
			(xy 251.002792 -16.596461) (xy 244.652808 -16.596461) (xy 244.644822 -16.667335) (xy 244.628952 -16.73687)
			(xy 244.605395 -16.80419) (xy 244.57445 -16.868449) (xy 244.536504 -16.92884) (xy 244.492035 -16.984602)
			(xy 244.441602 -17.035035) (xy 244.38584 -17.079504) (xy 244.325449 -17.11745) (xy 244.26119 -17.148395)
			(xy 244.19387 -17.171952) (xy 244.124335 -17.187822) (xy 244.053461 -17.195808) (xy 243.982139 -17.195808)
			(xy 243.911265 -17.187822) (xy 243.84173 -17.171952) (xy 243.77441 -17.148395) (xy 243.710151 -17.11745)
			(xy 243.64976 -17.079504) (xy 243.593998 -17.035035) (xy 243.543565 -16.984602) (xy 243.499096 -16.92884)
			(xy 243.46115 -16.868449) (xy 243.430205 -16.80419) (xy 243.406648 -16.73687) (xy 243.390778 -16.667335)
			(xy 243.382792 -16.596461) (xy 237.032808 -16.596461) (xy 237.024822 -16.667335) (xy 237.008952 -16.73687)
			(xy 236.985395 -16.80419) (xy 236.95445 -16.868449) (xy 236.916504 -16.92884) (xy 236.872035 -16.984602)
			(xy 236.821602 -17.035035) (xy 236.76584 -17.079504) (xy 236.705449 -17.11745) (xy 236.64119 -17.148395)
			(xy 236.57387 -17.171952) (xy 236.504335 -17.187822) (xy 236.433461 -17.195808) (xy 236.362139 -17.195808)
			(xy 236.291265 -17.187822) (xy 236.22173 -17.171952) (xy 236.15441 -17.148395) (xy 236.090151 -17.11745)
			(xy 236.02976 -17.079504) (xy 235.973998 -17.035035) (xy 235.923565 -16.984602) (xy 235.879096 -16.92884)
			(xy 235.84115 -16.868449) (xy 235.810205 -16.80419) (xy 235.786648 -16.73687) (xy 235.770778 -16.667335)
			(xy 235.762792 -16.596461) (xy 229.412808 -16.596461) (xy 229.404822 -16.667335) (xy 229.388952 -16.73687)
			(xy 229.365395 -16.80419) (xy 229.33445 -16.868449) (xy 229.296504 -16.92884) (xy 229.252035 -16.984602)
			(xy 229.201602 -17.035035) (xy 229.14584 -17.079504) (xy 229.085449 -17.11745) (xy 229.02119 -17.148395)
			(xy 228.95387 -17.171952) (xy 228.884335 -17.187822) (xy 228.813461 -17.195808) (xy 228.742139 -17.195808)
			(xy 228.671265 -17.187822) (xy 228.60173 -17.171952) (xy 228.53441 -17.148395) (xy 228.470151 -17.11745)
			(xy 228.40976 -17.079504) (xy 228.353998 -17.035035) (xy 228.303565 -16.984602) (xy 228.259096 -16.92884)
			(xy 228.22115 -16.868449) (xy 228.190205 -16.80419) (xy 228.166648 -16.73687) (xy 228.150778 -16.667335)
			(xy 228.142792 -16.596461) (xy 221.792808 -16.596461) (xy 221.784822 -16.667335) (xy 221.768952 -16.73687)
			(xy 221.745395 -16.80419) (xy 221.71445 -16.868449) (xy 221.676504 -16.92884) (xy 221.632035 -16.984602)
			(xy 221.581602 -17.035035) (xy 221.52584 -17.079504) (xy 221.465449 -17.11745) (xy 221.40119 -17.148395)
			(xy 221.33387 -17.171952) (xy 221.264335 -17.187822) (xy 221.193461 -17.195808) (xy 221.122139 -17.195808)
			(xy 221.051265 -17.187822) (xy 220.98173 -17.171952) (xy 220.91441 -17.148395) (xy 220.850151 -17.11745)
			(xy 220.78976 -17.079504) (xy 220.733998 -17.035035) (xy 220.683565 -16.984602) (xy 220.639096 -16.92884)
			(xy 220.60115 -16.868449) (xy 220.570205 -16.80419) (xy 220.546648 -16.73687) (xy 220.530778 -16.667335)
			(xy 220.522792 -16.596461) (xy 214.172808 -16.596461) (xy 214.164822 -16.667335) (xy 214.148952 -16.73687)
			(xy 214.125395 -16.80419) (xy 214.09445 -16.868449) (xy 214.056504 -16.92884) (xy 214.012035 -16.984602)
			(xy 213.961602 -17.035035) (xy 213.90584 -17.079504) (xy 213.845449 -17.11745) (xy 213.78119 -17.148395)
			(xy 213.71387 -17.171952) (xy 213.644335 -17.187822) (xy 213.573461 -17.195808) (xy 213.502139 -17.195808)
			(xy 213.431265 -17.187822) (xy 213.36173 -17.171952) (xy 213.29441 -17.148395) (xy 213.230151 -17.11745)
			(xy 213.16976 -17.079504) (xy 213.113998 -17.035035) (xy 213.063565 -16.984602) (xy 213.019096 -16.92884)
			(xy 212.98115 -16.868449) (xy 212.950205 -16.80419) (xy 212.926648 -16.73687) (xy 212.910778 -16.667335)
			(xy 212.902792 -16.596461) (xy 206.552808 -16.596461) (xy 206.544822 -16.667335) (xy 206.528952 -16.73687)
			(xy 206.505395 -16.80419) (xy 206.47445 -16.868449) (xy 206.436504 -16.92884) (xy 206.392035 -16.984602)
			(xy 206.341602 -17.035035) (xy 206.28584 -17.079504) (xy 206.225449 -17.11745) (xy 206.16119 -17.148395)
			(xy 206.09387 -17.171952) (xy 206.024335 -17.187822) (xy 205.953461 -17.195808) (xy 205.882139 -17.195808)
			(xy 205.811265 -17.187822) (xy 205.74173 -17.171952) (xy 205.67441 -17.148395) (xy 205.610151 -17.11745)
			(xy 205.54976 -17.079504) (xy 205.493998 -17.035035) (xy 205.443565 -16.984602) (xy 205.399096 -16.92884)
			(xy 205.36115 -16.868449) (xy 205.330205 -16.80419) (xy 205.306648 -16.73687) (xy 205.290778 -16.667335)
			(xy 205.282792 -16.596461) (xy 203.8477 -16.596461) (xy 203.8477 -20.758663) (xy 254.812541 -20.758663)
			(xy 254.812541 -20.643337) (xy 254.820586 -20.528291) (xy 254.836636 -20.414087) (xy 254.860614 -20.301281)
			(xy 254.892402 -20.190422) (xy 254.931846 -20.08205) (xy 254.978754 -19.976694) (xy 255.032896 -19.874867)
			(xy 255.09401 -19.777065) (xy 255.161797 -19.683764) (xy 255.235927 -19.595419) (xy 255.31604 -19.51246)
			(xy 255.401744 -19.435291) (xy 255.492623 -19.364289) (xy 255.588233 -19.299799) (xy 255.688108 -19.242136)
			(xy 255.791763 -19.19158) (xy 255.898692 -19.148378) (xy 256.008374 -19.11274) (xy 256.120275 -19.08484)
			(xy 256.233849 -19.064814) (xy 256.348544 -19.052759) (xy 256.4638 -19.048735) (xy 256.579056 -19.052759)
			(xy 256.693751 -19.064814) (xy 256.807325 -19.08484) (xy 256.919226 -19.11274) (xy 257.028908 -19.148378)
			(xy 257.135837 -19.19158) (xy 257.239492 -19.242136) (xy 257.339367 -19.299799) (xy 257.434977 -19.364289)
			(xy 257.525856 -19.435291) (xy 257.61156 -19.51246) (xy 257.691673 -19.595419) (xy 257.765803 -19.683764)
			(xy 257.83359 -19.777065) (xy 257.894704 -19.874867) (xy 257.948846 -19.976694) (xy 257.995754 -20.08205)
			(xy 258.035198 -20.190422) (xy 258.066986 -20.301281) (xy 258.090964 -20.414087) (xy 258.107014 -20.528291)
			(xy 258.115059 -20.643337) (xy 258.115562 -20.701) (xy 258.115059 -20.758663) (xy 258.107014 -20.873709)
			(xy 258.090964 -20.987913) (xy 258.066986 -21.100719) (xy 258.035198 -21.211578) (xy 257.995754 -21.31995)
			(xy 257.948846 -21.425306) (xy 257.894704 -21.527133) (xy 257.83359 -21.624935) (xy 257.765803 -21.718236)
			(xy 257.691673 -21.806581) (xy 257.61156 -21.88954) (xy 257.525856 -21.966709) (xy 257.434977 -22.037711)
			(xy 257.339367 -22.102201) (xy 257.239492 -22.159864) (xy 257.135837 -22.21042) (xy 257.028908 -22.253622)
			(xy 256.919226 -22.28926) (xy 256.807325 -22.31716) (xy 256.693751 -22.337186) (xy 256.579056 -22.349241)
			(xy 256.4638 -22.353266) (xy 256.348544 -22.349241) (xy 256.233849 -22.337186) (xy 256.120275 -22.31716)
			(xy 256.008374 -22.28926) (xy 255.898692 -22.253622) (xy 255.791763 -22.21042) (xy 255.688108 -22.159864)
			(xy 255.588233 -22.102201) (xy 255.492623 -22.037711) (xy 255.401744 -21.966709) (xy 255.31604 -21.88954)
			(xy 255.235927 -21.806581) (xy 255.161797 -21.718236) (xy 255.09401 -21.624935) (xy 255.032896 -21.527133)
			(xy 254.978754 -21.425306) (xy 254.931846 -21.31995) (xy 254.892402 -21.211578) (xy 254.860614 -21.100719)
			(xy 254.836636 -20.987913) (xy 254.820586 -20.873709) (xy 254.812541 -20.758663) (xy 203.8477 -20.758663)
			(xy 203.8477 -28.407461) (xy 208.965792 -28.407461) (xy 208.965792 -28.336139) (xy 208.973778 -28.265265)
			(xy 208.989648 -28.19573) (xy 209.013205 -28.12841) (xy 209.04415 -28.064151) (xy 209.082096 -28.00376)
			(xy 209.126565 -27.947998) (xy 209.176998 -27.897565) (xy 209.23276 -27.853096) (xy 209.293151 -27.81515)
			(xy 209.35741 -27.784205) (xy 209.42473 -27.760648) (xy 209.494265 -27.744778) (xy 209.565139 -27.736792)
			(xy 209.636461 -27.736792) (xy 209.707335 -27.744778) (xy 209.77687 -27.760648) (xy 209.84419 -27.784205)
			(xy 209.908449 -27.81515) (xy 209.96884 -27.853096) (xy 210.024602 -27.897565) (xy 210.075035 -27.947998)
			(xy 210.119504 -28.00376) (xy 210.15745 -28.064151) (xy 210.188395 -28.12841) (xy 210.211952 -28.19573)
			(xy 210.227822 -28.265265) (xy 210.235808 -28.336139) (xy 210.236308 -28.3718) (xy 210.235808 -28.407461)
			(xy 216.585792 -28.407461) (xy 216.585792 -28.336139) (xy 216.593778 -28.265265) (xy 216.609648 -28.19573)
			(xy 216.633205 -28.12841) (xy 216.66415 -28.064151) (xy 216.702096 -28.00376) (xy 216.746565 -27.947998)
			(xy 216.796998 -27.897565) (xy 216.85276 -27.853096) (xy 216.913151 -27.81515) (xy 216.97741 -27.784205)
			(xy 217.04473 -27.760648) (xy 217.114265 -27.744778) (xy 217.185139 -27.736792) (xy 217.256461 -27.736792)
			(xy 217.327335 -27.744778) (xy 217.39687 -27.760648) (xy 217.46419 -27.784205) (xy 217.528449 -27.81515)
			(xy 217.58884 -27.853096) (xy 217.644602 -27.897565) (xy 217.695035 -27.947998) (xy 217.739504 -28.00376)
			(xy 217.77745 -28.064151) (xy 217.808395 -28.12841) (xy 217.831952 -28.19573) (xy 217.847822 -28.265265)
			(xy 217.855808 -28.336139) (xy 217.856308 -28.3718) (xy 217.855808 -28.407461) (xy 224.205792 -28.407461)
			(xy 224.205792 -28.336139) (xy 224.213778 -28.265265) (xy 224.229648 -28.19573) (xy 224.253205 -28.12841)
			(xy 224.28415 -28.064151) (xy 224.322096 -28.00376) (xy 224.366565 -27.947998) (xy 224.416998 -27.897565)
			(xy 224.47276 -27.853096) (xy 224.533151 -27.81515) (xy 224.59741 -27.784205) (xy 224.66473 -27.760648)
			(xy 224.734265 -27.744778) (xy 224.805139 -27.736792) (xy 224.876461 -27.736792) (xy 224.947335 -27.744778)
			(xy 225.01687 -27.760648) (xy 225.08419 -27.784205) (xy 225.148449 -27.81515) (xy 225.20884 -27.853096)
			(xy 225.264602 -27.897565) (xy 225.315035 -27.947998) (xy 225.359504 -28.00376) (xy 225.39745 -28.064151)
			(xy 225.428395 -28.12841) (xy 225.451952 -28.19573) (xy 225.467822 -28.265265) (xy 225.475808 -28.336139)
			(xy 225.476308 -28.3718) (xy 225.475808 -28.407461) (xy 231.825792 -28.407461) (xy 231.825792 -28.336139)
			(xy 231.833778 -28.265265) (xy 231.849648 -28.19573) (xy 231.873205 -28.12841) (xy 231.90415 -28.064151)
			(xy 231.942096 -28.00376) (xy 231.986565 -27.947998) (xy 232.036998 -27.897565) (xy 232.09276 -27.853096)
			(xy 232.153151 -27.81515) (xy 232.21741 -27.784205) (xy 232.28473 -27.760648) (xy 232.354265 -27.744778)
			(xy 232.425139 -27.736792) (xy 232.496461 -27.736792) (xy 232.567335 -27.744778) (xy 232.63687 -27.760648)
			(xy 232.70419 -27.784205) (xy 232.768449 -27.81515) (xy 232.82884 -27.853096) (xy 232.884602 -27.897565)
			(xy 232.935035 -27.947998) (xy 232.979504 -28.00376) (xy 233.01745 -28.064151) (xy 233.048395 -28.12841)
			(xy 233.071952 -28.19573) (xy 233.087822 -28.265265) (xy 233.095808 -28.336139) (xy 233.096308 -28.3718)
			(xy 233.095808 -28.407461) (xy 239.445792 -28.407461) (xy 239.445792 -28.336139) (xy 239.453778 -28.265265)
			(xy 239.469648 -28.19573) (xy 239.493205 -28.12841) (xy 239.52415 -28.064151) (xy 239.562096 -28.00376)
			(xy 239.606565 -27.947998) (xy 239.656998 -27.897565) (xy 239.71276 -27.853096) (xy 239.773151 -27.81515)
			(xy 239.83741 -27.784205) (xy 239.90473 -27.760648) (xy 239.974265 -27.744778) (xy 240.045139 -27.736792)
			(xy 240.116461 -27.736792) (xy 240.187335 -27.744778) (xy 240.25687 -27.760648) (xy 240.32419 -27.784205)
			(xy 240.388449 -27.81515) (xy 240.44884 -27.853096) (xy 240.504602 -27.897565) (xy 240.555035 -27.947998)
			(xy 240.599504 -28.00376) (xy 240.63745 -28.064151) (xy 240.668395 -28.12841) (xy 240.691952 -28.19573)
			(xy 240.707822 -28.265265) (xy 240.715808 -28.336139) (xy 240.716308 -28.3718) (xy 240.715808 -28.407461)
			(xy 247.065792 -28.407461) (xy 247.065792 -28.336139) (xy 247.073778 -28.265265) (xy 247.089648 -28.19573)
			(xy 247.113205 -28.12841) (xy 247.14415 -28.064151) (xy 247.182096 -28.00376) (xy 247.226565 -27.947998)
			(xy 247.276998 -27.897565) (xy 247.33276 -27.853096) (xy 247.393151 -27.81515) (xy 247.45741 -27.784205)
			(xy 247.52473 -27.760648) (xy 247.594265 -27.744778) (xy 247.665139 -27.736792) (xy 247.736461 -27.736792)
			(xy 247.807335 -27.744778) (xy 247.87687 -27.760648) (xy 247.94419 -27.784205) (xy 248.008449 -27.81515)
			(xy 248.06884 -27.853096) (xy 248.124602 -27.897565) (xy 248.175035 -27.947998) (xy 248.219504 -28.00376)
			(xy 248.25745 -28.064151) (xy 248.288395 -28.12841) (xy 248.311952 -28.19573) (xy 248.327822 -28.265265)
			(xy 248.335808 -28.336139) (xy 248.336308 -28.3718) (xy 248.335808 -28.407461) (xy 254.685792 -28.407461)
			(xy 254.685792 -28.336139) (xy 254.693778 -28.265265) (xy 254.709648 -28.19573) (xy 254.733205 -28.12841)
			(xy 254.76415 -28.064151) (xy 254.802096 -28.00376) (xy 254.846565 -27.947998) (xy 254.896998 -27.897565)
			(xy 254.95276 -27.853096) (xy 255.013151 -27.81515) (xy 255.07741 -27.784205) (xy 255.14473 -27.760648)
			(xy 255.214265 -27.744778) (xy 255.285139 -27.736792) (xy 255.356461 -27.736792) (xy 255.427335 -27.744778)
			(xy 255.49687 -27.760648) (xy 255.56419 -27.784205) (xy 255.628449 -27.81515) (xy 255.68884 -27.853096)
			(xy 255.744602 -27.897565) (xy 255.795035 -27.947998) (xy 255.839504 -28.00376) (xy 255.87745 -28.064151)
			(xy 255.908395 -28.12841) (xy 255.931952 -28.19573) (xy 255.947822 -28.265265) (xy 255.952396 -28.305861)
			(xy 262.813792 -28.305861) (xy 262.813792 -28.234539) (xy 262.821778 -28.163665) (xy 262.837648 -28.09413)
			(xy 262.861205 -28.02681) (xy 262.89215 -27.962551) (xy 262.930096 -27.90216) (xy 262.974565 -27.846398)
			(xy 263.024998 -27.795965) (xy 263.08076 -27.751496) (xy 263.141151 -27.71355) (xy 263.20541 -27.682605)
			(xy 263.27273 -27.659048) (xy 263.342265 -27.643178) (xy 263.413139 -27.635192) (xy 263.484461 -27.635192)
			(xy 263.555335 -27.643178) (xy 263.62487 -27.659048) (xy 263.69219 -27.682605) (xy 263.756449 -27.71355)
			(xy 263.81684 -27.751496) (xy 263.872602 -27.795965) (xy 263.923035 -27.846398) (xy 263.967504 -27.90216)
			(xy 264.00545 -27.962551) (xy 264.036395 -28.02681) (xy 264.059952 -28.09413) (xy 264.075822 -28.163665)
			(xy 264.083808 -28.234539) (xy 264.084308 -28.2702) (xy 264.083808 -28.305861) (xy 270.433792 -28.305861)
			(xy 270.433792 -28.234539) (xy 270.441778 -28.163665) (xy 270.457648 -28.09413) (xy 270.481205 -28.02681)
			(xy 270.51215 -27.962551) (xy 270.550096 -27.90216) (xy 270.594565 -27.846398) (xy 270.644998 -27.795965)
			(xy 270.70076 -27.751496) (xy 270.761151 -27.71355) (xy 270.82541 -27.682605) (xy 270.89273 -27.659048)
			(xy 270.962265 -27.643178) (xy 271.033139 -27.635192) (xy 271.104461 -27.635192) (xy 271.175335 -27.643178)
			(xy 271.24487 -27.659048) (xy 271.31219 -27.682605) (xy 271.376449 -27.71355) (xy 271.43684 -27.751496)
			(xy 271.492602 -27.795965) (xy 271.543035 -27.846398) (xy 271.587504 -27.90216) (xy 271.62545 -27.962551)
			(xy 271.656395 -28.02681) (xy 271.679952 -28.09413) (xy 271.695822 -28.163665) (xy 271.703808 -28.234539)
			(xy 271.704308 -28.2702) (xy 271.703808 -28.305861) (xy 278.053792 -28.305861) (xy 278.053792 -28.234539)
			(xy 278.061778 -28.163665) (xy 278.077648 -28.09413) (xy 278.101205 -28.02681) (xy 278.13215 -27.962551)
			(xy 278.170096 -27.90216) (xy 278.214565 -27.846398) (xy 278.264998 -27.795965) (xy 278.32076 -27.751496)
			(xy 278.381151 -27.71355) (xy 278.44541 -27.682605) (xy 278.51273 -27.659048) (xy 278.582265 -27.643178)
			(xy 278.653139 -27.635192) (xy 278.724461 -27.635192) (xy 278.795335 -27.643178) (xy 278.86487 -27.659048)
			(xy 278.93219 -27.682605) (xy 278.996449 -27.71355) (xy 279.05684 -27.751496) (xy 279.112602 -27.795965)
			(xy 279.163035 -27.846398) (xy 279.207504 -27.90216) (xy 279.24545 -27.962551) (xy 279.276395 -28.02681)
			(xy 279.299952 -28.09413) (xy 279.315822 -28.163665) (xy 279.323808 -28.234539) (xy 279.324308 -28.2702)
			(xy 279.323808 -28.305861) (xy 285.673792 -28.305861) (xy 285.673792 -28.234539) (xy 285.681778 -28.163665)
			(xy 285.697648 -28.09413) (xy 285.721205 -28.02681) (xy 285.75215 -27.962551) (xy 285.790096 -27.90216)
			(xy 285.834565 -27.846398) (xy 285.884998 -27.795965) (xy 285.94076 -27.751496) (xy 286.001151 -27.71355)
			(xy 286.06541 -27.682605) (xy 286.13273 -27.659048) (xy 286.202265 -27.643178) (xy 286.273139 -27.635192)
			(xy 286.344461 -27.635192) (xy 286.415335 -27.643178) (xy 286.48487 -27.659048) (xy 286.55219 -27.682605)
			(xy 286.616449 -27.71355) (xy 286.67684 -27.751496) (xy 286.732602 -27.795965) (xy 286.783035 -27.846398)
			(xy 286.827504 -27.90216) (xy 286.86545 -27.962551) (xy 286.896395 -28.02681) (xy 286.919952 -28.09413)
			(xy 286.935822 -28.163665) (xy 286.943808 -28.234539) (xy 286.944308 -28.2702) (xy 286.943808 -28.305861)
			(xy 286.935822 -28.376735) (xy 286.919952 -28.44627) (xy 286.896395 -28.51359) (xy 286.86545 -28.577849)
			(xy 286.827504 -28.63824) (xy 286.783035 -28.694002) (xy 286.732602 -28.744435) (xy 286.67684 -28.788904)
			(xy 286.616449 -28.82685) (xy 286.55219 -28.857795) (xy 286.48487 -28.881352) (xy 286.415335 -28.897222)
			(xy 286.344461 -28.905208) (xy 286.273139 -28.905208) (xy 286.202265 -28.897222) (xy 286.13273 -28.881352)
			(xy 286.06541 -28.857795) (xy 286.001151 -28.82685) (xy 285.94076 -28.788904) (xy 285.884998 -28.744435)
			(xy 285.834565 -28.694002) (xy 285.790096 -28.63824) (xy 285.75215 -28.577849) (xy 285.721205 -28.51359)
			(xy 285.697648 -28.44627) (xy 285.681778 -28.376735) (xy 285.673792 -28.305861) (xy 279.323808 -28.305861)
			(xy 279.315822 -28.376735) (xy 279.299952 -28.44627) (xy 279.276395 -28.51359) (xy 279.24545 -28.577849)
			(xy 279.207504 -28.63824) (xy 279.163035 -28.694002) (xy 279.112602 -28.744435) (xy 279.05684 -28.788904)
			(xy 278.996449 -28.82685) (xy 278.93219 -28.857795) (xy 278.86487 -28.881352) (xy 278.795335 -28.897222)
			(xy 278.724461 -28.905208) (xy 278.653139 -28.905208) (xy 278.582265 -28.897222) (xy 278.51273 -28.881352)
			(xy 278.44541 -28.857795) (xy 278.381151 -28.82685) (xy 278.32076 -28.788904) (xy 278.264998 -28.744435)
			(xy 278.214565 -28.694002) (xy 278.170096 -28.63824) (xy 278.13215 -28.577849) (xy 278.101205 -28.51359)
			(xy 278.077648 -28.44627) (xy 278.061778 -28.376735) (xy 278.053792 -28.305861) (xy 271.703808 -28.305861)
			(xy 271.695822 -28.376735) (xy 271.679952 -28.44627) (xy 271.656395 -28.51359) (xy 271.62545 -28.577849)
			(xy 271.587504 -28.63824) (xy 271.543035 -28.694002) (xy 271.492602 -28.744435) (xy 271.43684 -28.788904)
			(xy 271.376449 -28.82685) (xy 271.31219 -28.857795) (xy 271.24487 -28.881352) (xy 271.175335 -28.897222)
			(xy 271.104461 -28.905208) (xy 271.033139 -28.905208) (xy 270.962265 -28.897222) (xy 270.89273 -28.881352)
			(xy 270.82541 -28.857795) (xy 270.761151 -28.82685) (xy 270.70076 -28.788904) (xy 270.644998 -28.744435)
			(xy 270.594565 -28.694002) (xy 270.550096 -28.63824) (xy 270.51215 -28.577849) (xy 270.481205 -28.51359)
			(xy 270.457648 -28.44627) (xy 270.441778 -28.376735) (xy 270.433792 -28.305861) (xy 264.083808 -28.305861)
			(xy 264.075822 -28.376735) (xy 264.059952 -28.44627) (xy 264.036395 -28.51359) (xy 264.00545 -28.577849)
			(xy 263.967504 -28.63824) (xy 263.923035 -28.694002) (xy 263.872602 -28.744435) (xy 263.81684 -28.788904)
			(xy 263.756449 -28.82685) (xy 263.69219 -28.857795) (xy 263.62487 -28.881352) (xy 263.555335 -28.897222)
			(xy 263.484461 -28.905208) (xy 263.413139 -28.905208) (xy 263.342265 -28.897222) (xy 263.27273 -28.881352)
			(xy 263.20541 -28.857795) (xy 263.141151 -28.82685) (xy 263.08076 -28.788904) (xy 263.024998 -28.744435)
			(xy 262.974565 -28.694002) (xy 262.930096 -28.63824) (xy 262.89215 -28.577849) (xy 262.861205 -28.51359)
			(xy 262.837648 -28.44627) (xy 262.821778 -28.376735) (xy 262.813792 -28.305861) (xy 255.952396 -28.305861)
			(xy 255.955808 -28.336139) (xy 255.956308 -28.3718) (xy 255.955808 -28.407461) (xy 255.947822 -28.478335)
			(xy 255.931952 -28.54787) (xy 255.908395 -28.61519) (xy 255.87745 -28.679449) (xy 255.839504 -28.73984)
			(xy 255.795035 -28.795602) (xy 255.744602 -28.846035) (xy 255.68884 -28.890504) (xy 255.628449 -28.92845)
			(xy 255.56419 -28.959395) (xy 255.49687 -28.982952) (xy 255.427335 -28.998822) (xy 255.356461 -29.006808)
			(xy 255.285139 -29.006808) (xy 255.214265 -28.998822) (xy 255.14473 -28.982952) (xy 255.07741 -28.959395)
			(xy 255.013151 -28.92845) (xy 254.95276 -28.890504) (xy 254.896998 -28.846035) (xy 254.846565 -28.795602)
			(xy 254.802096 -28.73984) (xy 254.76415 -28.679449) (xy 254.733205 -28.61519) (xy 254.709648 -28.54787)
			(xy 254.693778 -28.478335) (xy 254.685792 -28.407461) (xy 248.335808 -28.407461) (xy 248.327822 -28.478335)
			(xy 248.311952 -28.54787) (xy 248.288395 -28.61519) (xy 248.25745 -28.679449) (xy 248.219504 -28.73984)
			(xy 248.175035 -28.795602) (xy 248.124602 -28.846035) (xy 248.06884 -28.890504) (xy 248.008449 -28.92845)
			(xy 247.94419 -28.959395) (xy 247.87687 -28.982952) (xy 247.807335 -28.998822) (xy 247.736461 -29.006808)
			(xy 247.665139 -29.006808) (xy 247.594265 -28.998822) (xy 247.52473 -28.982952) (xy 247.45741 -28.959395)
			(xy 247.393151 -28.92845) (xy 247.33276 -28.890504) (xy 247.276998 -28.846035) (xy 247.226565 -28.795602)
			(xy 247.182096 -28.73984) (xy 247.14415 -28.679449) (xy 247.113205 -28.61519) (xy 247.089648 -28.54787)
			(xy 247.073778 -28.478335) (xy 247.065792 -28.407461) (xy 240.715808 -28.407461) (xy 240.707822 -28.478335)
			(xy 240.691952 -28.54787) (xy 240.668395 -28.61519) (xy 240.63745 -28.679449) (xy 240.599504 -28.73984)
			(xy 240.555035 -28.795602) (xy 240.504602 -28.846035) (xy 240.44884 -28.890504) (xy 240.388449 -28.92845)
			(xy 240.32419 -28.959395) (xy 240.25687 -28.982952) (xy 240.187335 -28.998822) (xy 240.116461 -29.006808)
			(xy 240.045139 -29.006808) (xy 239.974265 -28.998822) (xy 239.90473 -28.982952) (xy 239.83741 -28.959395)
			(xy 239.773151 -28.92845) (xy 239.71276 -28.890504) (xy 239.656998 -28.846035) (xy 239.606565 -28.795602)
			(xy 239.562096 -28.73984) (xy 239.52415 -28.679449) (xy 239.493205 -28.61519) (xy 239.469648 -28.54787)
			(xy 239.453778 -28.478335) (xy 239.445792 -28.407461) (xy 233.095808 -28.407461) (xy 233.087822 -28.478335)
			(xy 233.071952 -28.54787) (xy 233.048395 -28.61519) (xy 233.01745 -28.679449) (xy 232.979504 -28.73984)
			(xy 232.935035 -28.795602) (xy 232.884602 -28.846035) (xy 232.82884 -28.890504) (xy 232.768449 -28.92845)
			(xy 232.70419 -28.959395) (xy 232.63687 -28.982952) (xy 232.567335 -28.998822) (xy 232.496461 -29.006808)
			(xy 232.425139 -29.006808) (xy 232.354265 -28.998822) (xy 232.28473 -28.982952) (xy 232.21741 -28.959395)
			(xy 232.153151 -28.92845) (xy 232.09276 -28.890504) (xy 232.036998 -28.846035) (xy 231.986565 -28.795602)
			(xy 231.942096 -28.73984) (xy 231.90415 -28.679449) (xy 231.873205 -28.61519) (xy 231.849648 -28.54787)
			(xy 231.833778 -28.478335) (xy 231.825792 -28.407461) (xy 225.475808 -28.407461) (xy 225.467822 -28.478335)
			(xy 225.451952 -28.54787) (xy 225.428395 -28.61519) (xy 225.39745 -28.679449) (xy 225.359504 -28.73984)
			(xy 225.315035 -28.795602) (xy 225.264602 -28.846035) (xy 225.20884 -28.890504) (xy 225.148449 -28.92845)
			(xy 225.08419 -28.959395) (xy 225.01687 -28.982952) (xy 224.947335 -28.998822) (xy 224.876461 -29.006808)
			(xy 224.805139 -29.006808) (xy 224.734265 -28.998822) (xy 224.66473 -28.982952) (xy 224.59741 -28.959395)
			(xy 224.533151 -28.92845) (xy 224.47276 -28.890504) (xy 224.416998 -28.846035) (xy 224.366565 -28.795602)
			(xy 224.322096 -28.73984) (xy 224.28415 -28.679449) (xy 224.253205 -28.61519) (xy 224.229648 -28.54787)
			(xy 224.213778 -28.478335) (xy 224.205792 -28.407461) (xy 217.855808 -28.407461) (xy 217.847822 -28.478335)
			(xy 217.831952 -28.54787) (xy 217.808395 -28.61519) (xy 217.77745 -28.679449) (xy 217.739504 -28.73984)
			(xy 217.695035 -28.795602) (xy 217.644602 -28.846035) (xy 217.58884 -28.890504) (xy 217.528449 -28.92845)
			(xy 217.46419 -28.959395) (xy 217.39687 -28.982952) (xy 217.327335 -28.998822) (xy 217.256461 -29.006808)
			(xy 217.185139 -29.006808) (xy 217.114265 -28.998822) (xy 217.04473 -28.982952) (xy 216.97741 -28.959395)
			(xy 216.913151 -28.92845) (xy 216.85276 -28.890504) (xy 216.796998 -28.846035) (xy 216.746565 -28.795602)
			(xy 216.702096 -28.73984) (xy 216.66415 -28.679449) (xy 216.633205 -28.61519) (xy 216.609648 -28.54787)
			(xy 216.593778 -28.478335) (xy 216.585792 -28.407461) (xy 210.235808 -28.407461) (xy 210.227822 -28.478335)
			(xy 210.211952 -28.54787) (xy 210.188395 -28.61519) (xy 210.15745 -28.679449) (xy 210.119504 -28.73984)
			(xy 210.075035 -28.795602) (xy 210.024602 -28.846035) (xy 209.96884 -28.890504) (xy 209.908449 -28.92845)
			(xy 209.84419 -28.959395) (xy 209.77687 -28.982952) (xy 209.707335 -28.998822) (xy 209.636461 -29.006808)
			(xy 209.565139 -29.006808) (xy 209.494265 -28.998822) (xy 209.42473 -28.982952) (xy 209.35741 -28.959395)
			(xy 209.293151 -28.92845) (xy 209.23276 -28.890504) (xy 209.176998 -28.846035) (xy 209.126565 -28.795602)
			(xy 209.082096 -28.73984) (xy 209.04415 -28.679449) (xy 209.013205 -28.61519) (xy 208.989648 -28.54787)
			(xy 208.973778 -28.478335) (xy 208.965792 -28.407461) (xy 203.8477 -28.407461) (xy 203.8477 -47.6123)
			(xy 205.360016 -49.124616) (xy 205.376445 -49.14033) (xy 205.413797 -49.16624) (xy 205.455163 -49.185091)
			(xy 205.499222 -49.196283) (xy 205.544569 -49.199458) (xy 205.589758 -49.194515) (xy 205.633346 -49.181612)
			(xy 205.673944 -49.16116) (xy 205.710256 -49.133812) (xy 205.741124 -49.10044) (xy 205.765562 -49.06211)
			(xy 205.782791 -49.020043) (xy 205.792262 -48.975582) (xy 205.793672 -48.930146) (xy 205.786977 -48.885183)
			(xy 205.780132 -48.863504) (xy 205.752736 -48.78119) (xy 205.703855 -48.614713) (xy 205.661804 -48.446382)
			(xy 205.626652 -48.276475) (xy 205.598458 -48.105277) (xy 205.577269 -47.933071) (xy 205.56312 -47.760144)
			(xy 205.556035 -47.586784) (xy 205.555596 -47.500032) (xy 205.555596 -41.500044) (xy 205.556102 -41.407222)
			(xy 205.5642 -41.221753) (xy 205.58038 -41.036815) (xy 205.604611 -40.852758) (xy 205.636848 -40.669933)
			(xy 205.677029 -40.488689) (xy 205.725078 -40.30937) (xy 205.780902 -40.132317) (xy 205.844396 -39.957868)
			(xy 205.91544 -39.786354) (xy 205.993897 -39.618103) (xy 206.079618 -39.453434) (xy 206.17244 -39.29266)
			(xy 206.272187 -39.136089) (xy 206.378669 -38.984018) (xy 206.491682 -38.836736) (xy 206.611013 -38.694523)
			(xy 206.736433 -38.557651) (xy 206.867703 -38.426381) (xy 207.004575 -38.300961) (xy 207.146788 -38.18163)
			(xy 207.29407 -38.068617) (xy 207.446141 -37.962135) (xy 207.602712 -37.862388) (xy 207.763486 -37.769566)
			(xy 207.928155 -37.683845) (xy 208.096406 -37.605388) (xy 208.26792 -37.534344) (xy 208.442369 -37.47085)
			(xy 208.619422 -37.415026) (xy 208.798741 -37.366977) (xy 208.979985 -37.326796) (xy 209.16281 -37.294559)
			(xy 209.346867 -37.270328) (xy 209.531805 -37.254148) (xy 209.717274 -37.24605) (xy 209.902918 -37.24605)
			(xy 210.088387 -37.254148) (xy 210.273325 -37.270328) (xy 210.457382 -37.294559) (xy 210.640207 -37.326796)
			(xy 210.821451 -37.366977) (xy 211.00077 -37.415026) (xy 211.177823 -37.47085) (xy 211.352272 -37.534344)
			(xy 211.523786 -37.605388) (xy 211.692037 -37.683845) (xy 211.856706 -37.769566) (xy 212.01748 -37.862388)
			(xy 212.174051 -37.962135) (xy 212.326122 -38.068617) (xy 212.473404 -38.18163) (xy 212.615617 -38.300961)
			(xy 212.752489 -38.426381) (xy 212.883759 -38.557651) (xy 213.009179 -38.694523) (xy 213.12851 -38.836736)
			(xy 213.241523 -38.984018) (xy 213.348005 -39.136089) (xy 213.447752 -39.29266) (xy 213.540574 -39.453434)
			(xy 213.626295 -39.618103) (xy 213.704752 -39.786354) (xy 213.775796 -39.957868) (xy 213.83929 -40.132317)
			(xy 213.895114 -40.30937) (xy 213.943163 -40.488689) (xy 213.983344 -40.669933) (xy 214.015581 -40.852758)
			(xy 214.039812 -41.036815) (xy 214.055992 -41.221753) (xy 214.06409 -41.407222) (xy 214.064596 -41.500044)
			(xy 214.064596 -43.977661) (xy 216.636592 -43.977661) (xy 216.636592 -43.906339) (xy 216.644578 -43.835465)
			(xy 216.660448 -43.76593) (xy 216.684005 -43.69861) (xy 216.71495 -43.634351) (xy 216.752896 -43.57396)
			(xy 216.797365 -43.518198) (xy 216.847798 -43.467765) (xy 216.90356 -43.423296) (xy 216.963951 -43.38535)
			(xy 217.02821 -43.354405) (xy 217.09553 -43.330848) (xy 217.165065 -43.314978) (xy 217.235939 -43.306992)
			(xy 217.307261 -43.306992) (xy 217.378135 -43.314978) (xy 217.44767 -43.330848) (xy 217.51499 -43.354405)
			(xy 217.579249 -43.38535) (xy 217.63964 -43.423296) (xy 217.695402 -43.467765) (xy 217.745835 -43.518198)
			(xy 217.790304 -43.57396) (xy 217.82825 -43.634351) (xy 217.859195 -43.69861) (xy 217.882752 -43.76593)
			(xy 217.898622 -43.835465) (xy 217.906608 -43.906339) (xy 217.907108 -43.942) (xy 217.906608 -43.977661)
			(xy 224.256592 -43.977661) (xy 224.256592 -43.906339) (xy 224.264578 -43.835465) (xy 224.280448 -43.76593)
			(xy 224.304005 -43.69861) (xy 224.33495 -43.634351) (xy 224.372896 -43.57396) (xy 224.417365 -43.518198)
			(xy 224.467798 -43.467765) (xy 224.52356 -43.423296) (xy 224.583951 -43.38535) (xy 224.64821 -43.354405)
			(xy 224.71553 -43.330848) (xy 224.785065 -43.314978) (xy 224.855939 -43.306992) (xy 224.927261 -43.306992)
			(xy 224.998135 -43.314978) (xy 225.06767 -43.330848) (xy 225.13499 -43.354405) (xy 225.199249 -43.38535)
			(xy 225.25964 -43.423296) (xy 225.315402 -43.467765) (xy 225.365835 -43.518198) (xy 225.410304 -43.57396)
			(xy 225.44825 -43.634351) (xy 225.479195 -43.69861) (xy 225.502752 -43.76593) (xy 225.518622 -43.835465)
			(xy 225.526608 -43.906339) (xy 225.527108 -43.942) (xy 225.526608 -43.977661) (xy 231.876592 -43.977661)
			(xy 231.876592 -43.906339) (xy 231.884578 -43.835465) (xy 231.900448 -43.76593) (xy 231.924005 -43.69861)
			(xy 231.95495 -43.634351) (xy 231.992896 -43.57396) (xy 232.037365 -43.518198) (xy 232.087798 -43.467765)
			(xy 232.14356 -43.423296) (xy 232.203951 -43.38535) (xy 232.26821 -43.354405) (xy 232.33553 -43.330848)
			(xy 232.405065 -43.314978) (xy 232.475939 -43.306992) (xy 232.547261 -43.306992) (xy 232.618135 -43.314978)
			(xy 232.68767 -43.330848) (xy 232.75499 -43.354405) (xy 232.819249 -43.38535) (xy 232.87964 -43.423296)
			(xy 232.935402 -43.467765) (xy 232.985835 -43.518198) (xy 233.030304 -43.57396) (xy 233.06825 -43.634351)
			(xy 233.099195 -43.69861) (xy 233.122752 -43.76593) (xy 233.138622 -43.835465) (xy 233.146608 -43.906339)
			(xy 233.147108 -43.942) (xy 233.146608 -43.977661) (xy 239.496592 -43.977661) (xy 239.496592 -43.906339)
			(xy 239.504578 -43.835465) (xy 239.520448 -43.76593) (xy 239.544005 -43.69861) (xy 239.57495 -43.634351)
			(xy 239.612896 -43.57396) (xy 239.657365 -43.518198) (xy 239.707798 -43.467765) (xy 239.76356 -43.423296)
			(xy 239.823951 -43.38535) (xy 239.88821 -43.354405) (xy 239.95553 -43.330848) (xy 240.025065 -43.314978)
			(xy 240.095939 -43.306992) (xy 240.167261 -43.306992) (xy 240.238135 -43.314978) (xy 240.30767 -43.330848)
			(xy 240.37499 -43.354405) (xy 240.439249 -43.38535) (xy 240.49964 -43.423296) (xy 240.555402 -43.467765)
			(xy 240.605835 -43.518198) (xy 240.650304 -43.57396) (xy 240.68825 -43.634351) (xy 240.719195 -43.69861)
			(xy 240.742752 -43.76593) (xy 240.758622 -43.835465) (xy 240.766608 -43.906339) (xy 240.767108 -43.942)
			(xy 240.766608 -43.977661) (xy 247.116592 -43.977661) (xy 247.116592 -43.906339) (xy 247.124578 -43.835465)
			(xy 247.140448 -43.76593) (xy 247.164005 -43.69861) (xy 247.19495 -43.634351) (xy 247.232896 -43.57396)
			(xy 247.277365 -43.518198) (xy 247.327798 -43.467765) (xy 247.38356 -43.423296) (xy 247.443951 -43.38535)
			(xy 247.50821 -43.354405) (xy 247.57553 -43.330848) (xy 247.645065 -43.314978) (xy 247.715939 -43.306992)
			(xy 247.787261 -43.306992) (xy 247.858135 -43.314978) (xy 247.92767 -43.330848) (xy 247.99499 -43.354405)
			(xy 248.059249 -43.38535) (xy 248.11964 -43.423296) (xy 248.175402 -43.467765) (xy 248.225835 -43.518198)
			(xy 248.270304 -43.57396) (xy 248.30825 -43.634351) (xy 248.339195 -43.69861) (xy 248.362752 -43.76593)
			(xy 248.378622 -43.835465) (xy 248.386608 -43.906339) (xy 248.387108 -43.942) (xy 248.386608 -43.977661)
			(xy 254.736592 -43.977661) (xy 254.736592 -43.906339) (xy 254.744578 -43.835465) (xy 254.760448 -43.76593)
			(xy 254.784005 -43.69861) (xy 254.81495 -43.634351) (xy 254.852896 -43.57396) (xy 254.897365 -43.518198)
			(xy 254.947798 -43.467765) (xy 255.00356 -43.423296) (xy 255.063951 -43.38535) (xy 255.12821 -43.354405)
			(xy 255.19553 -43.330848) (xy 255.265065 -43.314978) (xy 255.335939 -43.306992) (xy 255.407261 -43.306992)
			(xy 255.478135 -43.314978) (xy 255.54767 -43.330848) (xy 255.61499 -43.354405) (xy 255.679249 -43.38535)
			(xy 255.73964 -43.423296) (xy 255.795402 -43.467765) (xy 255.845835 -43.518198) (xy 255.890304 -43.57396)
			(xy 255.92825 -43.634351) (xy 255.959195 -43.69861) (xy 255.982752 -43.76593) (xy 255.998622 -43.835465)
			(xy 256.006608 -43.906339) (xy 256.007108 -43.942) (xy 256.006608 -43.977661) (xy 262.356592 -43.977661)
			(xy 262.356592 -43.906339) (xy 262.364578 -43.835465) (xy 262.380448 -43.76593) (xy 262.404005 -43.69861)
			(xy 262.43495 -43.634351) (xy 262.472896 -43.57396) (xy 262.517365 -43.518198) (xy 262.567798 -43.467765)
			(xy 262.62356 -43.423296) (xy 262.683951 -43.38535) (xy 262.74821 -43.354405) (xy 262.81553 -43.330848)
			(xy 262.885065 -43.314978) (xy 262.955939 -43.306992) (xy 263.027261 -43.306992) (xy 263.098135 -43.314978)
			(xy 263.16767 -43.330848) (xy 263.23499 -43.354405) (xy 263.299249 -43.38535) (xy 263.35964 -43.423296)
			(xy 263.415402 -43.467765) (xy 263.465835 -43.518198) (xy 263.510304 -43.57396) (xy 263.54825 -43.634351)
			(xy 263.579195 -43.69861) (xy 263.602752 -43.76593) (xy 263.618622 -43.835465) (xy 263.623196 -43.876061)
			(xy 270.484592 -43.876061) (xy 270.484592 -43.804739) (xy 270.492578 -43.733865) (xy 270.508448 -43.66433)
			(xy 270.532005 -43.59701) (xy 270.56295 -43.532751) (xy 270.600896 -43.47236) (xy 270.645365 -43.416598)
			(xy 270.695798 -43.366165) (xy 270.75156 -43.321696) (xy 270.811951 -43.28375) (xy 270.87621 -43.252805)
			(xy 270.94353 -43.229248) (xy 271.013065 -43.213378) (xy 271.083939 -43.205392) (xy 271.155261 -43.205392)
			(xy 271.226135 -43.213378) (xy 271.29567 -43.229248) (xy 271.36299 -43.252805) (xy 271.427249 -43.28375)
			(xy 271.48764 -43.321696) (xy 271.543402 -43.366165) (xy 271.593835 -43.416598) (xy 271.638304 -43.47236)
			(xy 271.67625 -43.532751) (xy 271.707195 -43.59701) (xy 271.730752 -43.66433) (xy 271.746622 -43.733865)
			(xy 271.754608 -43.804739) (xy 271.755108 -43.8404) (xy 271.754608 -43.876061) (xy 278.104592 -43.876061)
			(xy 278.104592 -43.804739) (xy 278.112578 -43.733865) (xy 278.128448 -43.66433) (xy 278.152005 -43.59701)
			(xy 278.18295 -43.532751) (xy 278.220896 -43.47236) (xy 278.265365 -43.416598) (xy 278.315798 -43.366165)
			(xy 278.37156 -43.321696) (xy 278.431951 -43.28375) (xy 278.49621 -43.252805) (xy 278.56353 -43.229248)
			(xy 278.633065 -43.213378) (xy 278.703939 -43.205392) (xy 278.775261 -43.205392) (xy 278.846135 -43.213378)
			(xy 278.91567 -43.229248) (xy 278.98299 -43.252805) (xy 279.047249 -43.28375) (xy 279.10764 -43.321696)
			(xy 279.163402 -43.366165) (xy 279.213835 -43.416598) (xy 279.258304 -43.47236) (xy 279.29625 -43.532751)
			(xy 279.327195 -43.59701) (xy 279.350752 -43.66433) (xy 279.366622 -43.733865) (xy 279.374608 -43.804739)
			(xy 279.375108 -43.8404) (xy 279.374608 -43.876061) (xy 285.724592 -43.876061) (xy 285.724592 -43.804739)
			(xy 285.732578 -43.733865) (xy 285.748448 -43.66433) (xy 285.772005 -43.59701) (xy 285.80295 -43.532751)
			(xy 285.840896 -43.47236) (xy 285.885365 -43.416598) (xy 285.935798 -43.366165) (xy 285.99156 -43.321696)
			(xy 286.051951 -43.28375) (xy 286.11621 -43.252805) (xy 286.18353 -43.229248) (xy 286.253065 -43.213378)
			(xy 286.323939 -43.205392) (xy 286.395261 -43.205392) (xy 286.466135 -43.213378) (xy 286.53567 -43.229248)
			(xy 286.60299 -43.252805) (xy 286.667249 -43.28375) (xy 286.72764 -43.321696) (xy 286.783402 -43.366165)
			(xy 286.833835 -43.416598) (xy 286.878304 -43.47236) (xy 286.91625 -43.532751) (xy 286.947195 -43.59701)
			(xy 286.970752 -43.66433) (xy 286.986622 -43.733865) (xy 286.994608 -43.804739) (xy 286.995108 -43.8404)
			(xy 286.994608 -43.876061) (xy 293.344592 -43.876061) (xy 293.344592 -43.804739) (xy 293.352578 -43.733865)
			(xy 293.368448 -43.66433) (xy 293.392005 -43.59701) (xy 293.42295 -43.532751) (xy 293.460896 -43.47236)
			(xy 293.505365 -43.416598) (xy 293.555798 -43.366165) (xy 293.61156 -43.321696) (xy 293.671951 -43.28375)
			(xy 293.73621 -43.252805) (xy 293.80353 -43.229248) (xy 293.873065 -43.213378) (xy 293.943939 -43.205392)
			(xy 294.015261 -43.205392) (xy 294.086135 -43.213378) (xy 294.15567 -43.229248) (xy 294.22299 -43.252805)
			(xy 294.287249 -43.28375) (xy 294.34764 -43.321696) (xy 294.403402 -43.366165) (xy 294.453835 -43.416598)
			(xy 294.498304 -43.47236) (xy 294.53625 -43.532751) (xy 294.567195 -43.59701) (xy 294.590752 -43.66433)
			(xy 294.606622 -43.733865) (xy 294.614608 -43.804739) (xy 294.615108 -43.8404) (xy 294.614608 -43.876061)
			(xy 294.606622 -43.946935) (xy 294.590752 -44.01647) (xy 294.567195 -44.08379) (xy 294.53625 -44.148049)
			(xy 294.498304 -44.20844) (xy 294.453835 -44.264202) (xy 294.403402 -44.314635) (xy 294.34764 -44.359104)
			(xy 294.287249 -44.39705) (xy 294.22299 -44.427995) (xy 294.15567 -44.451552) (xy 294.086135 -44.467422)
			(xy 294.015261 -44.475408) (xy 293.943939 -44.475408) (xy 293.873065 -44.467422) (xy 293.80353 -44.451552)
			(xy 293.73621 -44.427995) (xy 293.671951 -44.39705) (xy 293.61156 -44.359104) (xy 293.555798 -44.314635)
			(xy 293.505365 -44.264202) (xy 293.460896 -44.20844) (xy 293.42295 -44.148049) (xy 293.392005 -44.08379)
			(xy 293.368448 -44.01647) (xy 293.352578 -43.946935) (xy 293.344592 -43.876061) (xy 286.994608 -43.876061)
			(xy 286.986622 -43.946935) (xy 286.970752 -44.01647) (xy 286.947195 -44.08379) (xy 286.91625 -44.148049)
			(xy 286.878304 -44.20844) (xy 286.833835 -44.264202) (xy 286.783402 -44.314635) (xy 286.72764 -44.359104)
			(xy 286.667249 -44.39705) (xy 286.60299 -44.427995) (xy 286.53567 -44.451552) (xy 286.466135 -44.467422)
			(xy 286.395261 -44.475408) (xy 286.323939 -44.475408) (xy 286.253065 -44.467422) (xy 286.18353 -44.451552)
			(xy 286.11621 -44.427995) (xy 286.051951 -44.39705) (xy 285.99156 -44.359104) (xy 285.935798 -44.314635)
			(xy 285.885365 -44.264202) (xy 285.840896 -44.20844) (xy 285.80295 -44.148049) (xy 285.772005 -44.08379)
			(xy 285.748448 -44.01647) (xy 285.732578 -43.946935) (xy 285.724592 -43.876061) (xy 279.374608 -43.876061)
			(xy 279.366622 -43.946935) (xy 279.350752 -44.01647) (xy 279.327195 -44.08379) (xy 279.29625 -44.148049)
			(xy 279.258304 -44.20844) (xy 279.213835 -44.264202) (xy 279.163402 -44.314635) (xy 279.10764 -44.359104)
			(xy 279.047249 -44.39705) (xy 278.98299 -44.427995) (xy 278.91567 -44.451552) (xy 278.846135 -44.467422)
			(xy 278.775261 -44.475408) (xy 278.703939 -44.475408) (xy 278.633065 -44.467422) (xy 278.56353 -44.451552)
			(xy 278.49621 -44.427995) (xy 278.431951 -44.39705) (xy 278.37156 -44.359104) (xy 278.315798 -44.314635)
			(xy 278.265365 -44.264202) (xy 278.220896 -44.20844) (xy 278.18295 -44.148049) (xy 278.152005 -44.08379)
			(xy 278.128448 -44.01647) (xy 278.112578 -43.946935) (xy 278.104592 -43.876061) (xy 271.754608 -43.876061)
			(xy 271.746622 -43.946935) (xy 271.730752 -44.01647) (xy 271.707195 -44.08379) (xy 271.67625 -44.148049)
			(xy 271.638304 -44.20844) (xy 271.593835 -44.264202) (xy 271.543402 -44.314635) (xy 271.48764 -44.359104)
			(xy 271.427249 -44.39705) (xy 271.36299 -44.427995) (xy 271.29567 -44.451552) (xy 271.226135 -44.467422)
			(xy 271.155261 -44.475408) (xy 271.083939 -44.475408) (xy 271.013065 -44.467422) (xy 270.94353 -44.451552)
			(xy 270.87621 -44.427995) (xy 270.811951 -44.39705) (xy 270.75156 -44.359104) (xy 270.695798 -44.314635)
			(xy 270.645365 -44.264202) (xy 270.600896 -44.20844) (xy 270.56295 -44.148049) (xy 270.532005 -44.08379)
			(xy 270.508448 -44.01647) (xy 270.492578 -43.946935) (xy 270.484592 -43.876061) (xy 263.623196 -43.876061)
			(xy 263.626608 -43.906339) (xy 263.627108 -43.942) (xy 263.626608 -43.977661) (xy 263.618622 -44.048535)
			(xy 263.602752 -44.11807) (xy 263.579195 -44.18539) (xy 263.54825 -44.249649) (xy 263.510304 -44.31004)
			(xy 263.465835 -44.365802) (xy 263.415402 -44.416235) (xy 263.35964 -44.460704) (xy 263.299249 -44.49865)
			(xy 263.23499 -44.529595) (xy 263.16767 -44.553152) (xy 263.098135 -44.569022) (xy 263.027261 -44.577008)
			(xy 262.955939 -44.577008) (xy 262.885065 -44.569022) (xy 262.81553 -44.553152) (xy 262.74821 -44.529595)
			(xy 262.683951 -44.49865) (xy 262.62356 -44.460704) (xy 262.567798 -44.416235) (xy 262.517365 -44.365802)
			(xy 262.472896 -44.31004) (xy 262.43495 -44.249649) (xy 262.404005 -44.18539) (xy 262.380448 -44.11807)
			(xy 262.364578 -44.048535) (xy 262.356592 -43.977661) (xy 256.006608 -43.977661) (xy 255.998622 -44.048535)
			(xy 255.982752 -44.11807) (xy 255.959195 -44.18539) (xy 255.92825 -44.249649) (xy 255.890304 -44.31004)
			(xy 255.845835 -44.365802) (xy 255.795402 -44.416235) (xy 255.73964 -44.460704) (xy 255.679249 -44.49865)
			(xy 255.61499 -44.529595) (xy 255.54767 -44.553152) (xy 255.478135 -44.569022) (xy 255.407261 -44.577008)
			(xy 255.335939 -44.577008) (xy 255.265065 -44.569022) (xy 255.19553 -44.553152) (xy 255.12821 -44.529595)
			(xy 255.063951 -44.49865) (xy 255.00356 -44.460704) (xy 254.947798 -44.416235) (xy 254.897365 -44.365802)
			(xy 254.852896 -44.31004) (xy 254.81495 -44.249649) (xy 254.784005 -44.18539) (xy 254.760448 -44.11807)
			(xy 254.744578 -44.048535) (xy 254.736592 -43.977661) (xy 248.386608 -43.977661) (xy 248.378622 -44.048535)
			(xy 248.362752 -44.11807) (xy 248.339195 -44.18539) (xy 248.30825 -44.249649) (xy 248.270304 -44.31004)
			(xy 248.225835 -44.365802) (xy 248.175402 -44.416235) (xy 248.11964 -44.460704) (xy 248.059249 -44.49865)
			(xy 247.99499 -44.529595) (xy 247.92767 -44.553152) (xy 247.858135 -44.569022) (xy 247.787261 -44.577008)
			(xy 247.715939 -44.577008) (xy 247.645065 -44.569022) (xy 247.57553 -44.553152) (xy 247.50821 -44.529595)
			(xy 247.443951 -44.49865) (xy 247.38356 -44.460704) (xy 247.327798 -44.416235) (xy 247.277365 -44.365802)
			(xy 247.232896 -44.31004) (xy 247.19495 -44.249649) (xy 247.164005 -44.18539) (xy 247.140448 -44.11807)
			(xy 247.124578 -44.048535) (xy 247.116592 -43.977661) (xy 240.766608 -43.977661) (xy 240.758622 -44.048535)
			(xy 240.742752 -44.11807) (xy 240.719195 -44.18539) (xy 240.68825 -44.249649) (xy 240.650304 -44.31004)
			(xy 240.605835 -44.365802) (xy 240.555402 -44.416235) (xy 240.49964 -44.460704) (xy 240.439249 -44.49865)
			(xy 240.37499 -44.529595) (xy 240.30767 -44.553152) (xy 240.238135 -44.569022) (xy 240.167261 -44.577008)
			(xy 240.095939 -44.577008) (xy 240.025065 -44.569022) (xy 239.95553 -44.553152) (xy 239.88821 -44.529595)
			(xy 239.823951 -44.49865) (xy 239.76356 -44.460704) (xy 239.707798 -44.416235) (xy 239.657365 -44.365802)
			(xy 239.612896 -44.31004) (xy 239.57495 -44.249649) (xy 239.544005 -44.18539) (xy 239.520448 -44.11807)
			(xy 239.504578 -44.048535) (xy 239.496592 -43.977661) (xy 233.146608 -43.977661) (xy 233.138622 -44.048535)
			(xy 233.122752 -44.11807) (xy 233.099195 -44.18539) (xy 233.06825 -44.249649) (xy 233.030304 -44.31004)
			(xy 232.985835 -44.365802) (xy 232.935402 -44.416235) (xy 232.87964 -44.460704) (xy 232.819249 -44.49865)
			(xy 232.75499 -44.529595) (xy 232.68767 -44.553152) (xy 232.618135 -44.569022) (xy 232.547261 -44.577008)
			(xy 232.475939 -44.577008) (xy 232.405065 -44.569022) (xy 232.33553 -44.553152) (xy 232.26821 -44.529595)
			(xy 232.203951 -44.49865) (xy 232.14356 -44.460704) (xy 232.087798 -44.416235) (xy 232.037365 -44.365802)
			(xy 231.992896 -44.31004) (xy 231.95495 -44.249649) (xy 231.924005 -44.18539) (xy 231.900448 -44.11807)
			(xy 231.884578 -44.048535) (xy 231.876592 -43.977661) (xy 225.526608 -43.977661) (xy 225.518622 -44.048535)
			(xy 225.502752 -44.11807) (xy 225.479195 -44.18539) (xy 225.44825 -44.249649) (xy 225.410304 -44.31004)
			(xy 225.365835 -44.365802) (xy 225.315402 -44.416235) (xy 225.25964 -44.460704) (xy 225.199249 -44.49865)
			(xy 225.13499 -44.529595) (xy 225.06767 -44.553152) (xy 224.998135 -44.569022) (xy 224.927261 -44.577008)
			(xy 224.855939 -44.577008) (xy 224.785065 -44.569022) (xy 224.71553 -44.553152) (xy 224.64821 -44.529595)
			(xy 224.583951 -44.49865) (xy 224.52356 -44.460704) (xy 224.467798 -44.416235) (xy 224.417365 -44.365802)
			(xy 224.372896 -44.31004) (xy 224.33495 -44.249649) (xy 224.304005 -44.18539) (xy 224.280448 -44.11807)
			(xy 224.264578 -44.048535) (xy 224.256592 -43.977661) (xy 217.906608 -43.977661) (xy 217.898622 -44.048535)
			(xy 217.882752 -44.11807) (xy 217.859195 -44.18539) (xy 217.82825 -44.249649) (xy 217.790304 -44.31004)
			(xy 217.745835 -44.365802) (xy 217.695402 -44.416235) (xy 217.63964 -44.460704) (xy 217.579249 -44.49865)
			(xy 217.51499 -44.529595) (xy 217.44767 -44.553152) (xy 217.378135 -44.569022) (xy 217.307261 -44.577008)
			(xy 217.235939 -44.577008) (xy 217.165065 -44.569022) (xy 217.09553 -44.553152) (xy 217.02821 -44.529595)
			(xy 216.963951 -44.49865) (xy 216.90356 -44.460704) (xy 216.847798 -44.416235) (xy 216.797365 -44.365802)
			(xy 216.752896 -44.31004) (xy 216.71495 -44.249649) (xy 216.684005 -44.18539) (xy 216.660448 -44.11807)
			(xy 216.644578 -44.048535) (xy 216.636592 -43.977661) (xy 214.064596 -43.977661) (xy 214.064596 -47.500032)
			(xy 214.064096 -47.591923) (xy 214.056146 -47.775532) (xy 214.040276 -47.958627) (xy 214.016516 -48.140866)
			(xy 213.984908 -48.32191) (xy 213.945513 -48.501419) (xy 213.898404 -48.67906) (xy 213.843669 -48.854502)
			(xy 213.781409 -49.027416) (xy 213.711742 -49.197481) (xy 213.634796 -49.364379) (xy 213.550716 -49.5278)
			(xy 213.459658 -49.687437) (xy 213.361793 -49.842994) (xy 213.309962 -49.918874) (xy 213.297261 -49.938108)
			(xy 213.278298 -49.980115) (xy 213.267222 -50.024852) (xy 213.264395 -50.070853) (xy 213.26991 -50.11661)
			(xy 213.283586 -50.160622) (xy 213.304976 -50.201446) (xy 213.333376 -50.237744) (xy 213.367857 -50.268324)
			(xy 213.407288 -50.292185) (xy 213.450375 -50.308544) (xy 213.495706 -50.316865) (xy 213.51875 -50.3174)
		)
		(stroke
			(width 0)
			(type solid)
		)
		(fill yes)
		(layer "F.Cu")
		(net "P12V")
	)
	(gr_poly
		(pts
			(arc
				(start 101.214682 -5.993638)
				(mid 100.862638 -5.993638)
				(end 101.214682 -5.993638)
			)
		)
		(stroke
			(width 0)
			(type solid)
		)
		(fill yes)
		(layer "B.Cu")
		(net "GND")
	)
	(gr_poly
		(pts
			(arc
				(start 101.214682 -4.952238)
				(mid 100.862638 -4.952238)
				(end 101.214682 -4.952238)
			)
		)
		(stroke
			(width 0)
			(type solid)
		)
		(fill yes)
		(layer "B.Cu")
		(net "GND")
	)
	(gr_poly
		(pts
			(arc
				(start 103.856282 -5.968238)
				(mid 103.504238 -5.968238)
				(end 103.856282 -5.968238)
			)
		)
		(stroke
			(width 0)
			(type solid)
		)
		(fill yes)
		(layer "B.Cu")
		(net "GND")
	)
	(gr_poly
		(pts
			(arc
				(start 103.856282 -5.053838)
				(mid 103.504238 -5.053838)
				(end 103.856282 -5.053838)
			)
		)
		(stroke
			(width 0)
			(type solid)
		)
		(fill yes)
		(layer "B.Cu")
		(net "GND")
	)
	(gr_poly
		(pts
			(arc
				(start 113.457482 -9.752838)
				(mid 113.105438 -9.752838)
				(end 113.457482 -9.752838)
			)
		)
		(stroke
			(width 0)
			(type solid)
		)
		(fill yes)
		(layer "B.Cu")
		(net "GND")
	)
	(gr_poly
		(pts
			(arc
				(start 113.457482 -8.609838)
				(mid 113.105438 -8.609838)
				(end 113.457482 -8.609838)
			)
		)
		(stroke
			(width 0)
			(type solid)
		)
		(fill yes)
		(layer "B.Cu")
		(net "GND")
	)
	(gr_poly
		(pts
			(arc
				(start 115.845082 -9.803638)
				(mid 115.493038 -9.803638)
				(end 115.845082 -9.803638)
			)
		)
		(stroke
			(width 0)
			(type solid)
		)
		(fill yes)
		(layer "B.Cu")
		(net "GND")
	)
	(gr_poly
		(pts
			(arc
				(start 115.845082 -8.635238)
				(mid 115.493038 -8.635238)
				(end 115.845082 -8.635238)
			)
		)
		(stroke
			(width 0)
			(type solid)
		)
		(fill yes)
		(layer "B.Cu")
		(net "GND")
	)
	(gr_poly
		(pts
			(arc
				(start 118.435882 -14.197838)
				(mid 118.083838 -14.197838)
				(end 118.435882 -14.197838)
			)
		)
		(stroke
			(width 0)
			(type solid)
		)
		(fill yes)
		(layer "B.Cu")
		(net "GND")
	)
	(gr_poly
		(pts
			(arc
				(start 120.696482 -0.989838)
				(mid 120.344438 -0.989838)
				(end 120.696482 -0.989838)
			)
		)
		(stroke
			(width 0)
			(type solid)
		)
		(fill yes)
		(layer "B.Cu")
		(net "GND")
	)
	(gr_poly
		(pts
			(arc
				(start 124.684282 -1.015238)
				(mid 124.332238 -1.015238)
				(end 124.684282 -1.015238)
			)
		)
		(stroke
			(width 0)
			(type solid)
		)
		(fill yes)
		(layer "B.Cu")
		(net "GND")
	)
	(gr_poly
		(pts
			(arc
				(start 129.002282 -1.066038)
				(mid 128.650238 -1.066038)
				(end 129.002282 -1.066038)
			)
		)
		(stroke
			(width 0)
			(type solid)
		)
		(fill yes)
		(layer "B.Cu")
		(net "GND")
	)
	(gr_poly
		(pts
			(arc
				(start 132.456682 -3.504438)
				(mid 132.104638 -3.504438)
				(end 132.456682 -3.504438)
			)
		)
		(stroke
			(width 0)
			(type solid)
		)
		(fill yes)
		(layer "B.Cu")
		(net "GND")
	)
	(gr_poly
		(pts
			(arc
				(start 132.482082 -5.714238)
				(mid 132.130038 -5.714238)
				(end 132.482082 -5.714238)
			)
		)
		(stroke
			(width 0)
			(type solid)
		)
		(fill yes)
		(layer "B.Cu")
		(net "GND")
	)
	(gr_poly
		(pts
			(arc
				(start 133.675882 -5.739638)
				(mid 133.323838 -5.739638)
				(end 133.675882 -5.739638)
			)
		)
		(stroke
			(width 0)
			(type solid)
		)
		(fill yes)
		(layer "B.Cu")
		(net "GND")
	)
	(gr_poly
		(pts
			(arc
				(start 133.675882 -3.529838)
				(mid 133.323838 -3.529838)
				(end 133.675882 -3.529838)
			)
		)
		(stroke
			(width 0)
			(type solid)
		)
		(fill yes)
		(layer "B.Cu")
		(net "GND")
	)
	(gr_poly
		(pts
			(arc
				(start 144.191482 -6.196838)
				(mid 143.839438 -6.196838)
				(end 144.191482 -6.196838)
			)
		)
		(stroke
			(width 0)
			(type solid)
		)
		(fill yes)
		(layer "B.Cu")
		(net "GND")
	)
	(gr_poly
		(pts
			(arc
				(start 144.216882 -5.206238)
				(mid 143.864838 -5.206238)
				(end 144.216882 -5.206238)
			)
		)
		(stroke
			(width 0)
			(type solid)
		)
		(fill yes)
		(layer "B.Cu")
		(net "GND")
	)
	(gr_poly
		(pts
			(arc
				(start 146.426682 -6.171438)
				(mid 146.074638 -6.171438)
				(end 146.426682 -6.171438)
			)
		)
		(stroke
			(width 0)
			(type solid)
		)
		(fill yes)
		(layer "B.Cu")
		(net "GND")
	)
	(gr_poly
		(pts
			(arc
				(start 146.452082 -5.282438)
				(mid 146.100038 -5.282438)
				(end 146.452082 -5.282438)
			)
		)
		(stroke
			(width 0)
			(type solid)
		)
		(fill yes)
		(layer "B.Cu")
		(net "GND")
	)
	(gr_poly
		(pts
			(arc
				(start 164.841682 -14.121638)
				(mid 164.489638 -14.121638)
				(end 164.841682 -14.121638)
			)
		)
		(stroke
			(width 0)
			(type solid)
		)
		(fill yes)
		(layer "B.Cu")
		(net "GND")
	)
	(gr_poly
		(pts
			(arc
				(start 165.552882 -23.138638)
				(mid 165.200838 -23.138638)
				(end 165.552882 -23.138638)
			)
		)
		(stroke
			(width 0)
			(type solid)
		)
		(fill yes)
		(layer "B.Cu")
		(net "GND")
	)
	(gr_poly
		(pts
			(arc
				(start 165.654482 -24.053038)
				(mid 165.302438 -24.053038)
				(end 165.654482 -24.053038)
			)
		)
		(stroke
			(width 0)
			(type solid)
		)
		(fill yes)
		(layer "B.Cu")
		(net "GND")
	)
	(gr_poly
		(pts
			(arc
				(start 166.594282 -1.040638)
				(mid 166.242238 -1.040638)
				(end 166.594282 -1.040638)
			)
		)
		(stroke
			(width 0)
			(type solid)
		)
		(fill yes)
		(layer "B.Cu")
		(net "GND")
	)
	(gr_poly
		(pts
			(arc
				(start 168.219882 -19.277838)
				(mid 167.867838 -19.277838)
				(end 168.219882 -19.277838)
			)
		)
		(stroke
			(width 0)
			(type solid)
		)
		(fill yes)
		(layer "B.Cu")
		(net "GND")
	)
	(gr_poly
		(pts
			(arc
				(start 169.108882 -14.197838)
				(mid 168.756838 -14.197838)
				(end 169.108882 -14.197838)
			)
		)
		(stroke
			(width 0)
			(type solid)
		)
		(fill yes)
		(layer "B.Cu")
		(net "GND")
	)
	(gr_poly
		(pts
			(arc
				(start 169.718482 -32.054038)
				(mid 169.366438 -32.054038)
				(end 169.718482 -32.054038)
			)
		)
		(stroke
			(width 0)
			(type solid)
		)
		(fill yes)
		(layer "B.Cu")
		(net "GND")
	)
	(gr_poly
		(pts
			(arc
				(start 173.122082 -33.832038)
				(mid 172.770038 -33.832038)
				(end 173.122082 -33.832038)
			)
		)
		(stroke
			(width 0)
			(type solid)
		)
		(fill yes)
		(layer "B.Cu")
		(net "GND")
	)
	(gr_poly
		(pts
			(arc
				(start 173.299882 -14.096238)
				(mid 172.947838 -14.096238)
				(end 173.299882 -14.096238)
			)
		)
		(stroke
			(width 0)
			(type solid)
		)
		(fill yes)
		(layer "B.Cu")
		(net "GND")
	)
	(gr_poly
		(pts
			(arc
				(start 174.315882 -33.832038)
				(mid 173.963838 -33.832038)
				(end 174.315882 -33.832038)
			)
		)
		(stroke
			(width 0)
			(type solid)
		)
		(fill yes)
		(layer "B.Cu")
		(net "GND")
	)
	(gr_poly
		(pts
			(arc
				(start 175.128682 -1.040638)
				(mid 174.776638 -1.040638)
				(end 175.128682 -1.040638)
			)
		)
		(stroke
			(width 0)
			(type solid)
		)
		(fill yes)
		(layer "B.Cu")
		(net "GND")
	)
	(gr_poly
		(pts
			(arc
				(start 177.567082 -22.935438)
				(mid 177.215038 -22.935438)
				(end 177.567082 -22.935438)
			)
		)
		(stroke
			(width 0)
			(type solid)
		)
		(fill yes)
		(layer "B.Cu")
		(net "GND")
	)
	(gr_poly
		(pts
			(arc
				(start 183.663082 -25.983438)
				(mid 183.311038 -25.983438)
				(end 183.663082 -25.983438)
			)
		)
		(stroke
			(width 0)
			(type solid)
		)
		(fill yes)
		(layer "B.Cu")
		(net "GND")
	)
	(gr_poly
		(pts
			(arc
				(start 183.942482 -30.199838)
				(mid 183.590438 -30.199838)
				(end 183.942482 -30.199838)
			)
		)
		(stroke
			(width 0)
			(type solid)
		)
		(fill yes)
		(layer "B.Cu")
		(net "GND")
	)
	(gr_poly
		(pts
			(arc
				(start 185.822082 -27.659838)
				(mid 185.470038 -27.659838)
				(end 185.822082 -27.659838)
			)
		)
		(stroke
			(width 0)
			(type solid)
		)
		(fill yes)
		(layer "B.Cu")
		(net "GND")
	)
	(gr_poly
		(pts
			(arc
				(start 191.765682 -30.834838)
				(mid 191.413638 -30.834838)
				(end 191.765682 -30.834838)
			)
		)
		(stroke
			(width 0)
			(type solid)
		)
		(fill yes)
		(layer "B.Cu")
		(net "GND")
	)
	(gr_poly
		(pts
			(arc
				(start 194.229482 -31.673038)
				(mid 193.877438 -31.673038)
				(end 194.229482 -31.673038)
			)
		)
		(stroke
			(width 0)
			(type solid)
		)
		(fill yes)
		(layer "B.Cu")
		(net "GND")
	)
	(gr_poly
		(pts
			(arc
				(start 196.921882 -22.935438)
				(mid 196.569838 -22.935438)
				(end 196.921882 -22.935438)
			)
		)
		(stroke
			(width 0)
			(type solid)
		)
		(fill yes)
		(layer "B.Cu")
		(net "GND")
	)
	(gr_poly
		(pts
			(arc
				(start 322.169282 -5.815838)
				(mid 321.817238 -5.815838)
				(end 322.169282 -5.815838)
			)
		)
		(stroke
			(width 0)
			(type solid)
		)
		(fill yes)
		(layer "B.Cu")
		(net "GND")
	)
	(gr_poly
		(pts
			(arc
				(start 322.169282 -5.003038)
				(mid 321.817238 -5.003038)
				(end 322.169282 -5.003038)
			)
		)
		(stroke
			(width 0)
			(type solid)
		)
		(fill yes)
		(layer "B.Cu")
		(net "GND")
	)
	(gr_poly
		(pts
			(arc
				(start 324.963282 -5.841238)
				(mid 324.611238 -5.841238)
				(end 324.963282 -5.841238)
			)
		)
		(stroke
			(width 0)
			(type solid)
		)
		(fill yes)
		(layer "B.Cu")
		(net "GND")
	)
	(gr_poly
		(pts
			(arc
				(start 324.963282 -5.028438)
				(mid 324.611238 -5.028438)
				(end 324.963282 -5.028438)
			)
		)
		(stroke
			(width 0)
			(type solid)
		)
		(fill yes)
		(layer "B.Cu")
		(net "GND")
	)
	(gr_poly
		(pts
			(arc
				(start 334.406748 -9.702038)
				(mid 334.054704 -9.702038)
				(end 334.406748 -9.702038)
			)
		)
		(stroke
			(width 0)
			(type solid)
		)
		(fill yes)
		(layer "B.Cu")
		(net "GND")
	)
	(gr_poly
		(pts
			(arc
				(start 334.432148 -8.609838)
				(mid 334.080104 -8.609838)
				(end 334.432148 -8.609838)
			)
		)
		(stroke
			(width 0)
			(type solid)
		)
		(fill yes)
		(layer "B.Cu")
		(net "GND")
	)
	(gr_poly
		(pts
			(arc
				(start 336.794348 -9.803638)
				(mid 336.442304 -9.803638)
				(end 336.794348 -9.803638)
			)
		)
		(stroke
			(width 0)
			(type solid)
		)
		(fill yes)
		(layer "B.Cu")
		(net "GND")
	)
	(gr_poly
		(pts
			(arc
				(start 336.794348 -8.584438)
				(mid 336.442304 -8.584438)
				(end 336.794348 -8.584438)
			)
		)
		(stroke
			(width 0)
			(type solid)
		)
		(fill yes)
		(layer "B.Cu")
		(net "GND")
	)
	(gr_poly
		(pts
			(arc
				(start 339.339682 -14.121638)
				(mid 338.987638 -14.121638)
				(end 339.339682 -14.121638)
			)
		)
		(stroke
			(width 0)
			(type solid)
		)
		(fill yes)
		(layer "B.Cu")
		(net "GND")
	)
	(gr_poly
		(pts
			(arc
				(start 341.727282 -1.040638)
				(mid 341.375238 -1.040638)
				(end 341.727282 -1.040638)
			)
		)
		(stroke
			(width 0)
			(type solid)
		)
		(fill yes)
		(layer "B.Cu")
		(net "GND")
	)
	(gr_poly
		(pts
			(arc
				(start 345.765882 -1.015238)
				(mid 345.413838 -1.015238)
				(end 345.765882 -1.015238)
			)
		)
		(stroke
			(width 0)
			(type solid)
		)
		(fill yes)
		(layer "B.Cu")
		(net "GND")
	)
	(gr_poly
		(pts
			(arc
				(start 349.753682 -1.015238)
				(mid 349.401638 -1.015238)
				(end 349.753682 -1.015238)
			)
		)
		(stroke
			(width 0)
			(type solid)
		)
		(fill yes)
		(layer "B.Cu")
		(net "GND")
	)
	(gr_poly
		(pts
			(arc
				(start 353.456748 -3.504438)
				(mid 353.104704 -3.504438)
				(end 353.456748 -3.504438)
			)
		)
		(stroke
			(width 0)
			(type solid)
		)
		(fill yes)
		(layer "B.Cu")
		(net "GND")
	)
	(gr_poly
		(pts
			(arc
				(start 353.482148 -5.714238)
				(mid 353.130104 -5.714238)
				(end 353.482148 -5.714238)
			)
		)
		(stroke
			(width 0)
			(type solid)
		)
		(fill yes)
		(layer "B.Cu")
		(net "GND")
	)
	(gr_poly
		(pts
			(arc
				(start 354.675948 -5.739638)
				(mid 354.323904 -5.739638)
				(end 354.675948 -5.739638)
			)
		)
		(stroke
			(width 0)
			(type solid)
		)
		(fill yes)
		(layer "B.Cu")
		(net "GND")
	)
	(gr_poly
		(pts
			(arc
				(start 354.675948 -3.529838)
				(mid 354.323904 -3.529838)
				(end 354.675948 -3.529838)
			)
		)
		(stroke
			(width 0)
			(type solid)
		)
		(fill yes)
		(layer "B.Cu")
		(net "GND")
	)
	(gr_poly
		(pts
			(arc
				(start 365.044482 -6.069838)
				(mid 364.692438 -6.069838)
				(end 365.044482 -6.069838)
			)
		)
		(stroke
			(width 0)
			(type solid)
		)
		(fill yes)
		(layer "B.Cu")
		(net "GND")
	)
	(gr_poly
		(pts
			(arc
				(start 365.044482 -5.257038)
				(mid 364.692438 -5.257038)
				(end 365.044482 -5.257038)
			)
		)
		(stroke
			(width 0)
			(type solid)
		)
		(fill yes)
		(layer "B.Cu")
		(net "GND")
	)
	(gr_poly
		(pts
			(arc
				(start 367.381282 -6.196838)
				(mid 367.029238 -6.196838)
				(end 367.381282 -6.196838)
			)
		)
		(stroke
			(width 0)
			(type solid)
		)
		(fill yes)
		(layer "B.Cu")
		(net "GND")
	)
	(gr_poly
		(pts
			(arc
				(start 367.432082 -5.282438)
				(mid 367.080038 -5.282438)
				(end 367.432082 -5.282438)
			)
		)
		(stroke
			(width 0)
			(type solid)
		)
		(fill yes)
		(layer "B.Cu")
		(net "GND")
	)
	(gr_poly
		(pts
			(arc
				(start 385.796282 -14.121638)
				(mid 385.444238 -14.121638)
				(end 385.796282 -14.121638)
			)
		)
		(stroke
			(width 0)
			(type solid)
		)
		(fill yes)
		(layer "B.Cu")
		(net "GND")
	)
	(gr_poly
		(pts
			(arc
				(start 386.552948 -23.138638)
				(mid 386.200904 -23.138638)
				(end 386.552948 -23.138638)
			)
		)
		(stroke
			(width 0)
			(type solid)
		)
		(fill yes)
		(layer "B.Cu")
		(net "GND")
	)
	(gr_poly
		(pts
			(arc
				(start 386.654548 -24.053038)
				(mid 386.302504 -24.053038)
				(end 386.654548 -24.053038)
			)
		)
		(stroke
			(width 0)
			(type solid)
		)
		(fill yes)
		(layer "B.Cu")
		(net "GND")
	)
	(gr_poly
		(pts
			(arc
				(start 388.082282 -0.964438)
				(mid 387.730238 -0.964438)
				(end 388.082282 -0.964438)
			)
		)
		(stroke
			(width 0)
			(type solid)
		)
		(fill yes)
		(layer "B.Cu")
		(net "GND")
	)
	(gr_poly
		(pts
			(arc
				(start 389.219948 -19.277838)
				(mid 388.867904 -19.277838)
				(end 389.219948 -19.277838)
			)
		)
		(stroke
			(width 0)
			(type solid)
		)
		(fill yes)
		(layer "B.Cu")
		(net "GND")
	)
	(gr_poly
		(pts
			(arc
				(start 390.139682 -14.172438)
				(mid 389.787638 -14.172438)
				(end 390.139682 -14.172438)
			)
		)
		(stroke
			(width 0)
			(type solid)
		)
		(fill yes)
		(layer "B.Cu")
		(net "GND")
	)
	(gr_poly
		(pts
			(arc
				(start 390.718548 -32.054038)
				(mid 390.366504 -32.054038)
				(end 390.718548 -32.054038)
			)
		)
		(stroke
			(width 0)
			(type solid)
		)
		(fill yes)
		(layer "B.Cu")
		(net "GND")
	)
	(gr_poly
		(pts
			(arc
				(start 394.122148 -33.832038)
				(mid 393.770104 -33.832038)
				(end 394.122148 -33.832038)
			)
		)
		(stroke
			(width 0)
			(type solid)
		)
		(fill yes)
		(layer "B.Cu")
		(net "GND")
	)
	(gr_poly
		(pts
			(arc
				(start 394.330682 -14.147038)
				(mid 393.978638 -14.147038)
				(end 394.330682 -14.147038)
			)
		)
		(stroke
			(width 0)
			(type solid)
		)
		(fill yes)
		(layer "B.Cu")
		(net "GND")
	)
	(gr_poly
		(pts
			(arc
				(start 395.315948 -33.832038)
				(mid 394.963904 -33.832038)
				(end 395.315948 -33.832038)
			)
		)
		(stroke
			(width 0)
			(type solid)
		)
		(fill yes)
		(layer "B.Cu")
		(net "GND")
	)
	(gr_poly
		(pts
			(arc
				(start 396.159482 -1.066038)
				(mid 395.807438 -1.066038)
				(end 396.159482 -1.066038)
			)
		)
		(stroke
			(width 0)
			(type solid)
		)
		(fill yes)
		(layer "B.Cu")
		(net "GND")
	)
	(gr_poly
		(pts
			(arc
				(start 398.567148 -22.935438)
				(mid 398.215104 -22.935438)
				(end 398.567148 -22.935438)
			)
		)
		(stroke
			(width 0)
			(type solid)
		)
		(fill yes)
		(layer "B.Cu")
		(net "GND")
	)
	(gr_poly
		(pts
			(arc
				(start 404.770082 -25.831038)
				(mid 404.418038 -25.831038)
				(end 404.770082 -25.831038)
			)
		)
		(stroke
			(width 0)
			(type solid)
		)
		(fill yes)
		(layer "B.Cu")
		(net "GND")
	)
	(gr_poly
		(pts
			(arc
				(start 404.871682 -30.225238)
				(mid 404.519638 -30.225238)
				(end 404.871682 -30.225238)
			)
		)
		(stroke
			(width 0)
			(type solid)
		)
		(fill yes)
		(layer "B.Cu")
		(net "GND")
	)
	(gr_poly
		(pts
			(arc
				(start 406.802082 -27.609038)
				(mid 406.450038 -27.609038)
				(end 406.802082 -27.609038)
			)
		)
		(stroke
			(width 0)
			(type solid)
		)
		(fill yes)
		(layer "B.Cu")
		(net "GND")
	)
	(gr_poly
		(pts
			(arc
				(start 412.745682 -30.860238)
				(mid 412.393638 -30.860238)
				(end 412.745682 -30.860238)
			)
		)
		(stroke
			(width 0)
			(type solid)
		)
		(fill yes)
		(layer "B.Cu")
		(net "GND")
	)
	(gr_poly
		(pts
			(arc
				(start 415.254948 -31.571438)
				(mid 414.902904 -31.571438)
				(end 415.254948 -31.571438)
			)
		)
		(stroke
			(width 0)
			(type solid)
		)
		(fill yes)
		(layer "B.Cu")
		(net "GND")
	)
	(gr_poly
		(pts
			(arc
				(start 417.921948 -22.935438)
				(mid 417.569904 -22.935438)
				(end 417.921948 -22.935438)
			)
		)
		(stroke
			(width 0)
			(type solid)
		)
		(fill yes)
		(layer "B.Cu")
		(net "GND")
	)
	(gr_poly
		(pts
			(xy 21.429472 -51.862736) (xy 30.636464 -51.862736) (xy 30.842204 -51.656996) (xy 30.842204 -45.449236)
			(xy 30.8991 -45.39234) (xy 30.8991 -35.8013) (xy 30.2768 -35.179)
			(arc
				(start 28.054808 -35.179)
				(mid 28.008877 -35.187597)
				(end 27.96921 -35.212274)
			)
			(arc
				(start 27.96921 -35.212274)
				(mid 27.72643 -35.327191)
				(end 27.460956 -35.286188)
			)
			(xy 27.434794 -35.273488) (xy 24.224488 -35.273488) (xy 19.220688 -40.277288) (xy 13.591286 -40.277288)
			(xy 12.481814 -41.38676)
			(arc
				(start 11.8618 -41.38676)
				(mid 11.771997 -41.423957)
				(end 11.7348 -41.51376)
			)
			(xy 11.7348 -51.4604) (xy 12.137136 -51.862736)
			(arc
				(start 20.557744 -51.862736)
				(mid 20.647547 -51.825539)
				(end 20.684744 -51.735736)
			)
			(xy 20.684744 -45.449236) (xy 21.232368 -45.449236)
			(arc
				(start 21.232368 -51.737768)
				(mid 21.269476 -51.827735)
				(end 21.359368 -51.864768)
			)
			(xy 21.426932 -51.864768)
		)
		(stroke
			(width 0)
			(type solid)
		)
		(fill yes)
		(layer "B.Cu")
		(net "P12V")
	)
	(gr_poly
		(pts
			(xy 0 -10.700004) (xy 0.000494 -10.794258) (xy 0.008387 -10.9826) (xy 0.024161 -11.170446) (xy 0.047788 -11.357467)
			(xy 0.079225 -11.543334) (xy 0.118418 -11.727723) (xy 0.165297 -11.910308) (xy 0.219782 -12.090769)
			(xy 0.281776 -12.268791) (xy 0.35117 -12.444061) (xy 0.427843 -12.616271) (xy 0.51166 -12.785119)
			(xy 0.602474 -12.95031) (xy 0.700126 -13.111552) (xy 0.804444 -13.268564) (xy 0.915246 -13.42107)
			(xy 1.032337 -13.568802) (xy 1.155512 -13.711501) (xy 1.284554 -13.848917) (xy 1.419237 -13.980809)
			(xy 1.559326 -14.106945) (xy 1.704573 -14.227104) (xy 1.854725 -14.341075) (xy 2.009518 -14.448659)
			(xy 2.16868 -14.549666) (xy 2.331932 -14.64392) (xy 2.498988 -14.731255) (xy 2.669554 -14.811517)
			(xy 2.843332 -14.884567) (xy 3.020017 -14.950275) (xy 3.199298 -15.008527) (xy 3.380861 -15.059221)
			(xy 3.564388 -15.102266) (xy 3.749557 -15.137589) (xy 3.936042 -15.165127) (xy 4.123517 -15.184831)
			(xy 4.311652 -15.196668) (xy 4.500118 -15.200616) (xy 4.688584 -15.196668) (xy 4.876719 -15.184831)
			(xy 5.064194 -15.165127) (xy 5.250679 -15.137589) (xy 5.435848 -15.102266) (xy 5.619375 -15.059221)
			(xy 5.800938 -15.008527) (xy 5.980219 -14.950275) (xy 6.156904 -14.884567) (xy 6.330682 -14.811517)
			(xy 6.501248 -14.731255) (xy 6.668304 -14.64392) (xy 6.831556 -14.549666) (xy 6.990718 -14.448659)
			(xy 7.145511 -14.341075) (xy 7.295663 -14.227104) (xy 7.44091 -14.106945) (xy 7.580999 -13.980809)
			(xy 7.715682 -13.848917) (xy 7.844724 -13.711501) (xy 7.967899 -13.568802) (xy 8.08499 -13.42107)
			(xy 8.195792 -13.268564) (xy 8.30011 -13.111552) (xy 8.397762 -12.95031) (xy 8.488576 -12.785119)
			(xy 8.572393 -12.616271) (xy 8.649066 -12.444061) (xy 8.71846 -12.268791) (xy 8.780454 -12.090769)
			(xy 8.834939 -11.910308) (xy 8.881818 -11.727723) (xy 8.921011 -11.543334) (xy 8.952448 -11.357467)
			(xy 8.976075 -11.170446) (xy 8.991849 -10.9826) (xy 8.999742 -10.794258) (xy 9.000236 -10.700004)
			(xy 9.000236 -4.700016) (xy 8.999742 -4.605762) (xy 8.991849 -4.41742) (xy 8.976075 -4.229574) (xy 8.952448 -4.042553)
			(xy 8.921011 -3.856686) (xy 8.881818 -3.672297) (xy 8.834939 -3.489712) (xy 8.780454 -3.309251) (xy 8.71846 -3.131229)
			(xy 8.649066 -2.955959) (xy 8.572393 -2.783749) (xy 8.488576 -2.614901) (xy 8.397762 -2.44971) (xy 8.30011 -2.288468)
			(xy 8.195792 -2.131456) (xy 8.08499 -1.97895) (xy 7.967899 -1.831218) (xy 7.844724 -1.688519) (xy 7.715682 -1.551103)
			(xy 7.580999 -1.419211) (xy 7.44091 -1.293075) (xy 7.295663 -1.172916) (xy 7.145511 -1.058945) (xy 6.990718 -0.951361)
			(xy 6.831556 -0.850354) (xy 6.668304 -0.7561) (xy 6.501248 -0.668765) (xy 6.330682 -0.588503) (xy 6.156904 -0.515453)
			(xy 5.980219 -0.449745) (xy 5.800938 -0.391493) (xy 5.619375 -0.340799) (xy 5.435848 -0.297754) (xy 5.250679 -0.262431)
			(xy 5.064194 -0.234893) (xy 4.876719 -0.215189) (xy 4.688584 -0.203352) (xy 4.500118 -0.199405) (xy 4.311652 -0.203352)
			(xy 4.123517 -0.215189) (xy 3.936042 -0.234893) (xy 3.749557 -0.262431) (xy 3.564388 -0.297754) (xy 3.380861 -0.340799)
			(xy 3.199298 -0.391493) (xy 3.020017 -0.449745) (xy 2.843332 -0.515453) (xy 2.669554 -0.588503) (xy 2.498988 -0.668765)
			(xy 2.331932 -0.7561) (xy 2.16868 -0.850354) (xy 2.009518 -0.951361) (xy 1.854725 -1.058945) (xy 1.704573 -1.172916)
			(xy 1.559326 -1.293075) (xy 1.419237 -1.419211) (xy 1.284554 -1.551103) (xy 1.155512 -1.688519) (xy 1.032337 -1.831218)
			(xy 0.915246 -1.97895) (xy 0.804444 -2.131456) (xy 0.700126 -2.288468) (xy 0.602474 -2.44971) (xy 0.51166 -2.614901)
			(xy 0.427843 -2.783749) (xy 0.35117 -2.955959) (xy 0.281776 -3.131229) (xy 0.219782 -3.309251) (xy 0.165297 -3.489712)
			(xy 0.118418 -3.672297) (xy 0.079225 -3.856686) (xy 0.047788 -4.042553) (xy 0.024161 -4.229574) (xy 0.008387 -4.41742)
			(xy 0.000494 -4.605762) (xy 0 -4.700016) (xy 2.185679 -4.700016) (xy 2.189668 -4.564187) (xy 2.201622 -4.428826)
			(xy 2.221499 -4.294401) (xy 2.249231 -4.161373) (xy 2.284722 -4.030202) (xy 2.327851 -3.90134) (xy 2.378467 -3.775232)
			(xy 2.436397 -3.652311) (xy 2.501442 -3.533002) (xy 2.573376 -3.417716) (xy 2.651952 -3.30685) (xy 2.736899 -3.200787)
			(xy 2.827924 -3.099892) (xy 2.924714 -3.004513) (xy 3.026934 -2.914979) (xy 3.134233 -2.831598) (xy 3.24624 -2.754658)
			(xy 3.36257 -2.684424) (xy 3.482821 -2.621138) (xy 3.606579 -2.565018) (xy 3.733417 -2.516258) (xy 3.862898 -2.475026)
			(xy 3.994576 -2.441465) (xy 4.127996 -2.415688) (xy 4.262699 -2.397787) (xy 4.398221 -2.387821) (xy 4.534094 -2.385826)
			(xy 4.669849 -2.391809) (xy 4.80502 -2.405749) (xy 4.939139 -2.427597) (xy 5.071746 -2.457279) (xy 5.202381 -2.494692)
			(xy 5.330596 -2.539707) (xy 5.455948 -2.592169) (xy 5.578005 -2.651898) (xy 5.696346 -2.718687) (xy 5.810564 -2.792306)
			(xy 5.920264 -2.872501) (xy 6.025069 -2.958996) (xy 6.124617 -3.051492) (xy 6.218565 -3.149671) (xy 6.306589 -3.253195)
			(xy 6.388386 -3.361706) (xy 6.463673 -3.474831) (xy 6.532192 -3.592179) (xy 6.593706 -3.713346) (xy 6.648003 -3.837915)
			(xy 6.694895 -3.965455) (xy 6.734222 -4.095527) (xy 6.765847 -4.227683) (xy 6.789662 -4.361468) (xy 6.805585 -4.496419)
			(xy 6.813559 -4.632072) (xy 6.814058 -4.700016) (xy 6.813559 -4.76796) (xy 6.805585 -4.903613) (xy 6.789662 -5.038564)
			(xy 6.765847 -5.172349) (xy 6.734222 -5.304505) (xy 6.694895 -5.434577) (xy 6.648003 -5.562117) (xy 6.593706 -5.686686)
			(xy 6.532192 -5.807853) (xy 6.463673 -5.925201) (xy 6.388386 -6.038326) (xy 6.306589 -6.146837) (xy 6.218565 -6.250361)
			(xy 6.124617 -6.34854) (xy 6.025069 -6.441036) (xy 5.920264 -6.527531) (xy 5.810564 -6.607726) (xy 5.696346 -6.681345)
			(xy 5.578005 -6.748134) (xy 5.455948 -6.807863) (xy 5.330596 -6.860325) (xy 5.202381 -6.90534) (xy 5.071746 -6.942753)
			(xy 4.939139 -6.972435) (xy 4.80502 -6.994283) (xy 4.669849 -7.008223) (xy 4.534094 -7.014206) (xy 4.398221 -7.012211)
			(xy 4.262699 -7.002245) (xy 4.127996 -6.984344) (xy 3.994576 -6.958567) (xy 3.862898 -6.925006) (xy 3.733417 -6.883774)
			(xy 3.606579 -6.835014) (xy 3.482821 -6.778894) (xy 3.36257 -6.715608) (xy 3.24624 -6.645374) (xy 3.134233 -6.568434)
			(xy 3.026934 -6.485053) (xy 2.924714 -6.395519) (xy 2.827924 -6.30014) (xy 2.736899 -6.199245) (xy 2.651952 -6.093182)
			(xy 2.573376 -5.982316) (xy 2.501442 -5.86703) (xy 2.436397 -5.747721) (xy 2.378467 -5.6248) (xy 2.327851 -5.498692)
			(xy 2.284722 -5.36983) (xy 2.249231 -5.238659) (xy 2.221499 -5.105631) (xy 2.201622 -4.971206) (xy 2.189668 -4.835845)
			(xy 2.185679 -4.700016) (xy 0 -4.700016)
		)
		(stroke
			(width 0)
			(type solid)
		)
		(fill yes)
		(layer "B.Cu")
		(net "GND")
	)
	(gr_poly
		(pts
			(xy 419.80993 -10.700004) (xy 419.810424 -10.794258) (xy 419.818317 -10.9826) (xy 419.834091 -11.170446)
			(xy 419.857718 -11.357467) (xy 419.889155 -11.543334) (xy 419.928348 -11.727723) (xy 419.975227 -11.910308)
			(xy 420.029712 -12.090769) (xy 420.091706 -12.268791) (xy 420.1611 -12.444061) (xy 420.237773 -12.616271)
			(xy 420.32159 -12.785119) (xy 420.412404 -12.95031) (xy 420.510056 -13.111552) (xy 420.614374 -13.268564)
			(xy 420.725176 -13.42107) (xy 420.842267 -13.568802) (xy 420.965442 -13.711501) (xy 421.094484 -13.848917)
			(xy 421.229167 -13.980809) (xy 421.369256 -14.106945) (xy 421.514503 -14.227104) (xy 421.664655 -14.341075)
			(xy 421.819448 -14.448659) (xy 421.97861 -14.549666) (xy 422.141862 -14.64392) (xy 422.308918 -14.731255)
			(xy 422.479484 -14.811517) (xy 422.653262 -14.884567) (xy 422.829947 -14.950275) (xy 423.009228 -15.008527)
			(xy 423.190791 -15.059221) (xy 423.374318 -15.102266) (xy 423.559487 -15.137589) (xy 423.745972 -15.165127)
			(xy 423.933447 -15.184831) (xy 424.121582 -15.196668) (xy 424.310048 -15.200616) (xy 424.498514 -15.196668)
			(xy 424.686649 -15.184831) (xy 424.874124 -15.165127) (xy 425.060609 -15.137589) (xy 425.245778 -15.102266)
			(xy 425.429305 -15.059221) (xy 425.610868 -15.008527) (xy 425.790149 -14.950275) (xy 425.966834 -14.884567)
			(xy 426.140612 -14.811517) (xy 426.311178 -14.731255) (xy 426.478234 -14.64392) (xy 426.641486 -14.549666)
			(xy 426.800648 -14.448659) (xy 426.955441 -14.341075) (xy 427.105593 -14.227104) (xy 427.25084 -14.106945)
			(xy 427.390929 -13.980809) (xy 427.525612 -13.848917) (xy 427.654654 -13.711501) (xy 427.777829 -13.568802)
			(xy 427.89492 -13.42107) (xy 428.005722 -13.268564) (xy 428.11004 -13.111552) (xy 428.207692 -12.95031)
			(xy 428.298506 -12.785119) (xy 428.382323 -12.616271) (xy 428.458996 -12.444061) (xy 428.52839 -12.268791)
			(xy 428.590384 -12.090769) (xy 428.644869 -11.910308) (xy 428.691748 -11.727723) (xy 428.730941 -11.543334)
			(xy 428.762378 -11.357467) (xy 428.786005 -11.170446) (xy 428.801779 -10.9826) (xy 428.809672 -10.794258)
			(xy 428.810166 -10.700004) (xy 428.810166 -4.700016) (xy 428.809672 -4.605762) (xy 428.801779 -4.41742)
			(xy 428.786005 -4.229574) (xy 428.762378 -4.042553) (xy 428.730941 -3.856686) (xy 428.691748 -3.672297)
			(xy 428.644869 -3.489712) (xy 428.590384 -3.309251) (xy 428.52839 -3.131229) (xy 428.458996 -2.955959)
			(xy 428.382323 -2.783749) (xy 428.298506 -2.614901) (xy 428.207692 -2.44971) (xy 428.11004 -2.288468)
			(xy 428.005722 -2.131456) (xy 427.89492 -1.97895) (xy 427.777829 -1.831218) (xy 427.654654 -1.688519)
			(xy 427.525612 -1.551103) (xy 427.390929 -1.419211) (xy 427.25084 -1.293075) (xy 427.105593 -1.172916)
			(xy 426.955441 -1.058945) (xy 426.800648 -0.951361) (xy 426.641486 -0.850354) (xy 426.478234 -0.7561)
			(xy 426.311178 -0.668765) (xy 426.140612 -0.588503) (xy 425.966834 -0.515453) (xy 425.790149 -0.449745)
			(xy 425.610868 -0.391493) (xy 425.429305 -0.340799) (xy 425.245778 -0.297754) (xy 425.060609 -0.262431)
			(xy 424.874124 -0.234893) (xy 424.686649 -0.215189) (xy 424.498514 -0.203352) (xy 424.310048 -0.199405)
			(xy 424.121582 -0.203352) (xy 423.933447 -0.215189) (xy 423.745972 -0.234893) (xy 423.559487 -0.262431)
			(xy 423.374318 -0.297754) (xy 423.190791 -0.340799) (xy 423.009228 -0.391493) (xy 422.829947 -0.449745)
			(xy 422.653262 -0.515453) (xy 422.479484 -0.588503) (xy 422.308918 -0.668765) (xy 422.141862 -0.7561)
			(xy 421.97861 -0.850354) (xy 421.819448 -0.951361) (xy 421.664655 -1.058945) (xy 421.514503 -1.172916)
			(xy 421.369256 -1.293075) (xy 421.229167 -1.419211) (xy 421.094484 -1.551103) (xy 420.965442 -1.688519)
			(xy 420.842267 -1.831218) (xy 420.725176 -1.97895) (xy 420.614374 -2.131456) (xy 420.510056 -2.288468)
			(xy 420.412404 -2.44971) (xy 420.32159 -2.614901) (xy 420.237773 -2.783749) (xy 420.1611 -2.955959)
			(xy 420.091706 -3.131229) (xy 420.029712 -3.309251) (xy 419.975227 -3.489712) (xy 419.928348 -3.672297)
			(xy 419.889155 -3.856686) (xy 419.857718 -4.042553) (xy 419.834091 -4.229574) (xy 419.818317 -4.41742)
			(xy 419.810424 -4.605762) (xy 419.80993 -4.700016) (xy 421.995609 -4.700016) (xy 421.999598 -4.564187)
			(xy 422.011552 -4.428826) (xy 422.031429 -4.294401) (xy 422.059161 -4.161373) (xy 422.094652 -4.030202)
			(xy 422.137781 -3.90134) (xy 422.188397 -3.775232) (xy 422.246327 -3.652311) (xy 422.311372 -3.533002)
			(xy 422.383306 -3.417716) (xy 422.461882 -3.30685) (xy 422.546829 -3.200787) (xy 422.637854 -3.099892)
			(xy 422.734644 -3.004513) (xy 422.836864 -2.914979) (xy 422.944163 -2.831598) (xy 423.05617 -2.754658)
			(xy 423.1725 -2.684424) (xy 423.292751 -2.621138) (xy 423.416509 -2.565018) (xy 423.543347 -2.516258)
			(xy 423.672828 -2.475026) (xy 423.804506 -2.441465) (xy 423.937926 -2.415688) (xy 424.072629 -2.397787)
			(xy 424.208151 -2.387821) (xy 424.344024 -2.385826) (xy 424.479779 -2.391809) (xy 424.61495 -2.405749)
			(xy 424.749069 -2.427597) (xy 424.881676 -2.457279) (xy 425.012311 -2.494692) (xy 425.140526 -2.539707)
			(xy 425.265878 -2.592169) (xy 425.387935 -2.651898) (xy 425.506276 -2.718687) (xy 425.620494 -2.792306)
			(xy 425.730194 -2.872501) (xy 425.834999 -2.958996) (xy 425.934547 -3.051492) (xy 426.028495 -3.149671)
			(xy 426.116519 -3.253195) (xy 426.198316 -3.361706) (xy 426.273603 -3.474831) (xy 426.342122 -3.592179)
			(xy 426.403636 -3.713346) (xy 426.457933 -3.837915) (xy 426.504825 -3.965455) (xy 426.544152 -4.095527)
			(xy 426.575777 -4.227683) (xy 426.599592 -4.361468) (xy 426.615515 -4.496419) (xy 426.623489 -4.632072)
			(xy 426.623988 -4.700016) (xy 426.623489 -4.76796) (xy 426.615515 -4.903613) (xy 426.599592 -5.038564)
			(xy 426.575777 -5.172349) (xy 426.544152 -5.304505) (xy 426.504825 -5.434577) (xy 426.457933 -5.562117)
			(xy 426.403636 -5.686686) (xy 426.342122 -5.807853) (xy 426.273603 -5.925201) (xy 426.198316 -6.038326)
			(xy 426.116519 -6.146837) (xy 426.028495 -6.250361) (xy 425.934547 -6.34854) (xy 425.834999 -6.441036)
			(xy 425.730194 -6.527531) (xy 425.620494 -6.607726) (xy 425.506276 -6.681345) (xy 425.387935 -6.748134)
			(xy 425.265878 -6.807863) (xy 425.140526 -6.860325) (xy 425.012311 -6.90534) (xy 424.881676 -6.942753)
			(xy 424.749069 -6.972435) (xy 424.61495 -6.994283) (xy 424.479779 -7.008223) (xy 424.344024 -7.014206)
			(xy 424.208151 -7.012211) (xy 424.072629 -7.002245) (xy 423.937926 -6.984344) (xy 423.804506 -6.958567)
			(xy 423.672828 -6.925006) (xy 423.543347 -6.883774) (xy 423.416509 -6.835014) (xy 423.292751 -6.778894)
			(xy 423.1725 -6.715608) (xy 423.05617 -6.645374) (xy 422.944163 -6.568434) (xy 422.836864 -6.485053)
			(xy 422.734644 -6.395519) (xy 422.637854 -6.30014) (xy 422.546829 -6.199245) (xy 422.461882 -6.093182)
			(xy 422.383306 -5.982316) (xy 422.311372 -5.86703) (xy 422.246327 -5.747721) (xy 422.188397 -5.6248)
			(xy 422.137781 -5.498692) (xy 422.094652 -5.36983) (xy 422.059161 -5.238659) (xy 422.031429 -5.105631)
			(xy 422.011552 -4.971206) (xy 421.999598 -4.835845) (xy 421.995609 -4.700016) (xy 419.80993 -4.700016)
		)
		(stroke
			(width 0)
			(type solid)
		)
		(fill yes)
		(layer "B.Cu")
		(net "GND")
	)
	(gr_poly
		(pts
			(xy 0.499872 -34.99993) (xy 0.500295 -35.075331) (xy 0.989549 -35.075331) (xy 0.989944 -34.907967)
			(xy 0.998314 -34.740813) (xy 1.014639 -34.574246) (xy 1.038884 -34.408648) (xy 1.070993 -34.244392)
			(xy 1.110892 -34.081853) (xy 1.158491 -33.9214) (xy 1.213683 -33.763398) (xy 1.276341 -33.608206)
			(xy 1.346323 -33.456175) (xy 1.423471 -33.307652) (xy 1.507609 -33.162974) (xy 1.598545 -33.02247)
			(xy 1.696074 -32.886459) (xy 1.799973 -32.755251) (xy 1.910007 -32.629142) (xy 2.025925 -32.50842)
			(xy 2.086356 -32.450532) (xy 2.110056 -32.427339) (xy 2.151613 -32.375665) (xy 2.185811 -32.318852)
			(xy 2.212021 -32.25794) (xy 2.229764 -32.194046) (xy 2.238715 -32.128342) (xy 2.239264 -32.095186)
			(xy 2.239264 -28.999942) (xy 2.23976 -28.932938) (xy 2.247699 -28.799166) (xy 2.263549 -28.666099)
			(xy 2.287253 -28.534204) (xy 2.31873 -28.403946) (xy 2.357868 -28.275781) (xy 2.404529 -28.15016)
			(xy 2.458551 -28.027523) (xy 2.519743 -27.908302) (xy 2.58789 -27.792916) (xy 2.662753 -27.681769)
			(xy 2.744069 -27.575253) (xy 2.831552 -27.47374) (xy 2.924895 -27.377589) (xy 3.02377 -27.287136)
			(xy 3.12783 -27.202699) (xy 3.23671 -27.124576) (xy 3.350026 -27.053039) (xy 3.467381 -26.988341)
			(xy 3.588363 -26.930709) (xy 3.712547 -26.880346) (xy 3.839495 -26.837427) (xy 3.968764 -26.802104)
			(xy 4.099898 -26.774502) (xy 4.232437 -26.754716) (xy 4.365915 -26.742817) (xy 4.499864 -26.738846)
			(xy 4.633813 -26.742817) (xy 4.767291 -26.754716) (xy 4.89983 -26.774502) (xy 5.030964 -26.802104)
			(xy 5.160233 -26.837427) (xy 5.287181 -26.880346) (xy 5.411365 -26.930709) (xy 5.532347 -26.988341)
			(xy 5.649702 -27.053039) (xy 5.763018 -27.124576) (xy 5.871898 -27.202699) (xy 5.975958 -27.287136)
			(xy 6.074833 -27.377589) (xy 6.168176 -27.47374) (xy 6.255659 -27.575253) (xy 6.336975 -27.681769)
			(xy 6.411838 -27.792916) (xy 6.479985 -27.908302) (xy 6.541177 -28.027523) (xy 6.595199 -28.15016)
			(xy 6.64186 -28.275781) (xy 6.680998 -28.403946) (xy 6.712475 -28.534204) (xy 6.736179 -28.666099)
			(xy 6.752029 -28.799166) (xy 6.759968 -28.932938) (xy 6.760464 -28.999942) (xy 6.760464 -32.095186)
			(xy 6.761047 -32.128339) (xy 6.770007 -32.194038) (xy 6.787752 -32.257926) (xy 6.813957 -32.318835)
			(xy 6.848142 -32.37565) (xy 6.889683 -32.427331) (xy 6.913372 -32.450532) (xy 6.973803 -32.50842)
			(xy 7.089721 -32.629142) (xy 7.199755 -32.755251) (xy 7.303654 -32.886459) (xy 7.401183 -33.02247)
			(xy 7.492119 -33.162974) (xy 7.576257 -33.307652) (xy 7.653405 -33.456175) (xy 7.723387 -33.608206)
			(xy 7.786045 -33.763398) (xy 7.841237 -33.9214) (xy 7.888836 -34.081853) (xy 7.928735 -34.244392)
			(xy 7.960844 -34.408648) (xy 7.985089 -34.574246) (xy 8.001414 -34.740813) (xy 8.009784 -34.907967)
			(xy 8.010179 -35.075331) (xy 8.002598 -35.242524) (xy 7.987058 -35.409165) (xy 7.963595 -35.574877)
			(xy 7.932262 -35.739282) (xy 7.89313 -35.902007) (xy 7.846288 -36.062682) (xy 7.791843 -36.220943)
			(xy 7.729917 -36.37643) (xy 7.660653 -36.528789) (xy 7.584207 -36.677674) (xy 7.500753 -36.822747)
			(xy 7.41048 -36.963679) (xy 7.313595 -37.100148) (xy 7.210316 -37.231846) (xy 7.100878 -37.358472)
			(xy 6.985531 -37.47974) (xy 6.864536 -37.595373) (xy 6.738168 -37.705109) (xy 6.606714 -37.808698)
			(xy 6.470474 -37.905906) (xy 6.329756 -37.99651) (xy 6.18488 -38.080306) (xy 6.036175 -38.157104)
			(xy 5.88398 -38.226727) (xy 5.72864 -38.289019) (xy 5.570508 -38.343838) (xy 5.409943 -38.391059)
			(xy 5.247311 -38.430574) (xy 5.08298 -38.462295) (xy 4.917324 -38.486149) (xy 4.75072 -38.502082)
			(xy 4.583546 -38.510057) (xy 4.416182 -38.510057) (xy 4.249008 -38.502082) (xy 4.082404 -38.486149)
			(xy 3.916748 -38.462295) (xy 3.752417 -38.430574) (xy 3.589785 -38.391059) (xy 3.42922 -38.343838)
			(xy 3.271088 -38.289019) (xy 3.115748 -38.226727) (xy 2.963553 -38.157104) (xy 2.814848 -38.080306)
			(xy 2.669972 -37.99651) (xy 2.529254 -37.905906) (xy 2.393014 -37.808698) (xy 2.26156 -37.705109)
			(xy 2.135192 -37.595373) (xy 2.014197 -37.47974) (xy 1.89885 -37.358472) (xy 1.789412 -37.231846)
			(xy 1.686133 -37.100148) (xy 1.589248 -36.963679) (xy 1.498975 -36.822747) (xy 1.415521 -36.677674)
			(xy 1.339075 -36.528789) (xy 1.269811 -36.37643) (xy 1.207885 -36.220943) (xy 1.15344 -36.062682)
			(xy 1.106598 -35.902007) (xy 1.067466 -35.739282) (xy 1.036133 -35.574877) (xy 1.01267 -35.409165)
			(xy 0.99713 -35.242524) (xy 0.989549 -35.075331) (xy 0.500295 -35.075331) (xy 0.500376 -35.089693)
			(xy 0.50843 -35.269039) (xy 0.524523 -35.447843) (xy 0.548621 -35.625745) (xy 0.580677 -35.802387)
			(xy 0.620625 -35.977413) (xy 0.668386 -36.15047) (xy 0.723863 -36.32121) (xy 0.786944 -36.489289)
			(xy 0.857503 -36.654369) (xy 0.935396 -36.816117) (xy 1.020469 -36.974207) (xy 1.112548 -37.128322)
			(xy 1.211448 -37.27815) (xy 1.316972 -37.42339) (xy 1.428905 -37.56375) (xy 1.547022 -37.698946)
			(xy 1.671087 -37.828707) (xy 1.800848 -37.952772) (xy 1.936044 -38.070889) (xy 2.076404 -38.182822)
			(xy 2.221644 -38.288346) (xy 2.371472 -38.387246) (xy 2.525587 -38.479325) (xy 2.683677 -38.564398)
			(xy 2.845425 -38.642291) (xy 3.010505 -38.71285) (xy 3.178584 -38.775931) (xy 3.349324 -38.831408)
			(xy 3.522381 -38.879169) (xy 3.697407 -38.919117) (xy 3.874049 -38.951173) (xy 4.051951 -38.975271)
			(xy 4.230755 -38.991364) (xy 4.410101 -38.999418) (xy 4.589627 -38.999418) (xy 4.768973 -38.991364)
			(xy 4.947777 -38.975271) (xy 5.125679 -38.951173) (xy 5.302321 -38.919117) (xy 5.477347 -38.879169)
			(xy 5.650404 -38.831408) (xy 5.821144 -38.775931) (xy 5.989223 -38.71285) (xy 6.154303 -38.642291)
			(xy 6.316051 -38.564398) (xy 6.474141 -38.479325) (xy 6.628256 -38.387246) (xy 6.778084 -38.288346)
			(xy 6.923324 -38.182822) (xy 7.063684 -38.070889) (xy 7.19888 -37.952772) (xy 7.328641 -37.828707)
			(xy 7.452706 -37.698946) (xy 7.570823 -37.56375) (xy 7.682756 -37.42339) (xy 7.78828 -37.27815) (xy 7.88718 -37.128322)
			(xy 7.979259 -36.974207) (xy 8.064332 -36.816117) (xy 8.142225 -36.654369) (xy 8.212784 -36.489289)
			(xy 8.275865 -36.32121) (xy 8.331342 -36.15047) (xy 8.379103 -35.977413) (xy 8.419051 -35.802387)
			(xy 8.451107 -35.625745) (xy 8.475205 -35.447843) (xy 8.491298 -35.269039) (xy 8.499352 -35.089693)
			(xy 8.499856 -34.99993) (xy 8.499856 -28.999942) (xy 8.499352 -28.910179) (xy 8.491298 -28.730833)
			(xy 8.475205 -28.552029) (xy 8.451107 -28.374127) (xy 8.419051 -28.197485) (xy 8.379103 -28.022459)
			(xy 8.331342 -27.849402) (xy 8.275865 -27.678662) (xy 8.212784 -27.510583) (xy 8.142225 -27.345503)
			(xy 8.064332 -27.183755) (xy 7.979259 -27.025665) (xy 7.88718 -26.87155) (xy 7.78828 -26.721722)
			(xy 7.682756 -26.576482) (xy 7.570823 -26.436122) (xy 7.452706 -26.300926) (xy 7.328641 -26.171165)
			(xy 7.19888 -26.0471) (xy 7.063684 -25.928983) (xy 6.923324 -25.81705) (xy 6.778084 -25.711526) (xy 6.628256 -25.612626)
			(xy 6.474141 -25.520547) (xy 6.316051 -25.435474) (xy 6.154303 -25.357581) (xy 5.989223 -25.287022)
			(xy 5.821144 -25.223941) (xy 5.650404 -25.168464) (xy 5.477347 -25.120703) (xy 5.302321 -25.080755)
			(xy 5.125679 -25.048699) (xy 4.947777 -25.024601) (xy 4.768973 -25.008508) (xy 4.589627 -25.000454)
			(xy 4.410101 -25.000454) (xy 4.230755 -25.008508) (xy 4.051951 -25.024601) (xy 3.874049 -25.048699)
			(xy 3.697407 -25.080755) (xy 3.522381 -25.120703) (xy 3.349324 -25.168464) (xy 3.178584 -25.223941)
			(xy 3.010505 -25.287022) (xy 2.845425 -25.357581) (xy 2.683677 -25.435474) (xy 2.525587 -25.520547)
			(xy 2.371472 -25.612626) (xy 2.221644 -25.711526) (xy 2.076404 -25.81705) (xy 1.936044 -25.928983)
			(xy 1.800848 -26.0471) (xy 1.671087 -26.171165) (xy 1.547022 -26.300926) (xy 1.428905 -26.436122)
			(xy 1.316972 -26.576482) (xy 1.211448 -26.721722) (xy 1.112548 -26.87155) (xy 1.020469 -27.025665)
			(xy 0.935396 -27.183755) (xy 0.857503 -27.345503) (xy 0.786944 -27.510583) (xy 0.723863 -27.678662)
			(xy 0.668386 -27.849402) (xy 0.620625 -28.022459) (xy 0.580677 -28.197485) (xy 0.548621 -28.374127)
			(xy 0.524523 -28.552029) (xy 0.50843 -28.730833) (xy 0.500376 -28.910179) (xy 0.499872 -28.999942)
		)
		(stroke
			(width 0)
			(type solid)
		)
		(fill yes)
		(layer "B.Cu")
		(net "GND")
	)
	(gr_poly
		(pts
			(xy 75.81011 -47.500032) (xy 75.810533 -47.575433) (xy 76.299787 -47.575433) (xy 76.300182 -47.408069)
			(xy 76.308552 -47.240915) (xy 76.324877 -47.074348) (xy 76.349122 -46.90875) (xy 76.381231 -46.744494)
			(xy 76.42113 -46.581955) (xy 76.468729 -46.421502) (xy 76.523921 -46.2635) (xy 76.586579 -46.108308)
			(xy 76.656561 -45.956277) (xy 76.733709 -45.807754) (xy 76.817847 -45.663076) (xy 76.908783 -45.522572)
			(xy 77.006312 -45.386561) (xy 77.110211 -45.255353) (xy 77.220245 -45.129244) (xy 77.336163 -45.008522)
			(xy 77.396594 -44.950634) (xy 77.420287 -44.927434) (xy 77.461844 -44.875761) (xy 77.496041 -44.818949)
			(xy 77.522252 -44.758039) (xy 77.539997 -44.694147) (xy 77.548951 -44.628443) (xy 77.549502 -44.595288)
			(xy 77.549502 -41.500044) (xy 77.549998 -41.43304) (xy 77.557937 -41.299268) (xy 77.573787 -41.166201)
			(xy 77.597491 -41.034306) (xy 77.628968 -40.904048) (xy 77.668106 -40.775883) (xy 77.714767 -40.650262)
			(xy 77.768789 -40.527625) (xy 77.829981 -40.408404) (xy 77.898128 -40.293018) (xy 77.972991 -40.181871)
			(xy 78.054307 -40.075355) (xy 78.14179 -39.973842) (xy 78.235133 -39.877691) (xy 78.334008 -39.787238)
			(xy 78.438068 -39.702801) (xy 78.546948 -39.624678) (xy 78.660264 -39.553141) (xy 78.777619 -39.488443)
			(xy 78.898601 -39.430811) (xy 79.022785 -39.380448) (xy 79.149733 -39.337529) (xy 79.279002 -39.302206)
			(xy 79.410136 -39.274604) (xy 79.542675 -39.254818) (xy 79.676153 -39.242919) (xy 79.810102 -39.238948)
			(xy 79.944051 -39.242919) (xy 80.077529 -39.254818) (xy 80.210068 -39.274604) (xy 80.341202 -39.302206)
			(xy 80.470471 -39.337529) (xy 80.597419 -39.380448) (xy 80.721603 -39.430811) (xy 80.842585 -39.488443)
			(xy 80.95994 -39.553141) (xy 81.073256 -39.624678) (xy 81.182136 -39.702801) (xy 81.286196 -39.787238)
			(xy 81.385071 -39.877691) (xy 81.478414 -39.973842) (xy 81.565897 -40.075355) (xy 81.647213 -40.181871)
			(xy 81.722076 -40.293018) (xy 81.790223 -40.408404) (xy 81.851415 -40.527625) (xy 81.905437 -40.650262)
			(xy 81.952098 -40.775883) (xy 81.991236 -40.904048) (xy 82.022713 -41.034306) (xy 82.046417 -41.166201)
			(xy 82.062267 -41.299268) (xy 82.070206 -41.43304) (xy 82.070702 -41.500044) (xy 82.070702 -44.595288)
			(xy 82.071271 -44.628442) (xy 82.080233 -44.694141) (xy 82.09798 -44.75803) (xy 82.124187 -44.818939)
			(xy 82.158375 -44.875754) (xy 82.199919 -44.927434) (xy 82.22361 -44.950634) (xy 82.284041 -45.008522)
			(xy 82.399959 -45.129244) (xy 82.509993 -45.255353) (xy 82.613892 -45.386561) (xy 82.711421 -45.522572)
			(xy 82.802357 -45.663076) (xy 82.886495 -45.807754) (xy 82.963643 -45.956277) (xy 83.033625 -46.108308)
			(xy 83.096283 -46.2635) (xy 83.151475 -46.421502) (xy 83.199074 -46.581955) (xy 83.238973 -46.744494)
			(xy 83.271082 -46.90875) (xy 83.295327 -47.074348) (xy 83.311652 -47.240915) (xy 83.320022 -47.408069)
			(xy 83.320417 -47.575433) (xy 83.312836 -47.742626) (xy 83.297296 -47.909267) (xy 83.273833 -48.074979)
			(xy 83.2425 -48.239384) (xy 83.203368 -48.402109) (xy 83.156526 -48.562784) (xy 83.102081 -48.721045)
			(xy 83.040155 -48.876532) (xy 82.970891 -49.028891) (xy 82.894445 -49.177776) (xy 82.810991 -49.322849)
			(xy 82.720718 -49.463781) (xy 82.623833 -49.60025) (xy 82.520554 -49.731948) (xy 82.411116 -49.858574)
			(xy 82.295769 -49.979842) (xy 82.174774 -50.095475) (xy 82.048406 -50.205211) (xy 81.916952 -50.3088)
			(xy 81.780712 -50.406008) (xy 81.639994 -50.496612) (xy 81.495118 -50.580408) (xy 81.346413 -50.657206)
			(xy 81.194218 -50.726829) (xy 81.038878 -50.789121) (xy 80.880746 -50.84394) (xy 80.720181 -50.891161)
			(xy 80.557549 -50.930676) (xy 80.393218 -50.962397) (xy 80.227562 -50.986251) (xy 80.060958 -51.002184)
			(xy 79.893784 -51.010159) (xy 79.72642 -51.010159) (xy 79.559246 -51.002184) (xy 79.392642 -50.986251)
			(xy 79.226986 -50.962397) (xy 79.062655 -50.930676) (xy 78.900023 -50.891161) (xy 78.739458 -50.84394)
			(xy 78.581326 -50.789121) (xy 78.425986 -50.726829) (xy 78.273791 -50.657206) (xy 78.125086 -50.580408)
			(xy 77.98021 -50.496612) (xy 77.839492 -50.406008) (xy 77.703252 -50.3088) (xy 77.571798 -50.205211)
			(xy 77.44543 -50.095475) (xy 77.324435 -49.979842) (xy 77.209088 -49.858574) (xy 77.09965 -49.731948)
			(xy 76.996371 -49.60025) (xy 76.899486 -49.463781) (xy 76.809213 -49.322849) (xy 76.725759 -49.177776)
			(xy 76.649313 -49.028891) (xy 76.580049 -48.876532) (xy 76.518123 -48.721045) (xy 76.463678 -48.562784)
			(xy 76.416836 -48.402109) (xy 76.377704 -48.239384) (xy 76.346371 -48.074979) (xy 76.322908 -47.909267)
			(xy 76.307368 -47.742626) (xy 76.299787 -47.575433) (xy 75.810533 -47.575433) (xy 75.810614 -47.589795)
			(xy 75.818668 -47.769141) (xy 75.834761 -47.947945) (xy 75.858859 -48.125847) (xy 75.890915 -48.302489)
			(xy 75.930863 -48.477515) (xy 75.978624 -48.650572) (xy 76.034101 -48.821312) (xy 76.097182 -48.989391)
			(xy 76.167741 -49.154471) (xy 76.245634 -49.316219) (xy 76.330707 -49.474309) (xy 76.422786 -49.628424)
			(xy 76.521686 -49.778252) (xy 76.62721 -49.923492) (xy 76.739143 -50.063852) (xy 76.85726 -50.199048)
			(xy 76.981325 -50.328809) (xy 77.111086 -50.452874) (xy 77.246282 -50.570991) (xy 77.386642 -50.682924)
			(xy 77.531882 -50.788448) (xy 77.68171 -50.887348) (xy 77.835825 -50.979427) (xy 77.993915 -51.0645)
			(xy 78.155663 -51.142393) (xy 78.320743 -51.212952) (xy 78.488822 -51.276033) (xy 78.659562 -51.33151)
			(xy 78.832619 -51.379271) (xy 79.007645 -51.419219) (xy 79.184287 -51.451275) (xy 79.362189 -51.475373)
			(xy 79.540993 -51.491466) (xy 79.720339 -51.49952) (xy 79.899865 -51.49952) (xy 80.079211 -51.491466)
			(xy 80.258015 -51.475373) (xy 80.435917 -51.451275) (xy 80.612559 -51.419219) (xy 80.787585 -51.379271)
			(xy 80.960642 -51.33151) (xy 81.131382 -51.276033) (xy 81.299461 -51.212952) (xy 81.464541 -51.142393)
			(xy 81.626289 -51.0645) (xy 81.784379 -50.979427) (xy 81.938494 -50.887348) (xy 82.088322 -50.788448)
			(xy 82.233562 -50.682924) (xy 82.373922 -50.570991) (xy 82.509118 -50.452874) (xy 82.638879 -50.328809)
			(xy 82.762944 -50.199048) (xy 82.881061 -50.063852) (xy 82.992994 -49.923492) (xy 83.098518 -49.778252)
			(xy 83.197418 -49.628424) (xy 83.289497 -49.474309) (xy 83.37457 -49.316219) (xy 83.452463 -49.154471)
			(xy 83.523022 -48.989391) (xy 83.586103 -48.821312) (xy 83.64158 -48.650572) (xy 83.689341 -48.477515)
			(xy 83.729289 -48.302489) (xy 83.761345 -48.125847) (xy 83.785443 -47.947945) (xy 83.801536 -47.769141)
			(xy 83.80959 -47.589795) (xy 83.810094 -47.500032) (xy 83.810094 -41.500044) (xy 83.80959 -41.410281)
			(xy 83.801536 -41.230935) (xy 83.785443 -41.052131) (xy 83.761345 -40.874229) (xy 83.729289 -40.697587)
			(xy 83.689341 -40.522561) (xy 83.64158 -40.349504) (xy 83.586103 -40.178764) (xy 83.523022 -40.010685)
			(xy 83.452463 -39.845605) (xy 83.37457 -39.683857) (xy 83.289497 -39.525767) (xy 83.197418 -39.371652)
			(xy 83.098518 -39.221824) (xy 82.992994 -39.076584) (xy 82.881061 -38.936224) (xy 82.762944 -38.801028)
			(xy 82.638879 -38.671267) (xy 82.509118 -38.547202) (xy 82.373922 -38.429085) (xy 82.233562 -38.317152)
			(xy 82.088322 -38.211628) (xy 81.938494 -38.112728) (xy 81.784379 -38.020649) (xy 81.626289 -37.935576)
			(xy 81.464541 -37.857683) (xy 81.299461 -37.787124) (xy 81.131382 -37.724043) (xy 80.960642 -37.668566)
			(xy 80.787585 -37.620805) (xy 80.612559 -37.580857) (xy 80.435917 -37.548801) (xy 80.258015 -37.524703)
			(xy 80.079211 -37.50861) (xy 79.899865 -37.500556) (xy 79.720339 -37.500556) (xy 79.540993 -37.50861)
			(xy 79.362189 -37.524703) (xy 79.184287 -37.548801) (xy 79.007645 -37.580857) (xy 78.832619 -37.620805)
			(xy 78.659562 -37.668566) (xy 78.488822 -37.724043) (xy 78.320743 -37.787124) (xy 78.155663 -37.857683)
			(xy 77.993915 -37.935576) (xy 77.835825 -38.020649) (xy 77.68171 -38.112728) (xy 77.531882 -38.211628)
			(xy 77.386642 -38.317152) (xy 77.246282 -38.429085) (xy 77.111086 -38.547202) (xy 76.981325 -38.671267)
			(xy 76.85726 -38.801028) (xy 76.739143 -38.936224) (xy 76.62721 -39.076584) (xy 76.521686 -39.221824)
			(xy 76.422786 -39.371652) (xy 76.330707 -39.525767) (xy 76.245634 -39.683857) (xy 76.167741 -39.845605)
			(xy 76.097182 -40.010685) (xy 76.034101 -40.178764) (xy 75.978624 -40.349504) (xy 75.930863 -40.522561)
			(xy 75.890915 -40.697587) (xy 75.858859 -40.874229) (xy 75.834761 -41.052131) (xy 75.818668 -41.230935)
			(xy 75.810614 -41.410281) (xy 75.81011 -41.500044)
		)
		(stroke
			(width 0)
			(type solid)
		)
		(fill yes)
		(layer "B.Cu")
		(net "GND")
	)
	(gr_poly
		(pts
			(xy 195.049902 -10.700004) (xy 195.050325 -10.775405) (xy 195.539579 -10.775405) (xy 195.539974 -10.608041)
			(xy 195.548344 -10.440887) (xy 195.564669 -10.27432) (xy 195.588914 -10.108722) (xy 195.621023 -9.944466)
			(xy 195.660922 -9.781927) (xy 195.708521 -9.621474) (xy 195.763713 -9.463472) (xy 195.826371 -9.30828)
			(xy 195.896353 -9.156249) (xy 195.973501 -9.007726) (xy 196.057639 -8.863048) (xy 196.148575 -8.722544)
			(xy 196.246104 -8.586533) (xy 196.350003 -8.455325) (xy 196.460037 -8.329216) (xy 196.575955 -8.208494)
			(xy 196.636386 -8.150606) (xy 196.660091 -8.127418) (xy 196.701647 -8.075742) (xy 196.735843 -8.018928)
			(xy 196.762052 -7.958015) (xy 196.779794 -7.894121) (xy 196.788745 -7.828416) (xy 196.789294 -7.79526)
			(xy 196.789294 -4.700016) (xy 196.78979 -4.633012) (xy 196.797729 -4.49924) (xy 196.813579 -4.366173)
			(xy 196.837283 -4.234278) (xy 196.86876 -4.10402) (xy 196.907898 -3.975855) (xy 196.954559 -3.850234)
			(xy 197.008581 -3.727597) (xy 197.069773 -3.608376) (xy 197.13792 -3.49299) (xy 197.212783 -3.381843)
			(xy 197.294099 -3.275327) (xy 197.381582 -3.173814) (xy 197.474925 -3.077663) (xy 197.5738 -2.98721)
			(xy 197.67786 -2.902773) (xy 197.78674 -2.82465) (xy 197.900056 -2.753113) (xy 198.017411 -2.688415)
			(xy 198.138393 -2.630783) (xy 198.262577 -2.58042) (xy 198.389525 -2.537501) (xy 198.518794 -2.502178)
			(xy 198.649928 -2.474576) (xy 198.782467 -2.45479) (xy 198.915945 -2.442891) (xy 199.049894 -2.43892)
			(xy 199.183843 -2.442891) (xy 199.317321 -2.45479) (xy 199.44986 -2.474576) (xy 199.580994 -2.502178)
			(xy 199.710263 -2.537501) (xy 199.837211 -2.58042) (xy 199.961395 -2.630783) (xy 200.082377 -2.688415)
			(xy 200.199732 -2.753113) (xy 200.313048 -2.82465) (xy 200.421928 -2.902773) (xy 200.525988 -2.98721)
			(xy 200.624863 -3.077663) (xy 200.718206 -3.173814) (xy 200.805689 -3.275327) (xy 200.887005 -3.381843)
			(xy 200.961868 -3.49299) (xy 201.030015 -3.608376) (xy 201.091207 -3.727597) (xy 201.145229 -3.850234)
			(xy 201.19189 -3.975855) (xy 201.231028 -4.10402) (xy 201.262505 -4.234278) (xy 201.286209 -4.366173)
			(xy 201.302059 -4.49924) (xy 201.309998 -4.633012) (xy 201.310494 -4.700016) (xy 201.310494 -7.79526)
			(xy 201.311019 -7.828415) (xy 201.319989 -7.894117) (xy 201.337745 -7.958006) (xy 201.363961 -8.018915)
			(xy 201.398157 -8.075729) (xy 201.439708 -8.127407) (xy 201.463402 -8.150606) (xy 201.523833 -8.208494)
			(xy 201.639751 -8.329216) (xy 201.749785 -8.455325) (xy 201.853684 -8.586533) (xy 201.951213 -8.722544)
			(xy 202.042149 -8.863048) (xy 202.126287 -9.007726) (xy 202.203435 -9.156249) (xy 202.273417 -9.30828)
			(xy 202.336075 -9.463472) (xy 202.391267 -9.621474) (xy 202.438866 -9.781927) (xy 202.478765 -9.944466)
			(xy 202.510874 -10.108722) (xy 202.535119 -10.27432) (xy 202.551444 -10.440887) (xy 202.559814 -10.608041)
			(xy 202.560209 -10.775405) (xy 202.552628 -10.942598) (xy 202.537088 -11.109239) (xy 202.513625 -11.274951)
			(xy 202.482292 -11.439356) (xy 202.44316 -11.602081) (xy 202.396318 -11.762756) (xy 202.341873 -11.921017)
			(xy 202.279947 -12.076504) (xy 202.210683 -12.228863) (xy 202.134237 -12.377748) (xy 202.050783 -12.522821)
			(xy 201.96051 -12.663753) (xy 201.863625 -12.800222) (xy 201.760346 -12.93192) (xy 201.650908 -13.058546)
			(xy 201.535561 -13.179814) (xy 201.414566 -13.295447) (xy 201.288198 -13.405183) (xy 201.156744 -13.508772)
			(xy 201.020504 -13.60598) (xy 200.879786 -13.696584) (xy 200.73491 -13.78038) (xy 200.586205 -13.857178)
			(xy 200.43401 -13.926801) (xy 200.27867 -13.989093) (xy 200.120538 -14.043912) (xy 199.959973 -14.091133)
			(xy 199.797341 -14.130648) (xy 199.63301 -14.162369) (xy 199.467354 -14.186223) (xy 199.30075 -14.202156)
			(xy 199.133576 -14.210131) (xy 198.966212 -14.210131) (xy 198.799038 -14.202156) (xy 198.632434 -14.186223)
			(xy 198.466778 -14.162369) (xy 198.302447 -14.130648) (xy 198.139815 -14.091133) (xy 197.97925 -14.043912)
			(xy 197.821118 -13.989093) (xy 197.665778 -13.926801) (xy 197.513583 -13.857178) (xy 197.364878 -13.78038)
			(xy 197.220002 -13.696584) (xy 197.079284 -13.60598) (xy 196.943044 -13.508772) (xy 196.81159 -13.405183)
			(xy 196.685222 -13.295447) (xy 196.564227 -13.179814) (xy 196.44888 -13.058546) (xy 196.339442 -12.93192)
			(xy 196.236163 -12.800222) (xy 196.139278 -12.663753) (xy 196.049005 -12.522821) (xy 195.965551 -12.377748)
			(xy 195.889105 -12.228863) (xy 195.819841 -12.076504) (xy 195.757915 -11.921017) (xy 195.70347 -11.762756)
			(xy 195.656628 -11.602081) (xy 195.617496 -11.439356) (xy 195.586163 -11.274951) (xy 195.5627 -11.109239)
			(xy 195.54716 -10.942598) (xy 195.539579 -10.775405) (xy 195.050325 -10.775405) (xy 195.050406 -10.789767)
			(xy 195.05846 -10.969113) (xy 195.074553 -11.147917) (xy 195.098651 -11.325819) (xy 195.130707 -11.502461)
			(xy 195.170655 -11.677487) (xy 195.218416 -11.850544) (xy 195.273893 -12.021284) (xy 195.336974 -12.189363)
			(xy 195.407533 -12.354443) (xy 195.485426 -12.516191) (xy 195.570499 -12.674281) (xy 195.662578 -12.828396)
			(xy 195.761478 -12.978224) (xy 195.867002 -13.123464) (xy 195.978935 -13.263824) (xy 196.097052 -13.39902)
			(xy 196.221117 -13.528781) (xy 196.350878 -13.652846) (xy 196.486074 -13.770963) (xy 196.626434 -13.882896)
			(xy 196.771674 -13.98842) (xy 196.921502 -14.08732) (xy 197.075617 -14.179399) (xy 197.233707 -14.264472)
			(xy 197.395455 -14.342365) (xy 197.560535 -14.412924) (xy 197.728614 -14.476005) (xy 197.899354 -14.531482)
			(xy 198.072411 -14.579243) (xy 198.247437 -14.619191) (xy 198.424079 -14.651247) (xy 198.601981 -14.675345)
			(xy 198.780785 -14.691438) (xy 198.960131 -14.699492) (xy 199.139657 -14.699492) (xy 199.319003 -14.691438)
			(xy 199.497807 -14.675345) (xy 199.675709 -14.651247) (xy 199.852351 -14.619191) (xy 200.027377 -14.579243)
			(xy 200.200434 -14.531482) (xy 200.371174 -14.476005) (xy 200.539253 -14.412924) (xy 200.704333 -14.342365)
			(xy 200.866081 -14.264472) (xy 201.024171 -14.179399) (xy 201.178286 -14.08732) (xy 201.328114 -13.98842)
			(xy 201.473354 -13.882896) (xy 201.613714 -13.770963) (xy 201.74891 -13.652846) (xy 201.878671 -13.528781)
			(xy 202.002736 -13.39902) (xy 202.120853 -13.263824) (xy 202.232786 -13.123464) (xy 202.33831 -12.978224)
			(xy 202.43721 -12.828396) (xy 202.529289 -12.674281) (xy 202.614362 -12.516191) (xy 202.692255 -12.354443)
			(xy 202.762814 -12.189363) (xy 202.825895 -12.021284) (xy 202.881372 -11.850544) (xy 202.929133 -11.677487)
			(xy 202.969081 -11.502461) (xy 203.001137 -11.325819) (xy 203.025235 -11.147917) (xy 203.041328 -10.969113)
			(xy 203.049382 -10.789767) (xy 203.049886 -10.700004) (xy 203.049886 -4.700016) (xy 203.049382 -4.610253)
			(xy 203.041328 -4.430907) (xy 203.025235 -4.252103) (xy 203.001137 -4.074201) (xy 202.969081 -3.897559)
			(xy 202.929133 -3.722533) (xy 202.881372 -3.549476) (xy 202.825895 -3.378736) (xy 202.762814 -3.210657)
			(xy 202.692255 -3.045577) (xy 202.614362 -2.883829) (xy 202.529289 -2.725739) (xy 202.43721 -2.571624)
			(xy 202.33831 -2.421796) (xy 202.232786 -2.276556) (xy 202.120853 -2.136196) (xy 202.002736 -2.001)
			(xy 201.878671 -1.871239) (xy 201.74891 -1.747174) (xy 201.613714 -1.629057) (xy 201.473354 -1.517124)
			(xy 201.328114 -1.4116) (xy 201.178286 -1.3127) (xy 201.024171 -1.220621) (xy 200.866081 -1.135548)
			(xy 200.704333 -1.057655) (xy 200.539253 -0.987096) (xy 200.371174 -0.924015) (xy 200.200434 -0.868538)
			(xy 200.027377 -0.820777) (xy 199.852351 -0.780829) (xy 199.675709 -0.748773) (xy 199.497807 -0.724675)
			(xy 199.319003 -0.708582) (xy 199.139657 -0.700528) (xy 198.960131 -0.700528) (xy 198.780785 -0.708582)
			(xy 198.601981 -0.724675) (xy 198.424079 -0.748773) (xy 198.247437 -0.780829) (xy 198.072411 -0.820777)
			(xy 197.899354 -0.868538) (xy 197.728614 -0.924015) (xy 197.560535 -0.987096) (xy 197.395455 -1.057655)
			(xy 197.233707 -1.135548) (xy 197.075617 -1.220621) (xy 196.921502 -1.3127) (xy 196.771674 -1.4116)
			(xy 196.626434 -1.517124) (xy 196.486074 -1.629057) (xy 196.350878 -1.747174) (xy 196.221117 -1.871239)
			(xy 196.097052 -2.001) (xy 195.978935 -2.136196) (xy 195.867002 -2.276556) (xy 195.761478 -2.421796)
			(xy 195.662578 -2.571624) (xy 195.570499 -2.725739) (xy 195.485426 -2.883829) (xy 195.407533 -3.045577)
			(xy 195.336974 -3.210657) (xy 195.273893 -3.378736) (xy 195.218416 -3.549476) (xy 195.170655 -3.722533)
			(xy 195.130707 -3.897559) (xy 195.098651 -4.074201) (xy 195.074553 -4.252103) (xy 195.05846 -4.430907)
			(xy 195.050406 -4.610253) (xy 195.049902 -4.700016)
		)
		(stroke
			(width 0)
			(type solid)
		)
		(fill yes)
		(layer "B.Cu")
		(net "GND")
	)
	(gr_poly
		(pts
			(xy 205.810104 -47.500032) (xy 205.810527 -47.575433) (xy 206.299781 -47.575433) (xy 206.300176 -47.408069)
			(xy 206.308546 -47.240915) (xy 206.324871 -47.074348) (xy 206.349116 -46.90875) (xy 206.381225 -46.744494)
			(xy 206.421124 -46.581955) (xy 206.468723 -46.421502) (xy 206.523915 -46.2635) (xy 206.586573 -46.108308)
			(xy 206.656555 -45.956277) (xy 206.733703 -45.807754) (xy 206.817841 -45.663076) (xy 206.908777 -45.522572)
			(xy 207.006306 -45.386561) (xy 207.110205 -45.255353) (xy 207.220239 -45.129244) (xy 207.336157 -45.008522)
			(xy 207.396588 -44.950634) (xy 207.42028 -44.927433) (xy 207.461837 -44.87576) (xy 207.496034 -44.818948)
			(xy 207.522246 -44.758038) (xy 207.539991 -44.694146) (xy 207.548945 -44.628443) (xy 207.549496 -44.595288)
			(xy 207.549496 -41.500044) (xy 207.549992 -41.43304) (xy 207.557931 -41.299268) (xy 207.573781 -41.166201)
			(xy 207.597485 -41.034306) (xy 207.628962 -40.904048) (xy 207.6681 -40.775883) (xy 207.714761 -40.650262)
			(xy 207.768783 -40.527625) (xy 207.829975 -40.408404) (xy 207.898122 -40.293018) (xy 207.972985 -40.181871)
			(xy 208.054301 -40.075355) (xy 208.141784 -39.973842) (xy 208.235127 -39.877691) (xy 208.334002 -39.787238)
			(xy 208.438062 -39.702801) (xy 208.546942 -39.624678) (xy 208.660258 -39.553141) (xy 208.777613 -39.488443)
			(xy 208.898595 -39.430811) (xy 209.022779 -39.380448) (xy 209.149727 -39.337529) (xy 209.278996 -39.302206)
			(xy 209.41013 -39.274604) (xy 209.542669 -39.254818) (xy 209.676147 -39.242919) (xy 209.810096 -39.238948)
			(xy 209.944045 -39.242919) (xy 210.077523 -39.254818) (xy 210.210062 -39.274604) (xy 210.341196 -39.302206)
			(xy 210.470465 -39.337529) (xy 210.597413 -39.380448) (xy 210.721597 -39.430811) (xy 210.842579 -39.488443)
			(xy 210.959934 -39.553141) (xy 211.07325 -39.624678) (xy 211.18213 -39.702801) (xy 211.28619 -39.787238)
			(xy 211.385065 -39.877691) (xy 211.478408 -39.973842) (xy 211.565891 -40.075355) (xy 211.647207 -40.181871)
			(xy 211.72207 -40.293018) (xy 211.790217 -40.408404) (xy 211.851409 -40.527625) (xy 211.905431 -40.650262)
			(xy 211.952092 -40.775883) (xy 211.99123 -40.904048) (xy 212.022707 -41.034306) (xy 212.046411 -41.166201)
			(xy 212.062261 -41.299268) (xy 212.0702 -41.43304) (xy 212.070696 -41.500044) (xy 212.070696 -44.595288)
			(xy 212.071267 -44.628442) (xy 212.080229 -44.694141) (xy 212.097975 -44.75803) (xy 212.124182 -44.818939)
			(xy 212.15837 -44.875754) (xy 212.199913 -44.927434) (xy 212.223604 -44.950634) (xy 212.284035 -45.008522)
			(xy 212.399953 -45.129244) (xy 212.509987 -45.255353) (xy 212.613886 -45.386561) (xy 212.711415 -45.522572)
			(xy 212.802351 -45.663076) (xy 212.886489 -45.807754) (xy 212.963637 -45.956277) (xy 213.033619 -46.108308)
			(xy 213.096277 -46.2635) (xy 213.151469 -46.421502) (xy 213.199068 -46.581955) (xy 213.238967 -46.744494)
			(xy 213.271076 -46.90875) (xy 213.295321 -47.074348) (xy 213.311646 -47.240915) (xy 213.320016 -47.408069)
			(xy 213.320411 -47.575433) (xy 213.31283 -47.742626) (xy 213.29729 -47.909267) (xy 213.273827 -48.074979)
			(xy 213.242494 -48.239384) (xy 213.203362 -48.402109) (xy 213.15652 -48.562784) (xy 213.102075 -48.721045)
			(xy 213.040149 -48.876532) (xy 212.970885 -49.028891) (xy 212.894439 -49.177776) (xy 212.810985 -49.322849)
			(xy 212.720712 -49.463781) (xy 212.623827 -49.60025) (xy 212.520548 -49.731948) (xy 212.41111 -49.858574)
			(xy 212.295763 -49.979842) (xy 212.174768 -50.095475) (xy 212.0484 -50.205211) (xy 211.916946 -50.3088)
			(xy 211.780706 -50.406008) (xy 211.639988 -50.496612) (xy 211.495112 -50.580408) (xy 211.346407 -50.657206)
			(xy 211.194212 -50.726829) (xy 211.038872 -50.789121) (xy 210.88074 -50.84394) (xy 210.720175 -50.891161)
			(xy 210.557543 -50.930676) (xy 210.393212 -50.962397) (xy 210.227556 -50.986251) (xy 210.060952 -51.002184)
			(xy 209.893778 -51.010159) (xy 209.726414 -51.010159) (xy 209.55924 -51.002184) (xy 209.392636 -50.986251)
			(xy 209.22698 -50.962397) (xy 209.062649 -50.930676) (xy 208.900017 -50.891161) (xy 208.739452 -50.84394)
			(xy 208.58132 -50.789121) (xy 208.42598 -50.726829) (xy 208.273785 -50.657206) (xy 208.12508 -50.580408)
			(xy 207.980204 -50.496612) (xy 207.839486 -50.406008) (xy 207.703246 -50.3088) (xy 207.571792 -50.205211)
			(xy 207.445424 -50.095475) (xy 207.324429 -49.979842) (xy 207.209082 -49.858574) (xy 207.099644 -49.731948)
			(xy 206.996365 -49.60025) (xy 206.89948 -49.463781) (xy 206.809207 -49.322849) (xy 206.725753 -49.177776)
			(xy 206.649307 -49.028891) (xy 206.580043 -48.876532) (xy 206.518117 -48.721045) (xy 206.463672 -48.562784)
			(xy 206.41683 -48.402109) (xy 206.377698 -48.239384) (xy 206.346365 -48.074979) (xy 206.322902 -47.909267)
			(xy 206.307362 -47.742626) (xy 206.299781 -47.575433) (xy 205.810527 -47.575433) (xy 205.810608 -47.589795)
			(xy 205.818662 -47.769141) (xy 205.834755 -47.947945) (xy 205.858853 -48.125847) (xy 205.890909 -48.302489)
			(xy 205.930857 -48.477515) (xy 205.978618 -48.650572) (xy 206.034095 -48.821312) (xy 206.097176 -48.989391)
			(xy 206.167735 -49.154471) (xy 206.245628 -49.316219) (xy 206.330701 -49.474309) (xy 206.42278 -49.628424)
			(xy 206.52168 -49.778252) (xy 206.627204 -49.923492) (xy 206.739137 -50.063852) (xy 206.857254 -50.199048)
			(xy 206.981319 -50.328809) (xy 207.11108 -50.452874) (xy 207.246276 -50.570991) (xy 207.386636 -50.682924)
			(xy 207.531876 -50.788448) (xy 207.681704 -50.887348) (xy 207.835819 -50.979427) (xy 207.993909 -51.0645)
			(xy 208.155657 -51.142393) (xy 208.320737 -51.212952) (xy 208.488816 -51.276033) (xy 208.659556 -51.33151)
			(xy 208.832613 -51.379271) (xy 209.007639 -51.419219) (xy 209.184281 -51.451275) (xy 209.362183 -51.475373)
			(xy 209.540987 -51.491466) (xy 209.720333 -51.49952) (xy 209.899859 -51.49952) (xy 210.079205 -51.491466)
			(xy 210.258009 -51.475373) (xy 210.435911 -51.451275) (xy 210.612553 -51.419219) (xy 210.787579 -51.379271)
			(xy 210.960636 -51.33151) (xy 211.131376 -51.276033) (xy 211.299455 -51.212952) (xy 211.464535 -51.142393)
			(xy 211.626283 -51.0645) (xy 211.784373 -50.979427) (xy 211.938488 -50.887348) (xy 212.088316 -50.788448)
			(xy 212.233556 -50.682924) (xy 212.373916 -50.570991) (xy 212.509112 -50.452874) (xy 212.638873 -50.328809)
			(xy 212.762938 -50.199048) (xy 212.881055 -50.063852) (xy 212.992988 -49.923492) (xy 213.098512 -49.778252)
			(xy 213.197412 -49.628424) (xy 213.289491 -49.474309) (xy 213.374564 -49.316219) (xy 213.452457 -49.154471)
			(xy 213.523016 -48.989391) (xy 213.586097 -48.821312) (xy 213.641574 -48.650572) (xy 213.689335 -48.477515)
			(xy 213.729283 -48.302489) (xy 213.761339 -48.125847) (xy 213.785437 -47.947945) (xy 213.80153 -47.769141)
			(xy 213.809584 -47.589795) (xy 213.810088 -47.500032) (xy 213.810088 -41.500044) (xy 213.809584 -41.410281)
			(xy 213.80153 -41.230935) (xy 213.785437 -41.052131) (xy 213.761339 -40.874229) (xy 213.729283 -40.697587)
			(xy 213.689335 -40.522561) (xy 213.641574 -40.349504) (xy 213.586097 -40.178764) (xy 213.523016 -40.010685)
			(xy 213.452457 -39.845605) (xy 213.374564 -39.683857) (xy 213.289491 -39.525767) (xy 213.197412 -39.371652)
			(xy 213.098512 -39.221824) (xy 212.992988 -39.076584) (xy 212.881055 -38.936224) (xy 212.762938 -38.801028)
			(xy 212.638873 -38.671267) (xy 212.509112 -38.547202) (xy 212.373916 -38.429085) (xy 212.233556 -38.317152)
			(xy 212.088316 -38.211628) (xy 211.938488 -38.112728) (xy 211.784373 -38.020649) (xy 211.626283 -37.935576)
			(xy 211.464535 -37.857683) (xy 211.299455 -37.787124) (xy 211.131376 -37.724043) (xy 210.960636 -37.668566)
			(xy 210.787579 -37.620805) (xy 210.612553 -37.580857) (xy 210.435911 -37.548801) (xy 210.258009 -37.524703)
			(xy 210.079205 -37.50861) (xy 209.899859 -37.500556) (xy 209.720333 -37.500556) (xy 209.540987 -37.50861)
			(xy 209.362183 -37.524703) (xy 209.184281 -37.548801) (xy 209.007639 -37.580857) (xy 208.832613 -37.620805)
			(xy 208.659556 -37.668566) (xy 208.488816 -37.724043) (xy 208.320737 -37.787124) (xy 208.155657 -37.857683)
			(xy 207.993909 -37.935576) (xy 207.835819 -38.020649) (xy 207.681704 -38.112728) (xy 207.531876 -38.211628)
			(xy 207.386636 -38.317152) (xy 207.246276 -38.429085) (xy 207.11108 -38.547202) (xy 206.981319 -38.671267)
			(xy 206.857254 -38.801028) (xy 206.739137 -38.936224) (xy 206.627204 -39.076584) (xy 206.52168 -39.221824)
			(xy 206.42278 -39.371652) (xy 206.330701 -39.525767) (xy 206.245628 -39.683857) (xy 206.167735 -39.845605)
			(xy 206.097176 -40.010685) (xy 206.034095 -40.178764) (xy 205.978618 -40.349504) (xy 205.930857 -40.522561)
			(xy 205.890909 -40.697587) (xy 205.858853 -40.874229) (xy 205.834755 -41.052131) (xy 205.818662 -41.230935)
			(xy 205.810608 -41.410281) (xy 205.810104 -41.500044)
		)
		(stroke
			(width 0)
			(type solid)
		)
		(fill yes)
		(layer "B.Cu")
		(net "GND")
	)
	(gr_poly
		(pts
			(xy 275.810218 -10.700004) (xy 275.810641 -10.775405) (xy 276.299895 -10.775405) (xy 276.30029 -10.608041)
			(xy 276.30866 -10.440887) (xy 276.324985 -10.27432) (xy 276.34923 -10.108722) (xy 276.381339 -9.944466)
			(xy 276.421238 -9.781927) (xy 276.468837 -9.621474) (xy 276.524029 -9.463472) (xy 276.586687 -9.30828)
			(xy 276.656669 -9.156249) (xy 276.733817 -9.007726) (xy 276.817955 -8.863048) (xy 276.908891 -8.722544)
			(xy 277.00642 -8.586533) (xy 277.110319 -8.455325) (xy 277.220353 -8.329216) (xy 277.336271 -8.208494)
			(xy 277.396702 -8.150606) (xy 277.420392 -8.127402) (xy 277.461952 -8.075732) (xy 277.496152 -8.018921)
			(xy 277.522364 -7.958011) (xy 277.540109 -7.894119) (xy 277.549061 -7.828415) (xy 277.54961 -7.79526)
			(xy 277.54961 -4.700016) (xy 277.550106 -4.633012) (xy 277.558045 -4.49924) (xy 277.573895 -4.366173)
			(xy 277.597599 -4.234278) (xy 277.629076 -4.10402) (xy 277.668214 -3.975855) (xy 277.714875 -3.850234)
			(xy 277.768897 -3.727597) (xy 277.830089 -3.608376) (xy 277.898236 -3.49299) (xy 277.973099 -3.381843)
			(xy 278.054415 -3.275327) (xy 278.141898 -3.173814) (xy 278.235241 -3.077663) (xy 278.334116 -2.98721)
			(xy 278.438176 -2.902773) (xy 278.547056 -2.82465) (xy 278.660372 -2.753113) (xy 278.777727 -2.688415)
			(xy 278.898709 -2.630783) (xy 279.022893 -2.58042) (xy 279.149841 -2.537501) (xy 279.27911 -2.502178)
			(xy 279.410244 -2.474576) (xy 279.542783 -2.45479) (xy 279.676261 -2.442891) (xy 279.81021 -2.43892)
			(xy 279.944159 -2.442891) (xy 280.077637 -2.45479) (xy 280.210176 -2.474576) (xy 280.34131 -2.502178)
			(xy 280.470579 -2.537501) (xy 280.597527 -2.58042) (xy 280.721711 -2.630783) (xy 280.842693 -2.688415)
			(xy 280.960048 -2.753113) (xy 281.073364 -2.82465) (xy 281.182244 -2.902773) (xy 281.286304 -2.98721)
			(xy 281.385179 -3.077663) (xy 281.478522 -3.173814) (xy 281.566005 -3.275327) (xy 281.647321 -3.381843)
			(xy 281.722184 -3.49299) (xy 281.790331 -3.608376) (xy 281.851523 -3.727597) (xy 281.905545 -3.850234)
			(xy 281.952206 -3.975855) (xy 281.991344 -4.10402) (xy 282.022821 -4.234278) (xy 282.046525 -4.366173)
			(xy 282.062375 -4.49924) (xy 282.070314 -4.633012) (xy 282.07081 -4.700016) (xy 282.07081 -7.79526)
			(xy 282.07133 -7.828416) (xy 282.080301 -7.894117) (xy 282.098057 -7.958007) (xy 282.124274 -8.018916)
			(xy 282.158471 -8.07573) (xy 282.200023 -8.127408) (xy 282.223718 -8.150606) (xy 282.284149 -8.208494)
			(xy 282.400067 -8.329216) (xy 282.510101 -8.455325) (xy 282.614 -8.586533) (xy 282.711529 -8.722544)
			(xy 282.802465 -8.863048) (xy 282.886603 -9.007726) (xy 282.963751 -9.156249) (xy 283.033733 -9.30828)
			(xy 283.096391 -9.463472) (xy 283.151583 -9.621474) (xy 283.199182 -9.781927) (xy 283.239081 -9.944466)
			(xy 283.27119 -10.108722) (xy 283.295435 -10.27432) (xy 283.31176 -10.440887) (xy 283.32013 -10.608041)
			(xy 283.320525 -10.775405) (xy 283.312944 -10.942598) (xy 283.297404 -11.109239) (xy 283.273941 -11.274951)
			(xy 283.242608 -11.439356) (xy 283.203476 -11.602081) (xy 283.156634 -11.762756) (xy 283.102189 -11.921017)
			(xy 283.040263 -12.076504) (xy 282.970999 -12.228863) (xy 282.894553 -12.377748) (xy 282.811099 -12.522821)
			(xy 282.720826 -12.663753) (xy 282.623941 -12.800222) (xy 282.520662 -12.93192) (xy 282.411224 -13.058546)
			(xy 282.295877 -13.179814) (xy 282.174882 -13.295447) (xy 282.048514 -13.405183) (xy 281.91706 -13.508772)
			(xy 281.78082 -13.60598) (xy 281.640102 -13.696584) (xy 281.495226 -13.78038) (xy 281.346521 -13.857178)
			(xy 281.194326 -13.926801) (xy 281.038986 -13.989093) (xy 280.880854 -14.043912) (xy 280.720289 -14.091133)
			(xy 280.557657 -14.130648) (xy 280.393326 -14.162369) (xy 280.22767 -14.186223) (xy 280.061066 -14.202156)
			(xy 279.893892 -14.210131) (xy 279.726528 -14.210131) (xy 279.559354 -14.202156) (xy 279.39275 -14.186223)
			(xy 279.227094 -14.162369) (xy 279.062763 -14.130648) (xy 278.900131 -14.091133) (xy 278.739566 -14.043912)
			(xy 278.581434 -13.989093) (xy 278.426094 -13.926801) (xy 278.273899 -13.857178) (xy 278.125194 -13.78038)
			(xy 277.980318 -13.696584) (xy 277.8396 -13.60598) (xy 277.70336 -13.508772) (xy 277.571906 -13.405183)
			(xy 277.445538 -13.295447) (xy 277.324543 -13.179814) (xy 277.209196 -13.058546) (xy 277.099758 -12.93192)
			(xy 276.996479 -12.800222) (xy 276.899594 -12.663753) (xy 276.809321 -12.522821) (xy 276.725867 -12.377748)
			(xy 276.649421 -12.228863) (xy 276.580157 -12.076504) (xy 276.518231 -11.921017) (xy 276.463786 -11.762756)
			(xy 276.416944 -11.602081) (xy 276.377812 -11.439356) (xy 276.346479 -11.274951) (xy 276.323016 -11.109239)
			(xy 276.307476 -10.942598) (xy 276.299895 -10.775405) (xy 275.810641 -10.775405) (xy 275.810722 -10.789767)
			(xy 275.818776 -10.969113) (xy 275.834869 -11.147917) (xy 275.858967 -11.325819) (xy 275.891023 -11.502461)
			(xy 275.930971 -11.677487) (xy 275.978732 -11.850544) (xy 276.034209 -12.021284) (xy 276.09729 -12.189363)
			(xy 276.167849 -12.354443) (xy 276.245742 -12.516191) (xy 276.330815 -12.674281) (xy 276.422894 -12.828396)
			(xy 276.521794 -12.978224) (xy 276.627318 -13.123464) (xy 276.739251 -13.263824) (xy 276.857368 -13.39902)
			(xy 276.981433 -13.528781) (xy 277.111194 -13.652846) (xy 277.24639 -13.770963) (xy 277.38675 -13.882896)
			(xy 277.53199 -13.98842) (xy 277.681818 -14.08732) (xy 277.835933 -14.179399) (xy 277.994023 -14.264472)
			(xy 278.155771 -14.342365) (xy 278.320851 -14.412924) (xy 278.48893 -14.476005) (xy 278.65967 -14.531482)
			(xy 278.832727 -14.579243) (xy 279.007753 -14.619191) (xy 279.184395 -14.651247) (xy 279.362297 -14.675345)
			(xy 279.541101 -14.691438) (xy 279.720447 -14.699492) (xy 279.899973 -14.699492) (xy 280.079319 -14.691438)
			(xy 280.258123 -14.675345) (xy 280.436025 -14.651247) (xy 280.612667 -14.619191) (xy 280.787693 -14.579243)
			(xy 280.96075 -14.531482) (xy 281.13149 -14.476005) (xy 281.299569 -14.412924) (xy 281.464649 -14.342365)
			(xy 281.626397 -14.264472) (xy 281.784487 -14.179399) (xy 281.938602 -14.08732) (xy 282.08843 -13.98842)
			(xy 282.23367 -13.882896) (xy 282.37403 -13.770963) (xy 282.509226 -13.652846) (xy 282.638987 -13.528781)
			(xy 282.763052 -13.39902) (xy 282.881169 -13.263824) (xy 282.993102 -13.123464) (xy 283.098626 -12.978224)
			(xy 283.197526 -12.828396) (xy 283.289605 -12.674281) (xy 283.374678 -12.516191) (xy 283.452571 -12.354443)
			(xy 283.52313 -12.189363) (xy 283.586211 -12.021284) (xy 283.641688 -11.850544) (xy 283.689449 -11.677487)
			(xy 283.729397 -11.502461) (xy 283.761453 -11.325819) (xy 283.785551 -11.147917) (xy 283.801644 -10.969113)
			(xy 283.809698 -10.789767) (xy 283.810202 -10.700004) (xy 283.810202 -4.700016) (xy 283.809698 -4.610253)
			(xy 283.801644 -4.430907) (xy 283.785551 -4.252103) (xy 283.761453 -4.074201) (xy 283.729397 -3.897559)
			(xy 283.689449 -3.722533) (xy 283.641688 -3.549476) (xy 283.586211 -3.378736) (xy 283.52313 -3.210657)
			(xy 283.452571 -3.045577) (xy 283.374678 -2.883829) (xy 283.289605 -2.725739) (xy 283.197526 -2.571624)
			(xy 283.098626 -2.421796) (xy 282.993102 -2.276556) (xy 282.881169 -2.136196) (xy 282.763052 -2.001)
			(xy 282.638987 -1.871239) (xy 282.509226 -1.747174) (xy 282.37403 -1.629057) (xy 282.23367 -1.517124)
			(xy 282.08843 -1.4116) (xy 281.938602 -1.3127) (xy 281.784487 -1.220621) (xy 281.626397 -1.135548)
			(xy 281.464649 -1.057655) (xy 281.299569 -0.987096) (xy 281.13149 -0.924015) (xy 280.96075 -0.868538)
			(xy 280.787693 -0.820777) (xy 280.612667 -0.780829) (xy 280.436025 -0.748773) (xy 280.258123 -0.724675)
			(xy 280.079319 -0.708582) (xy 279.899973 -0.700528) (xy 279.720447 -0.700528) (xy 279.541101 -0.708582)
			(xy 279.362297 -0.724675) (xy 279.184395 -0.748773) (xy 279.007753 -0.780829) (xy 278.832727 -0.820777)
			(xy 278.65967 -0.868538) (xy 278.48893 -0.924015) (xy 278.320851 -0.987096) (xy 278.155771 -1.057655)
			(xy 277.994023 -1.135548) (xy 277.835933 -1.220621) (xy 277.681818 -1.3127) (xy 277.53199 -1.4116)
			(xy 277.38675 -1.517124) (xy 277.24639 -1.629057) (xy 277.111194 -1.747174) (xy 276.981433 -1.871239)
			(xy 276.857368 -2.001) (xy 276.739251 -2.136196) (xy 276.627318 -2.276556) (xy 276.521794 -2.421796)
			(xy 276.422894 -2.571624) (xy 276.330815 -2.725739) (xy 276.245742 -2.883829) (xy 276.167849 -3.045577)
			(xy 276.09729 -3.210657) (xy 276.034209 -3.378736) (xy 275.978732 -3.549476) (xy 275.930971 -3.722533)
			(xy 275.891023 -3.897559) (xy 275.858967 -4.074201) (xy 275.834869 -4.252103) (xy 275.818776 -4.430907)
			(xy 275.810722 -4.610253) (xy 275.810218 -4.700016)
		)
		(stroke
			(width 0)
			(type solid)
		)
		(fill yes)
		(layer "B.Cu")
		(net "GND")
	)
	(gr_poly
		(pts
			(xy 296.810176 -47.500032) (xy 296.810599 -47.575433) (xy 297.299853 -47.575433) (xy 297.300248 -47.408069)
			(xy 297.308618 -47.240915) (xy 297.324943 -47.074348) (xy 297.349188 -46.90875) (xy 297.381297 -46.744494)
			(xy 297.421196 -46.581955) (xy 297.468795 -46.421502) (xy 297.523987 -46.2635) (xy 297.586645 -46.108308)
			(xy 297.656627 -45.956277) (xy 297.733775 -45.807754) (xy 297.817913 -45.663076) (xy 297.908849 -45.522572)
			(xy 298.006378 -45.386561) (xy 298.110277 -45.255353) (xy 298.220311 -45.129244) (xy 298.336229 -45.008522)
			(xy 298.39666 -44.950634) (xy 298.420347 -44.927428) (xy 298.461905 -44.875757) (xy 298.496104 -44.818946)
			(xy 298.522317 -44.758037) (xy 298.540063 -44.694146) (xy 298.549017 -44.628443) (xy 298.549568 -44.595288)
			(xy 298.549568 -41.500044) (xy 298.550064 -41.43304) (xy 298.558003 -41.299268) (xy 298.573853 -41.166201)
			(xy 298.597557 -41.034306) (xy 298.629034 -40.904048) (xy 298.668172 -40.775883) (xy 298.714833 -40.650262)
			(xy 298.768855 -40.527625) (xy 298.830047 -40.408404) (xy 298.898194 -40.293018) (xy 298.973057 -40.181871)
			(xy 299.054373 -40.075355) (xy 299.141856 -39.973842) (xy 299.235199 -39.877691) (xy 299.334074 -39.787238)
			(xy 299.438134 -39.702801) (xy 299.547014 -39.624678) (xy 299.66033 -39.553141) (xy 299.777685 -39.488443)
			(xy 299.898667 -39.430811) (xy 300.022851 -39.380448) (xy 300.149799 -39.337529) (xy 300.279068 -39.302206)
			(xy 300.410202 -39.274604) (xy 300.542741 -39.254818) (xy 300.676219 -39.242919) (xy 300.810168 -39.238948)
			(xy 300.944117 -39.242919) (xy 301.077595 -39.254818) (xy 301.210134 -39.274604) (xy 301.341268 -39.302206)
			(xy 301.470537 -39.337529) (xy 301.597485 -39.380448) (xy 301.721669 -39.430811) (xy 301.842651 -39.488443)
			(xy 301.960006 -39.553141) (xy 302.073322 -39.624678) (xy 302.182202 -39.702801) (xy 302.286262 -39.787238)
			(xy 302.385137 -39.877691) (xy 302.47848 -39.973842) (xy 302.565963 -40.075355) (xy 302.647279 -40.181871)
			(xy 302.722142 -40.293018) (xy 302.790289 -40.408404) (xy 302.851481 -40.527625) (xy 302.905503 -40.650262)
			(xy 302.952164 -40.775883) (xy 302.991302 -40.904048) (xy 303.022779 -41.034306) (xy 303.046483 -41.166201)
			(xy 303.062333 -41.299268) (xy 303.070272 -41.43304) (xy 303.070768 -41.500044) (xy 303.070768 -44.595288)
			(xy 303.071348 -44.628441) (xy 303.080309 -44.69414) (xy 303.098054 -44.758028) (xy 303.12426 -44.818937)
			(xy 303.158446 -44.875752) (xy 303.199987 -44.927433) (xy 303.223676 -44.950634) (xy 303.284107 -45.008522)
			(xy 303.400025 -45.129244) (xy 303.510059 -45.255353) (xy 303.613958 -45.386561) (xy 303.711487 -45.522572)
			(xy 303.802423 -45.663076) (xy 303.886561 -45.807754) (xy 303.963709 -45.956277) (xy 304.033691 -46.108308)
			(xy 304.096349 -46.2635) (xy 304.151541 -46.421502) (xy 304.19914 -46.581955) (xy 304.239039 -46.744494)
			(xy 304.271148 -46.90875) (xy 304.295393 -47.074348) (xy 304.311718 -47.240915) (xy 304.320088 -47.408069)
			(xy 304.320483 -47.575433) (xy 304.312902 -47.742626) (xy 304.297362 -47.909267) (xy 304.273899 -48.074979)
			(xy 304.242566 -48.239384) (xy 304.203434 -48.402109) (xy 304.156592 -48.562784) (xy 304.102147 -48.721045)
			(xy 304.040221 -48.876532) (xy 303.970957 -49.028891) (xy 303.894511 -49.177776) (xy 303.811057 -49.322849)
			(xy 303.720784 -49.463781) (xy 303.623899 -49.60025) (xy 303.52062 -49.731948) (xy 303.411182 -49.858574)
			(xy 303.295835 -49.979842) (xy 303.17484 -50.095475) (xy 303.048472 -50.205211) (xy 302.917018 -50.3088)
			(xy 302.780778 -50.406008) (xy 302.64006 -50.496612) (xy 302.495184 -50.580408) (xy 302.346479 -50.657206)
			(xy 302.194284 -50.726829) (xy 302.038944 -50.789121) (xy 301.880812 -50.84394) (xy 301.720247 -50.891161)
			(xy 301.557615 -50.930676) (xy 301.393284 -50.962397) (xy 301.227628 -50.986251) (xy 301.061024 -51.002184)
			(xy 300.89385 -51.010159) (xy 300.726486 -51.010159) (xy 300.559312 -51.002184) (xy 300.392708 -50.986251)
			(xy 300.227052 -50.962397) (xy 300.062721 -50.930676) (xy 299.900089 -50.891161) (xy 299.739524 -50.84394)
			(xy 299.581392 -50.789121) (xy 299.426052 -50.726829) (xy 299.273857 -50.657206) (xy 299.125152 -50.580408)
			(xy 298.980276 -50.496612) (xy 298.839558 -50.406008) (xy 298.703318 -50.3088) (xy 298.571864 -50.205211)
			(xy 298.445496 -50.095475) (xy 298.324501 -49.979842) (xy 298.209154 -49.858574) (xy 298.099716 -49.731948)
			(xy 297.996437 -49.60025) (xy 297.899552 -49.463781) (xy 297.809279 -49.322849) (xy 297.725825 -49.177776)
			(xy 297.649379 -49.028891) (xy 297.580115 -48.876532) (xy 297.518189 -48.721045) (xy 297.463744 -48.562784)
			(xy 297.416902 -48.402109) (xy 297.37777 -48.239384) (xy 297.346437 -48.074979) (xy 297.322974 -47.909267)
			(xy 297.307434 -47.742626) (xy 297.299853 -47.575433) (xy 296.810599 -47.575433) (xy 296.81068 -47.589795)
			(xy 296.818734 -47.769141) (xy 296.834827 -47.947945) (xy 296.858925 -48.125847) (xy 296.890981 -48.302489)
			(xy 296.930929 -48.477515) (xy 296.97869 -48.650572) (xy 297.034167 -48.821312) (xy 297.097248 -48.989391)
			(xy 297.167807 -49.154471) (xy 297.2457 -49.316219) (xy 297.330773 -49.474309) (xy 297.422852 -49.628424)
			(xy 297.521752 -49.778252) (xy 297.627276 -49.923492) (xy 297.739209 -50.063852) (xy 297.857326 -50.199048)
			(xy 297.981391 -50.328809) (xy 298.111152 -50.452874) (xy 298.246348 -50.570991) (xy 298.386708 -50.682924)
			(xy 298.531948 -50.788448) (xy 298.681776 -50.887348) (xy 298.835891 -50.979427) (xy 298.993981 -51.0645)
			(xy 299.155729 -51.142393) (xy 299.320809 -51.212952) (xy 299.488888 -51.276033) (xy 299.659628 -51.33151)
			(xy 299.832685 -51.379271) (xy 300.007711 -51.419219) (xy 300.184353 -51.451275) (xy 300.362255 -51.475373)
			(xy 300.541059 -51.491466) (xy 300.720405 -51.49952) (xy 300.899931 -51.49952) (xy 301.079277 -51.491466)
			(xy 301.258081 -51.475373) (xy 301.435983 -51.451275) (xy 301.612625 -51.419219) (xy 301.787651 -51.379271)
			(xy 301.960708 -51.33151) (xy 302.131448 -51.276033) (xy 302.299527 -51.212952) (xy 302.464607 -51.142393)
			(xy 302.626355 -51.0645) (xy 302.784445 -50.979427) (xy 302.93856 -50.887348) (xy 303.088388 -50.788448)
			(xy 303.233628 -50.682924) (xy 303.373988 -50.570991) (xy 303.509184 -50.452874) (xy 303.638945 -50.328809)
			(xy 303.76301 -50.199048) (xy 303.881127 -50.063852) (xy 303.99306 -49.923492) (xy 304.098584 -49.778252)
			(xy 304.197484 -49.628424) (xy 304.289563 -49.474309) (xy 304.374636 -49.316219) (xy 304.452529 -49.154471)
			(xy 304.523088 -48.989391) (xy 304.586169 -48.821312) (xy 304.641646 -48.650572) (xy 304.689407 -48.477515)
			(xy 304.729355 -48.302489) (xy 304.761411 -48.125847) (xy 304.785509 -47.947945) (xy 304.801602 -47.769141)
			(xy 304.809656 -47.589795) (xy 304.81016 -47.500032) (xy 304.81016 -41.500044) (xy 304.809656 -41.410281)
			(xy 304.801602 -41.230935) (xy 304.785509 -41.052131) (xy 304.761411 -40.874229) (xy 304.729355 -40.697587)
			(xy 304.689407 -40.522561) (xy 304.641646 -40.349504) (xy 304.586169 -40.178764) (xy 304.523088 -40.010685)
			(xy 304.452529 -39.845605) (xy 304.374636 -39.683857) (xy 304.289563 -39.525767) (xy 304.197484 -39.371652)
			(xy 304.098584 -39.221824) (xy 303.99306 -39.076584) (xy 303.881127 -38.936224) (xy 303.76301 -38.801028)
			(xy 303.638945 -38.671267) (xy 303.509184 -38.547202) (xy 303.373988 -38.429085) (xy 303.233628 -38.317152)
			(xy 303.088388 -38.211628) (xy 302.93856 -38.112728) (xy 302.784445 -38.020649) (xy 302.626355 -37.935576)
			(xy 302.464607 -37.857683) (xy 302.299527 -37.787124) (xy 302.131448 -37.724043) (xy 301.960708 -37.668566)
			(xy 301.787651 -37.620805) (xy 301.612625 -37.580857) (xy 301.435983 -37.548801) (xy 301.258081 -37.524703)
			(xy 301.079277 -37.50861) (xy 300.899931 -37.500556) (xy 300.720405 -37.500556) (xy 300.541059 -37.50861)
			(xy 300.362255 -37.524703) (xy 300.184353 -37.548801) (xy 300.007711 -37.580857) (xy 299.832685 -37.620805)
			(xy 299.659628 -37.668566) (xy 299.488888 -37.724043) (xy 299.320809 -37.787124) (xy 299.155729 -37.857683)
			(xy 298.993981 -37.935576) (xy 298.835891 -38.020649) (xy 298.681776 -38.112728) (xy 298.531948 -38.211628)
			(xy 298.386708 -38.317152) (xy 298.246348 -38.429085) (xy 298.111152 -38.547202) (xy 297.981391 -38.671267)
			(xy 297.857326 -38.801028) (xy 297.739209 -38.936224) (xy 297.627276 -39.076584) (xy 297.521752 -39.221824)
			(xy 297.422852 -39.371652) (xy 297.330773 -39.525767) (xy 297.2457 -39.683857) (xy 297.167807 -39.845605)
			(xy 297.097248 -40.010685) (xy 297.034167 -40.178764) (xy 296.97869 -40.349504) (xy 296.930929 -40.522561)
			(xy 296.890981 -40.697587) (xy 296.858925 -40.874229) (xy 296.834827 -41.052131) (xy 296.818734 -41.230935)
			(xy 296.81068 -41.410281) (xy 296.810176 -41.500044)
		)
		(stroke
			(width 0)
			(type solid)
		)
		(fill yes)
		(layer "B.Cu")
		(net "GND")
	)
	(gr_poly
		(pts
			(xy 40.875204 -51.6128) (xy 40.891852 -51.612256) (xy 40.924013 -51.603638) (xy 40.952848 -51.586989)
			(xy 40.976392 -51.563445) (xy 40.993039 -51.53461) (xy 41.001657 -51.502448) (xy 41.002204 -51.4858)
			(xy 41.002204 -45.449236) (xy 41.552368 -45.449236) (xy 41.552368 -51.4858) (xy 41.552911 -51.50245)
			(xy 41.561528 -51.534615) (xy 41.578176 -51.563455) (xy 41.601719 -51.587005) (xy 41.630555 -51.603659)
			(xy 41.662718 -51.612285) (xy 41.679368 -51.6128) (xy 50.7492 -51.6128) (xy 51.054 -51.308) (xy 51.054 -44.8056)
			(xy 50.0634 -43.815) (xy 50.0634 -41.9354) (xy 51.6128 -40.386) (xy 57.023 -40.386) (xy 57.160261 -40.523261)
			(xy 63.423792 -40.523261) (xy 63.423792 -40.451939) (xy 63.431778 -40.381065) (xy 63.447648 -40.31153)
			(xy 63.471205 -40.24421) (xy 63.50215 -40.179951) (xy 63.540096 -40.11956) (xy 63.584565 -40.063798)
			(xy 63.634998 -40.013365) (xy 63.69076 -39.968896) (xy 63.751151 -39.93095) (xy 63.81541 -39.900005)
			(xy 63.88273 -39.876448) (xy 63.952265 -39.860578) (xy 64.023139 -39.852592) (xy 64.094461 -39.852592)
			(xy 64.165335 -39.860578) (xy 64.23487 -39.876448) (xy 64.30219 -39.900005) (xy 64.366449 -39.93095)
			(xy 64.42684 -39.968896) (xy 64.482602 -40.013365) (xy 64.533035 -40.063798) (xy 64.577504 -40.11956)
			(xy 64.61545 -40.179951) (xy 64.646395 -40.24421) (xy 64.669952 -40.31153) (xy 64.685822 -40.381065)
			(xy 64.693808 -40.451939) (xy 64.694308 -40.4876) (xy 64.693808 -40.523261) (xy 64.685822 -40.594135)
			(xy 64.678809 -40.624861) (xy 70.484992 -40.624861) (xy 70.484992 -40.553539) (xy 70.492978 -40.482665)
			(xy 70.508848 -40.41313) (xy 70.532405 -40.34581) (xy 70.56335 -40.281551) (xy 70.601296 -40.22116)
			(xy 70.645765 -40.165398) (xy 70.696198 -40.114965) (xy 70.75196 -40.070496) (xy 70.812351 -40.03255)
			(xy 70.87661 -40.001605) (xy 70.94393 -39.978048) (xy 71.013465 -39.962178) (xy 71.084339 -39.954192)
			(xy 71.155661 -39.954192) (xy 71.226535 -39.962178) (xy 71.29607 -39.978048) (xy 71.36339 -40.001605)
			(xy 71.427649 -40.03255) (xy 71.48804 -40.070496) (xy 71.543802 -40.114965) (xy 71.594235 -40.165398)
			(xy 71.638704 -40.22116) (xy 71.67665 -40.281551) (xy 71.707595 -40.34581) (xy 71.731152 -40.41313)
			(xy 71.747022 -40.482665) (xy 71.755008 -40.553539) (xy 71.755508 -40.5892) (xy 71.755008 -40.624861)
			(xy 71.747022 -40.695735) (xy 71.731152 -40.76527) (xy 71.707595 -40.83259) (xy 71.67665 -40.896849)
			(xy 71.638704 -40.95724) (xy 71.594235 -41.013002) (xy 71.543802 -41.063435) (xy 71.48804 -41.107904)
			(xy 71.427649 -41.14585) (xy 71.36339 -41.176795) (xy 71.29607 -41.200352) (xy 71.226535 -41.216222)
			(xy 71.155661 -41.224208) (xy 71.084339 -41.224208) (xy 71.013465 -41.216222) (xy 70.94393 -41.200352)
			(xy 70.87661 -41.176795) (xy 70.812351 -41.14585) (xy 70.75196 -41.107904) (xy 70.696198 -41.063435)
			(xy 70.645765 -41.013002) (xy 70.601296 -40.95724) (xy 70.56335 -40.896849) (xy 70.532405 -40.83259)
			(xy 70.508848 -40.76527) (xy 70.492978 -40.695735) (xy 70.484992 -40.624861) (xy 64.678809 -40.624861)
			(xy 64.669952 -40.66367) (xy 64.646395 -40.73099) (xy 64.61545 -40.795249) (xy 64.577504 -40.85564)
			(xy 64.533035 -40.911402) (xy 64.482602 -40.961835) (xy 64.42684 -41.006304) (xy 64.366449 -41.04425)
			(xy 64.30219 -41.075195) (xy 64.23487 -41.098752) (xy 64.165335 -41.114622) (xy 64.094461 -41.122608)
			(xy 64.023139 -41.122608) (xy 63.952265 -41.114622) (xy 63.88273 -41.098752) (xy 63.81541 -41.075195)
			(xy 63.751151 -41.04425) (xy 63.69076 -41.006304) (xy 63.634998 -40.961835) (xy 63.584565 -40.911402)
			(xy 63.540096 -40.85564) (xy 63.50215 -40.795249) (xy 63.471205 -40.73099) (xy 63.447648 -40.66367)
			(xy 63.431778 -40.594135) (xy 63.423792 -40.523261) (xy 57.160261 -40.523261) (xy 58.293 -41.656)
			(xy 58.293 -45.730261) (xy 63.576192 -45.730261) (xy 63.576192 -45.658939) (xy 63.584178 -45.588065)
			(xy 63.600048 -45.51853) (xy 63.623605 -45.45121) (xy 63.65455 -45.386951) (xy 63.692496 -45.32656)
			(xy 63.736965 -45.270798) (xy 63.787398 -45.220365) (xy 63.84316 -45.175896) (xy 63.903551 -45.13795)
			(xy 63.96781 -45.107005) (xy 64.03513 -45.083448) (xy 64.104665 -45.067578) (xy 64.175539 -45.059592)
			(xy 64.246861 -45.059592) (xy 64.317735 -45.067578) (xy 64.38727 -45.083448) (xy 64.45459 -45.107005)
			(xy 64.518849 -45.13795) (xy 64.57924 -45.175896) (xy 64.635002 -45.220365) (xy 64.685435 -45.270798)
			(xy 64.729904 -45.32656) (xy 64.76785 -45.386951) (xy 64.798795 -45.45121) (xy 64.822352 -45.51853)
			(xy 64.838222 -45.588065) (xy 64.846208 -45.658939) (xy 64.846708 -45.6946) (xy 64.846208 -45.730261)
			(xy 64.838222 -45.801135) (xy 64.822352 -45.87067) (xy 64.80038 -45.933461) (xy 70.738992 -45.933461)
			(xy 70.738992 -45.862139) (xy 70.746978 -45.791265) (xy 70.762848 -45.72173) (xy 70.786405 -45.65441)
			(xy 70.81735 -45.590151) (xy 70.855296 -45.52976) (xy 70.899765 -45.473998) (xy 70.950198 -45.423565)
			(xy 71.00596 -45.379096) (xy 71.066351 -45.34115) (xy 71.13061 -45.310205) (xy 71.19793 -45.286648)
			(xy 71.267465 -45.270778) (xy 71.338339 -45.262792) (xy 71.409661 -45.262792) (xy 71.480535 -45.270778)
			(xy 71.55007 -45.286648) (xy 71.61739 -45.310205) (xy 71.681649 -45.34115) (xy 71.74204 -45.379096)
			(xy 71.797802 -45.423565) (xy 71.848235 -45.473998) (xy 71.892704 -45.52976) (xy 71.93065 -45.590151)
			(xy 71.961595 -45.65441) (xy 71.985152 -45.72173) (xy 72.001022 -45.791265) (xy 72.009008 -45.862139)
			(xy 72.009508 -45.8978) (xy 72.009008 -45.933461) (xy 72.001022 -46.004335) (xy 71.985152 -46.07387)
			(xy 71.961595 -46.14119) (xy 71.93065 -46.205449) (xy 71.892704 -46.26584) (xy 71.848235 -46.321602)
			(xy 71.797802 -46.372035) (xy 71.74204 -46.416504) (xy 71.681649 -46.45445) (xy 71.61739 -46.485395)
			(xy 71.55007 -46.508952) (xy 71.480535 -46.524822) (xy 71.409661 -46.532808) (xy 71.338339 -46.532808)
			(xy 71.267465 -46.524822) (xy 71.19793 -46.508952) (xy 71.13061 -46.485395) (xy 71.066351 -46.45445)
			(xy 71.00596 -46.416504) (xy 70.950198 -46.372035) (xy 70.899765 -46.321602) (xy 70.855296 -46.26584)
			(xy 70.81735 -46.205449) (xy 70.786405 -46.14119) (xy 70.762848 -46.07387) (xy 70.746978 -46.004335)
			(xy 70.738992 -45.933461) (xy 64.80038 -45.933461) (xy 64.798795 -45.93799) (xy 64.76785 -46.002249)
			(xy 64.729904 -46.06264) (xy 64.685435 -46.118402) (xy 64.635002 -46.168835) (xy 64.57924 -46.213304)
			(xy 64.518849 -46.25125) (xy 64.45459 -46.282195) (xy 64.38727 -46.305752) (xy 64.317735 -46.321622)
			(xy 64.246861 -46.329608) (xy 64.175539 -46.329608) (xy 64.104665 -46.321622) (xy 64.03513 -46.305752)
			(xy 63.96781 -46.282195) (xy 63.903551 -46.25125) (xy 63.84316 -46.213304) (xy 63.787398 -46.168835)
			(xy 63.736965 -46.118402) (xy 63.692496 -46.06264) (xy 63.65455 -46.002249) (xy 63.623605 -45.93799)
			(xy 63.600048 -45.87067) (xy 63.584178 -45.801135) (xy 63.576192 -45.730261) (xy 58.293 -45.730261)
			(xy 58.293 -48.3362) (xy 60.2488 -50.292) (xy 77.032358 -50.292) (xy 77.054953 -50.291503) (xy 77.099429 -50.283501)
			(xy 77.141789 -50.267759) (xy 77.180697 -50.244774) (xy 77.214926 -50.21527) (xy 77.243398 -50.180178)
			(xy 77.265216 -50.140603) (xy 77.27969 -50.097794) (xy 77.286365 -50.0531) (xy 77.285031 -50.007929)
			(xy 77.275729 -49.963707) (xy 77.258753 -49.921827) (xy 77.234638 -49.883609) (xy 77.21981 -49.86655)
			(xy 77.164478 -49.80527) (xy 77.058961 -49.678255) (xy 76.959536 -49.546417) (xy 76.866423 -49.410048)
			(xy 76.779829 -49.26945) (xy 76.699944 -49.124934) (xy 76.626946 -48.97682) (xy 76.560996 -48.825435)
			(xy 76.502241 -48.671116) (xy 76.450811 -48.514204) (xy 76.406818 -48.355046) (xy 76.370362 -48.193995)
			(xy 76.341522 -48.031407) (xy 76.320363 -47.867643) (xy 76.306931 -47.703064) (xy 76.301256 -47.538036)
			(xy 76.303351 -47.372923) (xy 76.31321 -47.208092) (xy 76.330813 -47.043907) (xy 76.356119 -46.880732)
			(xy 76.389074 -46.718928) (xy 76.429604 -46.558854) (xy 76.47762 -46.400863) (xy 76.533014 -46.245306)
			(xy 76.595665 -46.092527) (xy 76.665434 -45.942864) (xy 76.742165 -45.79665) (xy 76.82569 -45.654206)
			(xy 76.915824 -45.51585) (xy 77.012366 -45.381887) (xy 77.115103 -45.252614) (xy 77.223808 -45.128316)
			(xy 77.33824 -45.009271) (xy 77.397864 -44.952158) (xy 77.421653 -44.92886) (xy 77.463365 -44.876958)
			(xy 77.497684 -44.819897) (xy 77.523982 -44.758725) (xy 77.541776 -44.694561) (xy 77.550741 -44.628581)
			(xy 77.55128 -44.595288) (xy 77.55128 -41.500044) (xy 77.551776 -41.433093) (xy 77.559709 -41.299426)
			(xy 77.575546 -41.166463) (xy 77.599232 -41.034673) (xy 77.630683 -40.904517) (xy 77.669791 -40.776453)
			(xy 77.716415 -40.65093) (xy 77.770395 -40.52839) (xy 77.831538 -40.409263) (xy 77.899632 -40.293967)
			(xy 77.974436 -40.182908) (xy 78.055688 -40.076475) (xy 78.143102 -39.975043) (xy 78.236372 -39.878967)
			(xy 78.335169 -39.788585) (xy 78.439148 -39.704215) (xy 78.547941 -39.626153) (xy 78.661168 -39.554673)
			(xy 78.778431 -39.490026) (xy 78.899318 -39.432439) (xy 79.023404 -39.382115) (xy 79.150253 -39.33923)
			(xy 79.27942 -39.303935) (xy 79.410451 -39.276354) (xy 79.542885 -39.256584) (xy 79.676259 -39.244694)
			(xy 79.810102 -39.240726) (xy 79.943945 -39.244694) (xy 80.077319 -39.256584) (xy 80.209753 -39.276354)
			(xy 80.340784 -39.303935) (xy 80.469951 -39.33923) (xy 80.5968 -39.382115) (xy 80.720886 -39.432439)
			(xy 80.841773 -39.490026) (xy 80.959036 -39.554673) (xy 81.072263 -39.626153) (xy 81.181056 -39.704215)
			(xy 81.285035 -39.788585) (xy 81.383832 -39.878967) (xy 81.477102 -39.975043) (xy 81.564516 -40.076475)
			(xy 81.645768 -40.182908) (xy 81.720572 -40.293967) (xy 81.788666 -40.409263) (xy 81.849809 -40.52839)
			(xy 81.903789 -40.65093) (xy 81.950413 -40.776453) (xy 81.989521 -40.904517) (xy 82.020972 -41.034673)
			(xy 82.038619 -41.132861) (xy 88.264992 -41.132861) (xy 88.264992 -41.061539) (xy 88.272978 -40.990665)
			(xy 88.288848 -40.92113) (xy 88.312405 -40.85381) (xy 88.34335 -40.789551) (xy 88.381296 -40.72916)
			(xy 88.425765 -40.673398) (xy 88.476198 -40.622965) (xy 88.53196 -40.578496) (xy 88.592351 -40.54055)
			(xy 88.65661 -40.509605) (xy 88.72393 -40.486048) (xy 88.793465 -40.470178) (xy 88.864339 -40.462192)
			(xy 88.935661 -40.462192) (xy 89.006535 -40.470178) (xy 89.07607 -40.486048) (xy 89.14339 -40.509605)
			(xy 89.207649 -40.54055) (xy 89.26804 -40.578496) (xy 89.323802 -40.622965) (xy 89.374235 -40.673398)
			(xy 89.418704 -40.72916) (xy 89.45665 -40.789551) (xy 89.487595 -40.85381) (xy 89.511152 -40.92113)
			(xy 89.527022 -40.990665) (xy 89.535008 -41.061539) (xy 89.535508 -41.0972) (xy 89.535008 -41.132861)
			(xy 89.527022 -41.203735) (xy 89.511152 -41.27327) (xy 89.487595 -41.34059) (xy 89.45665 -41.404849)
			(xy 89.418704 -41.46524) (xy 89.374235 -41.521002) (xy 89.323802 -41.571435) (xy 89.26804 -41.615904)
			(xy 89.207649 -41.65385) (xy 89.14339 -41.684795) (xy 89.07607 -41.708352) (xy 89.006535 -41.724222)
			(xy 88.935661 -41.732208) (xy 88.864339 -41.732208) (xy 88.793465 -41.724222) (xy 88.72393 -41.708352)
			(xy 88.65661 -41.684795) (xy 88.592351 -41.65385) (xy 88.53196 -41.615904) (xy 88.476198 -41.571435)
			(xy 88.425765 -41.521002) (xy 88.381296 -41.46524) (xy 88.34335 -41.404849) (xy 88.312405 -41.34059)
			(xy 88.288848 -41.27327) (xy 88.272978 -41.203735) (xy 88.264992 -41.132861) (xy 82.038619 -41.132861)
			(xy 82.044658 -41.166463) (xy 82.060495 -41.299426) (xy 82.068428 -41.433093) (xy 82.068924 -41.500044)
			(xy 82.06867 -44.595288) (xy 82.069218 -44.628591) (xy 82.078209 -44.694588) (xy 82.09604 -44.758763)
			(xy 82.122383 -44.819938) (xy 82.156756 -44.876989) (xy 82.198527 -44.92887) (xy 82.202789 -44.933038)
			(xy 115.78564 -44.933038) (xy 115.78564 -44.805162) (xy 115.793669 -44.677538) (xy 115.809697 -44.55067)
			(xy 115.833658 -44.425058) (xy 115.86546 -44.3012) (xy 115.904976 -44.179582) (xy 115.95205 -44.060685)
			(xy 116.006497 -43.944979) (xy 116.068102 -43.83292) (xy 116.136622 -43.724951) (xy 116.211786 -43.621497)
			(xy 116.293297 -43.522966) (xy 116.380834 -43.429748) (xy 116.474052 -43.342211) (xy 116.572583 -43.2607)
			(xy 116.676037 -43.185536) (xy 116.784006 -43.117016) (xy 116.896065 -43.055411) (xy 117.011771 -43.000964)
			(xy 117.130668 -42.95389) (xy 117.252286 -42.914374) (xy 117.376144 -42.882572) (xy 117.501756 -42.858611)
			(xy 117.628624 -42.842583) (xy 117.756248 -42.834554) (xy 117.884124 -42.834554) (xy 118.011748 -42.842583)
			(xy 118.138616 -42.858611) (xy 118.264228 -42.882572) (xy 118.388086 -42.914374) (xy 118.509704 -42.95389)
			(xy 118.628601 -43.000964) (xy 118.744307 -43.055411) (xy 118.856366 -43.117016) (xy 118.964335 -43.185536)
			(xy 119.067789 -43.2607) (xy 119.16632 -43.342211) (xy 119.259538 -43.429748) (xy 119.347075 -43.522966)
			(xy 119.428586 -43.621497) (xy 119.50375 -43.724951) (xy 119.57227 -43.83292) (xy 119.633875 -43.944979)
			(xy 119.688322 -44.060685) (xy 119.735396 -44.179582) (xy 119.774912 -44.3012) (xy 119.806714 -44.425058)
			(xy 119.830675 -44.55067) (xy 119.846703 -44.677538) (xy 119.854732 -44.805162) (xy 119.855234 -44.8691)
			(xy 119.854732 -44.932982) (xy 127.217418 -44.932982) (xy 127.217418 -44.805218) (xy 127.22544 -44.677705)
			(xy 127.241453 -44.550948) (xy 127.265394 -44.425446) (xy 127.297168 -44.301696) (xy 127.336649 -44.180184)
			(xy 127.383682 -44.061392) (xy 127.438082 -43.945787) (xy 127.499633 -43.833826) (xy 127.568093 -43.725951)
			(xy 127.643191 -43.622587) (xy 127.724631 -43.524142) (xy 127.812092 -43.431006) (xy 127.905228 -43.343545)
			(xy 128.003673 -43.262105) (xy 128.107037 -43.187007) (xy 128.214912 -43.118547) (xy 128.326873 -43.056996)
			(xy 128.442478 -43.002596) (xy 128.56127 -42.955563) (xy 128.682782 -42.916082) (xy 128.806532 -42.884308)
			(xy 128.932034 -42.860367) (xy 129.058791 -42.844354) (xy 129.186304 -42.836332) (xy 129.314068 -42.836332)
			(xy 129.441581 -42.844354) (xy 129.568338 -42.860367) (xy 129.69384 -42.884308) (xy 129.81759 -42.916082)
			(xy 129.939102 -42.955563) (xy 130.057894 -43.002596) (xy 130.173499 -43.056996) (xy 130.28546 -43.118547)
			(xy 130.393335 -43.187007) (xy 130.496699 -43.262105) (xy 130.595144 -43.343545) (xy 130.68828 -43.431006)
			(xy 130.775741 -43.524142) (xy 130.857181 -43.622587) (xy 130.932279 -43.725951) (xy 131.000739 -43.833826)
			(xy 131.06229 -43.945787) (xy 131.11669 -44.061392) (xy 131.163723 -44.180184) (xy 131.203204 -44.301696)
			(xy 131.234978 -44.425446) (xy 131.258919 -44.550948) (xy 131.274932 -44.677705) (xy 131.282954 -44.805218)
			(xy 131.283456 -44.8691) (xy 131.282954 -44.932982) (xy 131.274932 -45.060495) (xy 131.258919 -45.187252)
			(xy 131.234978 -45.312754) (xy 131.203204 -45.436504) (xy 131.163723 -45.558016) (xy 131.11669 -45.676808)
			(xy 131.06229 -45.792413) (xy 131.000739 -45.904374) (xy 130.932279 -46.012249) (xy 130.857181 -46.115613)
			(xy 130.775741 -46.214058) (xy 130.68828 -46.307194) (xy 130.595144 -46.394655) (xy 130.496699 -46.476095)
			(xy 130.393335 -46.551193) (xy 130.28546 -46.619653) (xy 130.173499 -46.681204) (xy 130.057894 -46.735604)
			(xy 129.939102 -46.782637) (xy 129.81759 -46.822118) (xy 129.69384 -46.853892) (xy 129.568338 -46.877833)
			(xy 129.441581 -46.893846) (xy 129.314068 -46.901868) (xy 129.186304 -46.901868) (xy 129.058791 -46.893846)
			(xy 128.932034 -46.877833) (xy 128.806532 -46.853892) (xy 128.682782 -46.822118) (xy 128.56127 -46.782637)
			(xy 128.442478 -46.735604) (xy 128.326873 -46.681204) (xy 128.214912 -46.619653) (xy 128.107037 -46.551193)
			(xy 128.003673 -46.476095) (xy 127.905228 -46.394655) (xy 127.812092 -46.307194) (xy 127.724631 -46.214058)
			(xy 127.643191 -46.115613) (xy 127.568093 -46.012249) (xy 127.499633 -45.904374) (xy 127.438082 -45.792413)
			(xy 127.383682 -45.676808) (xy 127.336649 -45.558016) (xy 127.297168 -45.436504) (xy 127.265394 -45.312754)
			(xy 127.241453 -45.187252) (xy 127.22544 -45.060495) (xy 127.217418 -44.932982) (xy 119.854732 -44.932982)
			(xy 119.854732 -44.933038) (xy 119.846703 -45.060662) (xy 119.830675 -45.18753) (xy 119.806714 -45.313142)
			(xy 119.774912 -45.437) (xy 119.735396 -45.558618) (xy 119.688322 -45.677515) (xy 119.633875 -45.793221)
			(xy 119.57227 -45.90528) (xy 119.50375 -46.013249) (xy 119.428586 -46.116703) (xy 119.347075 -46.215234)
			(xy 119.259538 -46.308452) (xy 119.16632 -46.395989) (xy 119.067789 -46.4775) (xy 118.964335 -46.552664)
			(xy 118.856366 -46.621184) (xy 118.744307 -46.682789) (xy 118.628601 -46.737236) (xy 118.509704 -46.78431)
			(xy 118.388086 -46.823826) (xy 118.264228 -46.855628) (xy 118.138616 -46.879589) (xy 118.011748 -46.895617)
			(xy 117.884124 -46.903646) (xy 117.756248 -46.903646) (xy 117.628624 -46.895617) (xy 117.501756 -46.879589)
			(xy 117.376144 -46.855628) (xy 117.252286 -46.823826) (xy 117.130668 -46.78431) (xy 117.011771 -46.737236)
			(xy 116.896065 -46.682789) (xy 116.784006 -46.621184) (xy 116.676037 -46.552664) (xy 116.572583 -46.4775)
			(xy 116.474052 -46.395989) (xy 116.380834 -46.308452) (xy 116.293297 -46.215234) (xy 116.211786 -46.116703)
			(xy 116.136622 -46.013249) (xy 116.068102 -45.90528) (xy 116.006497 -45.793221) (xy 115.95205 -45.677515)
			(xy 115.904976 -45.558618) (xy 115.86546 -45.437) (xy 115.833658 -45.313142) (xy 115.809697 -45.18753)
			(xy 115.793669 -45.060662) (xy 115.78564 -44.933038) (xy 82.202789 -44.933038) (xy 82.22234 -44.952158)
			(xy 82.281965 -45.009271) (xy 82.396404 -45.128313) (xy 82.505116 -45.252606) (xy 82.607861 -45.381877)
			(xy 82.70441 -45.515838) (xy 82.794549 -45.654193) (xy 82.87808 -45.796635) (xy 82.954818 -45.94285)
			(xy 82.997807 -46.035061) (xy 88.315792 -46.035061) (xy 88.315792 -45.963739) (xy 88.323778 -45.892865)
			(xy 88.339648 -45.82333) (xy 88.363205 -45.75601) (xy 88.39415 -45.691751) (xy 88.432096 -45.63136)
			(xy 88.476565 -45.575598) (xy 88.526998 -45.525165) (xy 88.58276 -45.480696) (xy 88.643151 -45.44275)
			(xy 88.70741 -45.411805) (xy 88.77473 -45.388248) (xy 88.844265 -45.372378) (xy 88.915139 -45.364392)
			(xy 88.986461 -45.364392) (xy 89.057335 -45.372378) (xy 89.12687 -45.388248) (xy 89.19419 -45.411805)
			(xy 89.258449 -45.44275) (xy 89.31884 -45.480696) (xy 89.374602 -45.525165) (xy 89.425035 -45.575598)
			(xy 89.469504 -45.63136) (xy 89.50745 -45.691751) (xy 89.538395 -45.75601) (xy 89.561952 -45.82333)
			(xy 89.577822 -45.892865) (xy 89.585808 -45.963739) (xy 89.586308 -45.9994) (xy 89.585808 -46.035061)
			(xy 89.577822 -46.105935) (xy 89.561952 -46.17547) (xy 89.538395 -46.24279) (xy 89.50745 -46.307049)
			(xy 89.469504 -46.36744) (xy 89.425035 -46.423202) (xy 89.374602 -46.473635) (xy 89.31884 -46.518104)
			(xy 89.258449 -46.55605) (xy 89.19419 -46.586995) (xy 89.12687 -46.610552) (xy 89.057335 -46.626422)
			(xy 88.986461 -46.634408) (xy 88.915139 -46.634408) (xy 88.844265 -46.626422) (xy 88.77473 -46.610552)
			(xy 88.70741 -46.586995) (xy 88.643151 -46.55605) (xy 88.58276 -46.518104) (xy 88.526998 -46.473635)
			(xy 88.476565 -46.423202) (xy 88.432096 -46.36744) (xy 88.39415 -46.307049) (xy 88.363205 -46.24279)
			(xy 88.339648 -46.17547) (xy 88.323778 -46.105935) (xy 88.315792 -46.035061) (xy 82.997807 -46.035061)
			(xy 83.024591 -46.092512) (xy 83.087247 -46.245292) (xy 83.142645 -46.40085) (xy 83.190664 -46.558841)
			(xy 83.231197 -46.718918) (xy 83.264154 -46.880723) (xy 83.289462 -47.0439) (xy 83.307066 -47.208087)
			(xy 83.316926 -47.372921) (xy 83.31902 -47.538035) (xy 83.313344 -47.703066) (xy 83.29991 -47.867646)
			(xy 83.278749 -48.031413) (xy 83.249907 -48.194002) (xy 83.213447 -48.355055) (xy 83.169451 -48.514214)
			(xy 83.118016 -48.671127) (xy 83.059256 -48.825447) (xy 82.993301 -48.976831) (xy 82.920297 -49.124944)
			(xy 82.840405 -49.26946) (xy 82.753804 -49.410056) (xy 82.660684 -49.546423) (xy 82.561251 -49.678258)
			(xy 82.455727 -49.805269) (xy 82.400394 -49.86655) (xy 82.385501 -49.883558) (xy 82.36137 -49.921782)
			(xy 82.344382 -49.963672) (xy 82.335072 -50.007906) (xy 82.333734 -50.05309) (xy 82.340411 -50.097798)
			(xy 82.354891 -50.140619) (xy 82.376718 -50.180203) (xy 82.405204 -50.215302) (xy 82.43945 -50.244808)
			(xy 82.478375 -50.26779) (xy 82.520752 -50.283524) (xy 82.565244 -50.291512) (xy 82.587846 -50.292)
			(xy 93.2688 -50.292) (xy 95.5802 -47.9806) (xy 113.3348 -47.9806) (xy 115.5954 -50.2412) (xy 131.572 -50.2412)
			(xy 133.8072 -48.006) (xy 151.384 -48.006) (xy 153.4922 -50.1142) (xy 158.2928 -50.1142) (xy 160.2994 -48.1076)
			(xy 204.343 -48.1076) (xy 206.5528 -50.3174) (xy 207.05572 -50.3174) (xy 207.0784 -50.316899) (xy 207.123039 -50.308844)
			(xy 207.16554 -50.292992) (xy 207.204551 -50.269847) (xy 207.238835 -50.240145) (xy 207.267301 -50.204829)
			(xy 207.289046 -50.165021) (xy 207.303379 -50.121985) (xy 207.309845 -50.077087) (xy 207.308239 -50.031756)
			(xy 207.29861 -49.987429) (xy 207.281267 -49.945515) (xy 207.256758 -49.907346) (xy 207.241648 -49.890426)
			(xy 207.18542 -49.829297) (xy 207.078133 -49.702481) (xy 206.976968 -49.57073) (xy 206.882151 -49.434339)
			(xy 206.793896 -49.293614) (xy 206.712398 -49.14887) (xy 206.637842 -49.000431) (xy 206.570394 -48.84863)
			(xy 206.510206 -48.693807) (xy 206.457412 -48.53631) (xy 206.41213 -48.37649) (xy 206.374463 -48.214707)
			(xy 206.344494 -48.051323) (xy 206.322291 -47.886703) (xy 206.307903 -47.721217) (xy 206.301362 -47.555235)
			(xy 206.302684 -47.38913) (xy 206.311865 -47.223273) (xy 206.328885 -47.058037) (xy 206.353706 -46.893791)
			(xy 206.386272 -46.730904) (xy 206.426509 -46.569741) (xy 206.474329 -46.410663) (xy 206.529623 -46.254025)
			(xy 206.592267 -46.10018) (xy 206.662123 -45.949472) (xy 206.739032 -45.802239) (xy 206.822823 -45.65881)
			(xy 206.913307 -45.519507) (xy 207.010282 -45.384643) (xy 207.113532 -45.254519) (xy 207.222823 -45.129426)
			(xy 207.337912 -45.009646) (xy 207.397858 -44.952158) (xy 207.421655 -44.928859) (xy 207.463388 -44.876959)
			(xy 207.497738 -44.819903) (xy 207.524075 -44.758734) (xy 207.541919 -44.694571) (xy 207.550943 -44.628587)
			(xy 207.551528 -44.595288) (xy 207.551274 -41.500044) (xy 207.551757 -41.433094) (xy 207.559682 -41.299429)
			(xy 207.575512 -41.166468) (xy 207.599191 -41.034678) (xy 207.630636 -40.904522) (xy 207.669737 -40.776459)
			(xy 207.716355 -40.650936) (xy 207.770329 -40.528396) (xy 207.831467 -40.409268) (xy 207.899555 -40.293972)
			(xy 207.974354 -40.182912) (xy 208.055601 -40.076478) (xy 208.14301 -39.975045) (xy 208.236276 -39.878968)
			(xy 208.335069 -39.788585) (xy 208.439044 -39.704213) (xy 208.547834 -39.62615) (xy 208.661058 -39.554669)
			(xy 208.778318 -39.490021) (xy 208.899202 -39.432433) (xy 209.023285 -39.382108) (xy 209.150131 -39.339222)
			(xy 209.279296 -39.303927) (xy 209.410324 -39.276345) (xy 209.542757 -39.256575) (xy 209.676128 -39.244685)
			(xy 209.809969 -39.240716) (xy 209.94381 -39.244685) (xy 210.077181 -39.256575) (xy 210.209614 -39.276345)
			(xy 210.340642 -39.303927) (xy 210.469807 -39.339222) (xy 210.596653 -39.382108) (xy 210.720736 -39.432433)
			(xy 210.84162 -39.490021) (xy 210.95888 -39.554669) (xy 211.072104 -39.62615) (xy 211.180894 -39.704213)
			(xy 211.284869 -39.788585) (xy 211.383662 -39.878968) (xy 211.476928 -39.975045) (xy 211.564337 -40.076478)
			(xy 211.645584 -40.182912) (xy 211.720383 -40.293972) (xy 211.788471 -40.409268) (xy 211.849609 -40.528396)
			(xy 211.903583 -40.650936) (xy 211.950201 -40.776459) (xy 211.989302 -40.904522) (xy 212.020747 -41.034678)
			(xy 212.044426 -41.166468) (xy 212.060256 -41.299429) (xy 212.068181 -41.433094) (xy 212.068664 -41.500044)
			(xy 212.068664 -44.595288) (xy 212.069212 -44.628591) (xy 212.078203 -44.694588) (xy 212.096033 -44.758763)
			(xy 212.122377 -44.819938) (xy 212.156749 -44.87699) (xy 212.19852 -44.928871) (xy 212.222334 -44.952158)
			(xy 212.282312 -45.009613) (xy 212.397397 -45.129398) (xy 212.506684 -45.254494) (xy 212.609929 -45.384622)
			(xy 212.706901 -45.51949) (xy 212.797381 -45.658795) (xy 212.881169 -45.802226) (xy 212.958075 -45.949462)
			(xy 213.027927 -46.100172) (xy 213.090569 -46.254018) (xy 213.145861 -46.410657) (xy 213.193678 -46.569737)
			(xy 213.233914 -46.730901) (xy 213.266478 -46.893788) (xy 213.291297 -47.058035) (xy 213.308316 -47.223271)
			(xy 213.317497 -47.389128) (xy 213.318819 -47.555234) (xy 213.312279 -47.721216) (xy 213.297892 -47.886703)
			(xy 213.27569 -48.051323) (xy 213.245722 -48.214708) (xy 213.238702 -48.244861) (xy 217.042992 -48.244861)
			(xy 217.042992 -48.173539) (xy 217.050978 -48.102665) (xy 217.066848 -48.03313) (xy 217.090405 -47.96581)
			(xy 217.12135 -47.901551) (xy 217.159296 -47.84116) (xy 217.203765 -47.785398) (xy 217.254198 -47.734965)
			(xy 217.30996 -47.690496) (xy 217.370351 -47.65255) (xy 217.43461 -47.621605) (xy 217.50193 -47.598048)
			(xy 217.571465 -47.582178) (xy 217.642339 -47.574192) (xy 217.713661 -47.574192) (xy 217.784535 -47.582178)
			(xy 217.85407 -47.598048) (xy 217.92139 -47.621605) (xy 217.985649 -47.65255) (xy 218.04604 -47.690496)
			(xy 218.101802 -47.734965) (xy 218.152235 -47.785398) (xy 218.196704 -47.84116) (xy 218.23465 -47.901551)
			(xy 218.265595 -47.96581) (xy 218.289152 -48.03313) (xy 218.305022 -48.102665) (xy 218.313008 -48.173539)
			(xy 218.313508 -48.2092) (xy 218.313008 -48.244861) (xy 224.662992 -48.244861) (xy 224.662992 -48.173539)
			(xy 224.670978 -48.102665) (xy 224.686848 -48.03313) (xy 224.710405 -47.96581) (xy 224.74135 -47.901551)
			(xy 224.779296 -47.84116) (xy 224.823765 -47.785398) (xy 224.874198 -47.734965) (xy 224.92996 -47.690496)
			(xy 224.990351 -47.65255) (xy 225.05461 -47.621605) (xy 225.12193 -47.598048) (xy 225.191465 -47.582178)
			(xy 225.262339 -47.574192) (xy 225.333661 -47.574192) (xy 225.404535 -47.582178) (xy 225.47407 -47.598048)
			(xy 225.54139 -47.621605) (xy 225.605649 -47.65255) (xy 225.66604 -47.690496) (xy 225.721802 -47.734965)
			(xy 225.772235 -47.785398) (xy 225.816704 -47.84116) (xy 225.85465 -47.901551) (xy 225.885595 -47.96581)
			(xy 225.909152 -48.03313) (xy 225.925022 -48.102665) (xy 225.933008 -48.173539) (xy 225.933508 -48.2092)
			(xy 225.933008 -48.244861) (xy 232.282992 -48.244861) (xy 232.282992 -48.173539) (xy 232.290978 -48.102665)
			(xy 232.306848 -48.03313) (xy 232.330405 -47.96581) (xy 232.36135 -47.901551) (xy 232.399296 -47.84116)
			(xy 232.443765 -47.785398) (xy 232.494198 -47.734965) (xy 232.54996 -47.690496) (xy 232.610351 -47.65255)
			(xy 232.67461 -47.621605) (xy 232.74193 -47.598048) (xy 232.811465 -47.582178) (xy 232.882339 -47.574192)
			(xy 232.953661 -47.574192) (xy 233.024535 -47.582178) (xy 233.09407 -47.598048) (xy 233.16139 -47.621605)
			(xy 233.225649 -47.65255) (xy 233.28604 -47.690496) (xy 233.341802 -47.734965) (xy 233.392235 -47.785398)
			(xy 233.436704 -47.84116) (xy 233.47465 -47.901551) (xy 233.505595 -47.96581) (xy 233.529152 -48.03313)
			(xy 233.545022 -48.102665) (xy 233.553008 -48.173539) (xy 233.553508 -48.2092) (xy 233.553008 -48.244861)
			(xy 239.902992 -48.244861) (xy 239.902992 -48.173539) (xy 239.910978 -48.102665) (xy 239.926848 -48.03313)
			(xy 239.950405 -47.96581) (xy 239.98135 -47.901551) (xy 240.019296 -47.84116) (xy 240.063765 -47.785398)
			(xy 240.114198 -47.734965) (xy 240.16996 -47.690496) (xy 240.230351 -47.65255) (xy 240.29461 -47.621605)
			(xy 240.36193 -47.598048) (xy 240.431465 -47.582178) (xy 240.502339 -47.574192) (xy 240.573661 -47.574192)
			(xy 240.644535 -47.582178) (xy 240.71407 -47.598048) (xy 240.78139 -47.621605) (xy 240.845649 -47.65255)
			(xy 240.90604 -47.690496) (xy 240.961802 -47.734965) (xy 241.012235 -47.785398) (xy 241.056704 -47.84116)
			(xy 241.09465 -47.901551) (xy 241.125595 -47.96581) (xy 241.149152 -48.03313) (xy 241.165022 -48.102665)
			(xy 241.173008 -48.173539) (xy 241.173508 -48.2092) (xy 241.173008 -48.244861) (xy 247.522992 -48.244861)
			(xy 247.522992 -48.173539) (xy 247.530978 -48.102665) (xy 247.546848 -48.03313) (xy 247.570405 -47.96581)
			(xy 247.60135 -47.901551) (xy 247.639296 -47.84116) (xy 247.683765 -47.785398) (xy 247.734198 -47.734965)
			(xy 247.78996 -47.690496) (xy 247.850351 -47.65255) (xy 247.91461 -47.621605) (xy 247.98193 -47.598048)
			(xy 248.051465 -47.582178) (xy 248.122339 -47.574192) (xy 248.193661 -47.574192) (xy 248.264535 -47.582178)
			(xy 248.33407 -47.598048) (xy 248.40139 -47.621605) (xy 248.465649 -47.65255) (xy 248.52604 -47.690496)
			(xy 248.581802 -47.734965) (xy 248.632235 -47.785398) (xy 248.676704 -47.84116) (xy 248.71465 -47.901551)
			(xy 248.745595 -47.96581) (xy 248.769152 -48.03313) (xy 248.785022 -48.102665) (xy 248.793008 -48.173539)
			(xy 248.793508 -48.2092) (xy 248.793008 -48.244861) (xy 255.142992 -48.244861) (xy 255.142992 -48.173539)
			(xy 255.150978 -48.102665) (xy 255.166848 -48.03313) (xy 255.190405 -47.96581) (xy 255.22135 -47.901551)
			(xy 255.259296 -47.84116) (xy 255.303765 -47.785398) (xy 255.354198 -47.734965) (xy 255.40996 -47.690496)
			(xy 255.470351 -47.65255) (xy 255.53461 -47.621605) (xy 255.60193 -47.598048) (xy 255.671465 -47.582178)
			(xy 255.742339 -47.574192) (xy 255.813661 -47.574192) (xy 255.884535 -47.582178) (xy 255.95407 -47.598048)
			(xy 256.02139 -47.621605) (xy 256.085649 -47.65255) (xy 256.14604 -47.690496) (xy 256.201802 -47.734965)
			(xy 256.252235 -47.785398) (xy 256.296704 -47.84116) (xy 256.33465 -47.901551) (xy 256.365595 -47.96581)
			(xy 256.389152 -48.03313) (xy 256.405022 -48.102665) (xy 256.413008 -48.173539) (xy 256.413508 -48.2092)
			(xy 256.413008 -48.244861) (xy 262.762992 -48.244861) (xy 262.762992 -48.173539) (xy 262.770978 -48.102665)
			(xy 262.786848 -48.03313) (xy 262.810405 -47.96581) (xy 262.84135 -47.901551) (xy 262.879296 -47.84116)
			(xy 262.923765 -47.785398) (xy 262.974198 -47.734965) (xy 263.02996 -47.690496) (xy 263.090351 -47.65255)
			(xy 263.15461 -47.621605) (xy 263.22193 -47.598048) (xy 263.291465 -47.582178) (xy 263.362339 -47.574192)
			(xy 263.433661 -47.574192) (xy 263.504535 -47.582178) (xy 263.57407 -47.598048) (xy 263.64139 -47.621605)
			(xy 263.705649 -47.65255) (xy 263.76604 -47.690496) (xy 263.821802 -47.734965) (xy 263.872235 -47.785398)
			(xy 263.916704 -47.84116) (xy 263.95465 -47.901551) (xy 263.985595 -47.96581) (xy 264.009152 -48.03313)
			(xy 264.025022 -48.102665) (xy 264.033008 -48.173539) (xy 264.033508 -48.2092) (xy 264.033008 -48.244861)
			(xy 270.382992 -48.244861) (xy 270.382992 -48.173539) (xy 270.390978 -48.102665) (xy 270.406848 -48.03313)
			(xy 270.430405 -47.96581) (xy 270.46135 -47.901551) (xy 270.499296 -47.84116) (xy 270.543765 -47.785398)
			(xy 270.594198 -47.734965) (xy 270.64996 -47.690496) (xy 270.710351 -47.65255) (xy 270.77461 -47.621605)
			(xy 270.84193 -47.598048) (xy 270.911465 -47.582178) (xy 270.982339 -47.574192) (xy 271.053661 -47.574192)
			(xy 271.124535 -47.582178) (xy 271.19407 -47.598048) (xy 271.26139 -47.621605) (xy 271.325649 -47.65255)
			(xy 271.38604 -47.690496) (xy 271.441802 -47.734965) (xy 271.492235 -47.785398) (xy 271.536704 -47.84116)
			(xy 271.57465 -47.901551) (xy 271.605595 -47.96581) (xy 271.629152 -48.03313) (xy 271.645022 -48.102665)
			(xy 271.653008 -48.173539) (xy 271.653508 -48.2092) (xy 271.653008 -48.244861) (xy 278.002992 -48.244861)
			(xy 278.002992 -48.173539) (xy 278.010978 -48.102665) (xy 278.026848 -48.03313) (xy 278.050405 -47.96581)
			(xy 278.08135 -47.901551) (xy 278.119296 -47.84116) (xy 278.163765 -47.785398) (xy 278.214198 -47.734965)
			(xy 278.26996 -47.690496) (xy 278.330351 -47.65255) (xy 278.39461 -47.621605) (xy 278.46193 -47.598048)
			(xy 278.531465 -47.582178) (xy 278.602339 -47.574192) (xy 278.673661 -47.574192) (xy 278.744535 -47.582178)
			(xy 278.81407 -47.598048) (xy 278.88139 -47.621605) (xy 278.945649 -47.65255) (xy 279.00604 -47.690496)
			(xy 279.061802 -47.734965) (xy 279.112235 -47.785398) (xy 279.156704 -47.84116) (xy 279.19465 -47.901551)
			(xy 279.225595 -47.96581) (xy 279.249152 -48.03313) (xy 279.265022 -48.102665) (xy 279.273008 -48.173539)
			(xy 279.273508 -48.2092) (xy 279.273008 -48.244861) (xy 285.622992 -48.244861) (xy 285.622992 -48.173539)
			(xy 285.630978 -48.102665) (xy 285.646848 -48.03313) (xy 285.670405 -47.96581) (xy 285.70135 -47.901551)
			(xy 285.739296 -47.84116) (xy 285.783765 -47.785398) (xy 285.834198 -47.734965) (xy 285.88996 -47.690496)
			(xy 285.950351 -47.65255) (xy 286.01461 -47.621605) (xy 286.08193 -47.598048) (xy 286.151465 -47.582178)
			(xy 286.222339 -47.574192) (xy 286.293661 -47.574192) (xy 286.364535 -47.582178) (xy 286.43407 -47.598048)
			(xy 286.50139 -47.621605) (xy 286.565649 -47.65255) (xy 286.62604 -47.690496) (xy 286.681802 -47.734965)
			(xy 286.732235 -47.785398) (xy 286.776704 -47.84116) (xy 286.81465 -47.901551) (xy 286.845595 -47.96581)
			(xy 286.869152 -48.03313) (xy 286.885022 -48.102665) (xy 286.893008 -48.173539) (xy 286.893508 -48.2092)
			(xy 286.893008 -48.244861) (xy 293.242992 -48.244861) (xy 293.242992 -48.173539) (xy 293.250978 -48.102665)
			(xy 293.266848 -48.03313) (xy 293.290405 -47.96581) (xy 293.32135 -47.901551) (xy 293.359296 -47.84116)
			(xy 293.403765 -47.785398) (xy 293.454198 -47.734965) (xy 293.50996 -47.690496) (xy 293.570351 -47.65255)
			(xy 293.63461 -47.621605) (xy 293.70193 -47.598048) (xy 293.771465 -47.582178) (xy 293.842339 -47.574192)
			(xy 293.913661 -47.574192) (xy 293.984535 -47.582178) (xy 294.05407 -47.598048) (xy 294.12139 -47.621605)
			(xy 294.185649 -47.65255) (xy 294.24604 -47.690496) (xy 294.301802 -47.734965) (xy 294.352235 -47.785398)
			(xy 294.396704 -47.84116) (xy 294.43465 -47.901551) (xy 294.465595 -47.96581) (xy 294.489152 -48.03313)
			(xy 294.505022 -48.102665) (xy 294.513008 -48.173539) (xy 294.513508 -48.2092) (xy 294.513008 -48.244861)
			(xy 294.505022 -48.315735) (xy 294.489152 -48.38527) (xy 294.465595 -48.45259) (xy 294.43465 -48.516849)
			(xy 294.396704 -48.57724) (xy 294.352235 -48.633002) (xy 294.301802 -48.683435) (xy 294.24604 -48.727904)
			(xy 294.185649 -48.76585) (xy 294.12139 -48.796795) (xy 294.05407 -48.820352) (xy 293.984535 -48.836222)
			(xy 293.913661 -48.844208) (xy 293.842339 -48.844208) (xy 293.771465 -48.836222) (xy 293.70193 -48.820352)
			(xy 293.63461 -48.796795) (xy 293.570351 -48.76585) (xy 293.50996 -48.727904) (xy 293.454198 -48.683435)
			(xy 293.403765 -48.633002) (xy 293.359296 -48.57724) (xy 293.32135 -48.516849) (xy 293.290405 -48.45259)
			(xy 293.266848 -48.38527) (xy 293.250978 -48.315735) (xy 293.242992 -48.244861) (xy 286.893008 -48.244861)
			(xy 286.885022 -48.315735) (xy 286.869152 -48.38527) (xy 286.845595 -48.45259) (xy 286.81465 -48.516849)
			(xy 286.776704 -48.57724) (xy 286.732235 -48.633002) (xy 286.681802 -48.683435) (xy 286.62604 -48.727904)
			(xy 286.565649 -48.76585) (xy 286.50139 -48.796795) (xy 286.43407 -48.820352) (xy 286.364535 -48.836222)
			(xy 286.293661 -48.844208) (xy 286.222339 -48.844208) (xy 286.151465 -48.836222) (xy 286.08193 -48.820352)
			(xy 286.01461 -48.796795) (xy 285.950351 -48.76585) (xy 285.88996 -48.727904) (xy 285.834198 -48.683435)
			(xy 285.783765 -48.633002) (xy 285.739296 -48.57724) (xy 285.70135 -48.516849) (xy 285.670405 -48.45259)
			(xy 285.646848 -48.38527) (xy 285.630978 -48.315735) (xy 285.622992 -48.244861) (xy 279.273008 -48.244861)
			(xy 279.265022 -48.315735) (xy 279.249152 -48.38527) (xy 279.225595 -48.45259) (xy 279.19465 -48.516849)
			(xy 279.156704 -48.57724) (xy 279.112235 -48.633002) (xy 279.061802 -48.683435) (xy 279.00604 -48.727904)
			(xy 278.945649 -48.76585) (xy 278.88139 -48.796795) (xy 278.81407 -48.820352) (xy 278.744535 -48.836222)
			(xy 278.673661 -48.844208) (xy 278.602339 -48.844208) (xy 278.531465 -48.836222) (xy 278.46193 -48.820352)
			(xy 278.39461 -48.796795) (xy 278.330351 -48.76585) (xy 278.26996 -48.727904) (xy 278.214198 -48.683435)
			(xy 278.163765 -48.633002) (xy 278.119296 -48.57724) (xy 278.08135 -48.516849) (xy 278.050405 -48.45259)
			(xy 278.026848 -48.38527) (xy 278.010978 -48.315735) (xy 278.002992 -48.244861) (xy 271.653008 -48.244861)
			(xy 271.645022 -48.315735) (xy 271.629152 -48.38527) (xy 271.605595 -48.45259) (xy 271.57465 -48.516849)
			(xy 271.536704 -48.57724) (xy 271.492235 -48.633002) (xy 271.441802 -48.683435) (xy 271.38604 -48.727904)
			(xy 271.325649 -48.76585) (xy 271.26139 -48.796795) (xy 271.19407 -48.820352) (xy 271.124535 -48.836222)
			(xy 271.053661 -48.844208) (xy 270.982339 -48.844208) (xy 270.911465 -48.836222) (xy 270.84193 -48.820352)
			(xy 270.77461 -48.796795) (xy 270.710351 -48.76585) (xy 270.64996 -48.727904) (xy 270.594198 -48.683435)
			(xy 270.543765 -48.633002) (xy 270.499296 -48.57724) (xy 270.46135 -48.516849) (xy 270.430405 -48.45259)
			(xy 270.406848 -48.38527) (xy 270.390978 -48.315735) (xy 270.382992 -48.244861) (xy 264.033008 -48.244861)
			(xy 264.025022 -48.315735) (xy 264.009152 -48.38527) (xy 263.985595 -48.45259) (xy 263.95465 -48.516849)
			(xy 263.916704 -48.57724) (xy 263.872235 -48.633002) (xy 263.821802 -48.683435) (xy 263.76604 -48.727904)
			(xy 263.705649 -48.76585) (xy 263.64139 -48.796795) (xy 263.57407 -48.820352) (xy 263.504535 -48.836222)
			(xy 263.433661 -48.844208) (xy 263.362339 -48.844208) (xy 263.291465 -48.836222) (xy 263.22193 -48.820352)
			(xy 263.15461 -48.796795) (xy 263.090351 -48.76585) (xy 263.02996 -48.727904) (xy 262.974198 -48.683435)
			(xy 262.923765 -48.633002) (xy 262.879296 -48.57724) (xy 262.84135 -48.516849) (xy 262.810405 -48.45259)
			(xy 262.786848 -48.38527) (xy 262.770978 -48.315735) (xy 262.762992 -48.244861) (xy 256.413008 -48.244861)
			(xy 256.405022 -48.315735) (xy 256.389152 -48.38527) (xy 256.365595 -48.45259) (xy 256.33465 -48.516849)
			(xy 256.296704 -48.57724) (xy 256.252235 -48.633002) (xy 256.201802 -48.683435) (xy 256.14604 -48.727904)
			(xy 256.085649 -48.76585) (xy 256.02139 -48.796795) (xy 255.95407 -48.820352) (xy 255.884535 -48.836222)
			(xy 255.813661 -48.844208) (xy 255.742339 -48.844208) (xy 255.671465 -48.836222) (xy 255.60193 -48.820352)
			(xy 255.53461 -48.796795) (xy 255.470351 -48.76585) (xy 255.40996 -48.727904) (xy 255.354198 -48.683435)
			(xy 255.303765 -48.633002) (xy 255.259296 -48.57724) (xy 255.22135 -48.516849) (xy 255.190405 -48.45259)
			(xy 255.166848 -48.38527) (xy 255.150978 -48.315735) (xy 255.142992 -48.244861) (xy 248.793008 -48.244861)
			(xy 248.785022 -48.315735) (xy 248.769152 -48.38527) (xy 248.745595 -48.45259) (xy 248.71465 -48.516849)
			(xy 248.676704 -48.57724) (xy 248.632235 -48.633002) (xy 248.581802 -48.683435) (xy 248.52604 -48.727904)
			(xy 248.465649 -48.76585) (xy 248.40139 -48.796795) (xy 248.33407 -48.820352) (xy 248.264535 -48.836222)
			(xy 248.193661 -48.844208) (xy 248.122339 -48.844208) (xy 248.051465 -48.836222) (xy 247.98193 -48.820352)
			(xy 247.91461 -48.796795) (xy 247.850351 -48.76585) (xy 247.78996 -48.727904) (xy 247.734198 -48.683435)
			(xy 247.683765 -48.633002) (xy 247.639296 -48.57724) (xy 247.60135 -48.516849) (xy 247.570405 -48.45259)
			(xy 247.546848 -48.38527) (xy 247.530978 -48.315735) (xy 247.522992 -48.244861) (xy 241.173008 -48.244861)
			(xy 241.165022 -48.315735) (xy 241.149152 -48.38527) (xy 241.125595 -48.45259) (xy 241.09465 -48.516849)
			(xy 241.056704 -48.57724) (xy 241.012235 -48.633002) (xy 240.961802 -48.683435) (xy 240.90604 -48.727904)
			(xy 240.845649 -48.76585) (xy 240.78139 -48.796795) (xy 240.71407 -48.820352) (xy 240.644535 -48.836222)
			(xy 240.573661 -48.844208) (xy 240.502339 -48.844208) (xy 240.431465 -48.836222) (xy 240.36193 -48.820352)
			(xy 240.29461 -48.796795) (xy 240.230351 -48.76585) (xy 240.16996 -48.727904) (xy 240.114198 -48.683435)
			(xy 240.063765 -48.633002) (xy 240.019296 -48.57724) (xy 239.98135 -48.516849) (xy 239.950405 -48.45259)
			(xy 239.926848 -48.38527) (xy 239.910978 -48.315735) (xy 239.902992 -48.244861) (xy 233.553008 -48.244861)
			(xy 233.545022 -48.315735) (xy 233.529152 -48.38527) (xy 233.505595 -48.45259) (xy 233.47465 -48.516849)
			(xy 233.436704 -48.57724) (xy 233.392235 -48.633002) (xy 233.341802 -48.683435) (xy 233.28604 -48.727904)
			(xy 233.225649 -48.76585) (xy 233.16139 -48.796795) (xy 233.09407 -48.820352) (xy 233.024535 -48.836222)
			(xy 232.953661 -48.844208) (xy 232.882339 -48.844208) (xy 232.811465 -48.836222) (xy 232.74193 -48.820352)
			(xy 232.67461 -48.796795) (xy 232.610351 -48.76585) (xy 232.54996 -48.727904) (xy 232.494198 -48.683435)
			(xy 232.443765 -48.633002) (xy 232.399296 -48.57724) (xy 232.36135 -48.516849) (xy 232.330405 -48.45259)
			(xy 232.306848 -48.38527) (xy 232.290978 -48.315735) (xy 232.282992 -48.244861) (xy 225.933008 -48.244861)
			(xy 225.925022 -48.315735) (xy 225.909152 -48.38527) (xy 225.885595 -48.45259) (xy 225.85465 -48.516849)
			(xy 225.816704 -48.57724) (xy 225.772235 -48.633002) (xy 225.721802 -48.683435) (xy 225.66604 -48.727904)
			(xy 225.605649 -48.76585) (xy 225.54139 -48.796795) (xy 225.47407 -48.820352) (xy 225.404535 -48.836222)
			(xy 225.333661 -48.844208) (xy 225.262339 -48.844208) (xy 225.191465 -48.836222) (xy 225.12193 -48.820352)
			(xy 225.05461 -48.796795) (xy 224.990351 -48.76585) (xy 224.92996 -48.727904) (xy 224.874198 -48.683435)
			(xy 224.823765 -48.633002) (xy 224.779296 -48.57724) (xy 224.74135 -48.516849) (xy 224.710405 -48.45259)
			(xy 224.686848 -48.38527) (xy 224.670978 -48.315735) (xy 224.662992 -48.244861) (xy 218.313008 -48.244861)
			(xy 218.305022 -48.315735) (xy 218.289152 -48.38527) (xy 218.265595 -48.45259) (xy 218.23465 -48.516849)
			(xy 218.196704 -48.57724) (xy 218.152235 -48.633002) (xy 218.101802 -48.683435) (xy 218.04604 -48.727904)
			(xy 217.985649 -48.76585) (xy 217.92139 -48.796795) (xy 217.85407 -48.820352) (xy 217.784535 -48.836222)
			(xy 217.713661 -48.844208) (xy 217.642339 -48.844208) (xy 217.571465 -48.836222) (xy 217.50193 -48.820352)
			(xy 217.43461 -48.796795) (xy 217.370351 -48.76585) (xy 217.30996 -48.727904) (xy 217.254198 -48.683435)
			(xy 217.203765 -48.633002) (xy 217.159296 -48.57724) (xy 217.12135 -48.516849) (xy 217.090405 -48.45259)
			(xy 217.066848 -48.38527) (xy 217.050978 -48.315735) (xy 217.042992 -48.244861) (xy 213.238702 -48.244861)
			(xy 213.208057 -48.376492) (xy 213.162777 -48.536313) (xy 213.109985 -48.693812) (xy 213.0498 -48.848636)
			(xy 212.982355 -49.000438) (xy 212.907802 -49.148879) (xy 212.826308 -49.293626) (xy 212.738056 -49.434354)
			(xy 212.643244 -49.570748) (xy 212.542083 -49.702502) (xy 212.4348 -49.829322) (xy 212.378544 -49.890426)
			(xy 212.363464 -49.90737) (xy 212.33896 -49.945534) (xy 212.321619 -49.987441) (xy 212.311993 -50.031761)
			(xy 212.310387 -50.077086) (xy 212.316852 -50.121977) (xy 212.331183 -50.165007) (xy 212.352925 -50.204809)
			(xy 212.381386 -50.24012) (xy 212.415664 -50.269819) (xy 212.454669 -50.29296) (xy 212.497163 -50.308811)
			(xy 212.541795 -50.316866) (xy 212.564472 -50.3174) (xy 298.055792 -50.3174) (xy 298.078474 -50.316902)
			(xy 298.123118 -50.30885) (xy 298.165623 -50.293) (xy 298.204639 -50.269856) (xy 298.238926 -50.240154)
			(xy 298.267396 -50.204836) (xy 298.289144 -50.165025) (xy 298.303479 -50.121985) (xy 298.309945 -50.077085)
			(xy 298.308338 -50.031749) (xy 298.298707 -49.987419) (xy 298.28136 -49.945503) (xy 298.256847 -49.907332)
			(xy 298.24172 -49.890426) (xy 298.185492 -49.829296) (xy 298.078206 -49.70248) (xy 297.977042 -49.570729)
			(xy 297.882226 -49.434338) (xy 297.793971 -49.293613) (xy 297.712474 -49.148868) (xy 297.637919 -49.000429)
			(xy 297.570472 -48.848629) (xy 297.510284 -48.693806) (xy 297.45749 -48.536309) (xy 297.412209 -48.376489)
			(xy 297.374542 -48.214706) (xy 297.344573 -48.051322) (xy 297.32237 -47.886702) (xy 297.307982 -47.721216)
			(xy 297.301442 -47.555235) (xy 297.302764 -47.38913) (xy 297.311945 -47.223273) (xy 297.328965 -47.058037)
			(xy 297.353785 -46.893792) (xy 297.38635 -46.730905) (xy 297.426588 -46.569742) (xy 297.474407 -46.410664)
			(xy 297.5297 -46.254026) (xy 297.592345 -46.100181) (xy 297.662199 -45.949473) (xy 297.739108 -45.80224)
			(xy 297.822898 -45.658811) (xy 297.913382 -45.519508) (xy 298.010356 -45.384643) (xy 298.113605 -45.254519)
			(xy 298.222895 -45.129426) (xy 298.337983 -45.009646) (xy 298.39793 -44.952158) (xy 298.421728 -44.92886)
			(xy 298.463464 -44.87696) (xy 298.497815 -44.819904) (xy 298.524154 -44.758735) (xy 298.541999 -44.694572)
			(xy 298.551024 -44.628587) (xy 298.5516 -44.595288) (xy 298.5516 -41.500044) (xy 298.552096 -41.4331)
			(xy 298.560028 -41.299448) (xy 298.575863 -41.166501) (xy 298.599546 -41.034725) (xy 298.630994 -40.904584)
			(xy 298.670097 -40.776534) (xy 298.716717 -40.651025) (xy 298.77069 -40.528499) (xy 298.831827 -40.409386)
			(xy 298.899913 -40.294103) (xy 298.974708 -40.183056) (xy 299.055951 -40.076635) (xy 299.143355 -39.975214)
			(xy 299.236615 -39.879149) (xy 299.335401 -39.788778) (xy 299.439368 -39.704417) (xy 299.548149 -39.626363)
			(xy 299.661364 -39.554891) (xy 299.778613 -39.490252) (xy 299.899486 -39.432671) (xy 300.023558 -39.382353)
			(xy 300.150393 -39.339473) (xy 300.279545 -39.304182) (xy 300.410562 -39.276604) (xy 300.542981 -39.256836)
			(xy 300.67634 -39.244948) (xy 300.810168 -39.24098) (xy 300.943996 -39.244948) (xy 301.077355 -39.256836)
			(xy 301.209774 -39.276604) (xy 301.340791 -39.304182) (xy 301.469943 -39.339473) (xy 301.596778 -39.382353)
			(xy 301.72085 -39.432671) (xy 301.841723 -39.490252) (xy 301.958972 -39.554891) (xy 302.072187 -39.626363)
			(xy 302.180968 -39.704417) (xy 302.284935 -39.788778) (xy 302.383721 -39.879149) (xy 302.476981 -39.975214)
			(xy 302.564385 -40.076635) (xy 302.645628 -40.183056) (xy 302.720423 -40.294103) (xy 302.788509 -40.409386)
			(xy 302.849646 -40.528499) (xy 302.903619 -40.651025) (xy 302.950239 -40.776534) (xy 302.989342 -40.904584)
			(xy 303.02079 -41.034725) (xy 303.044473 -41.166501) (xy 303.060308 -41.299448) (xy 303.06824 -41.4331)
			(xy 303.068736 -41.500044) (xy 303.06899 -44.595288) (xy 303.069523 -44.628583) (xy 303.078479 -44.694566)
			(xy 303.096268 -44.758734) (xy 303.122564 -44.819911) (xy 303.156885 -44.876973) (xy 303.198601 -44.928874)
			(xy 303.202858 -44.933038) (xy 336.785706 -44.933038) (xy 336.785706 -44.805162) (xy 336.793735 -44.677538)
			(xy 336.809763 -44.55067) (xy 336.833724 -44.425058) (xy 336.865526 -44.3012) (xy 336.905042 -44.179582)
			(xy 336.952116 -44.060685) (xy 337.006563 -43.944979) (xy 337.068168 -43.83292) (xy 337.136688 -43.724951)
			(xy 337.211852 -43.621497) (xy 337.293363 -43.522966) (xy 337.3809 -43.429748) (xy 337.474118 -43.342211)
			(xy 337.572649 -43.2607) (xy 337.676103 -43.185536) (xy 337.784072 -43.117016) (xy 337.896131 -43.055411)
			(xy 338.011837 -43.000964) (xy 338.130734 -42.95389) (xy 338.252352 -42.914374) (xy 338.37621 -42.882572)
			(xy 338.501822 -42.858611) (xy 338.62869 -42.842583) (xy 338.756314 -42.834554) (xy 338.88419 -42.834554)
			(xy 339.011814 -42.842583) (xy 339.138682 -42.858611) (xy 339.264294 -42.882572) (xy 339.388152 -42.914374)
			(xy 339.50977 -42.95389) (xy 339.628667 -43.000964) (xy 339.744373 -43.055411) (xy 339.856432 -43.117016)
			(xy 339.964401 -43.185536) (xy 340.067855 -43.2607) (xy 340.166386 -43.342211) (xy 340.259604 -43.429748)
			(xy 340.347141 -43.522966) (xy 340.428652 -43.621497) (xy 340.503816 -43.724951) (xy 340.572336 -43.83292)
			(xy 340.633941 -43.944979) (xy 340.688388 -44.060685) (xy 340.735462 -44.179582) (xy 340.774978 -44.3012)
			(xy 340.80678 -44.425058) (xy 340.830741 -44.55067) (xy 340.846769 -44.677538) (xy 340.854798 -44.805162)
			(xy 340.8553 -44.8691) (xy 340.854798 -44.932982) (xy 348.217484 -44.932982) (xy 348.217484 -44.805218)
			(xy 348.225506 -44.677705) (xy 348.241519 -44.550948) (xy 348.26546 -44.425446) (xy 348.297234 -44.301696)
			(xy 348.336715 -44.180184) (xy 348.383748 -44.061392) (xy 348.438148 -43.945787) (xy 348.499699 -43.833826)
			(xy 348.568159 -43.725951) (xy 348.643257 -43.622587) (xy 348.724697 -43.524142) (xy 348.812158 -43.431006)
			(xy 348.905294 -43.343545) (xy 349.003739 -43.262105) (xy 349.107103 -43.187007) (xy 349.214978 -43.118547)
			(xy 349.326939 -43.056996) (xy 349.442544 -43.002596) (xy 349.561336 -42.955563) (xy 349.682848 -42.916082)
			(xy 349.806598 -42.884308) (xy 349.9321 -42.860367) (xy 350.058857 -42.844354) (xy 350.18637 -42.836332)
			(xy 350.314134 -42.836332) (xy 350.441647 -42.844354) (xy 350.568404 -42.860367) (xy 350.693906 -42.884308)
			(xy 350.817656 -42.916082) (xy 350.939168 -42.955563) (xy 351.05796 -43.002596) (xy 351.173565 -43.056996)
			(xy 351.285526 -43.118547) (xy 351.393401 -43.187007) (xy 351.496765 -43.262105) (xy 351.59521 -43.343545)
			(xy 351.688346 -43.431006) (xy 351.775807 -43.524142) (xy 351.857247 -43.622587) (xy 351.932345 -43.725951)
			(xy 352.000805 -43.833826) (xy 352.062356 -43.945787) (xy 352.116756 -44.061392) (xy 352.163789 -44.180184)
			(xy 352.20327 -44.301696) (xy 352.235044 -44.425446) (xy 352.258985 -44.550948) (xy 352.274998 -44.677705)
			(xy 352.28302 -44.805218) (xy 352.283522 -44.8691) (xy 352.28302 -44.932982) (xy 352.274998 -45.060495)
			(xy 352.258985 -45.187252) (xy 352.235044 -45.312754) (xy 352.20327 -45.436504) (xy 352.163789 -45.558016)
			(xy 352.116756 -45.676808) (xy 352.062356 -45.792413) (xy 352.000805 -45.904374) (xy 351.932345 -46.012249)
			(xy 351.857247 -46.115613) (xy 351.775807 -46.214058) (xy 351.688346 -46.307194) (xy 351.59521 -46.394655)
			(xy 351.496765 -46.476095) (xy 351.393401 -46.551193) (xy 351.285526 -46.619653) (xy 351.173565 -46.681204)
			(xy 351.05796 -46.735604) (xy 350.939168 -46.782637) (xy 350.817656 -46.822118) (xy 350.693906 -46.853892)
			(xy 350.568404 -46.877833) (xy 350.441647 -46.893846) (xy 350.314134 -46.901868) (xy 350.18637 -46.901868)
			(xy 350.058857 -46.893846) (xy 349.9321 -46.877833) (xy 349.806598 -46.853892) (xy 349.682848 -46.822118)
			(xy 349.561336 -46.782637) (xy 349.442544 -46.735604) (xy 349.326939 -46.681204) (xy 349.214978 -46.619653)
			(xy 349.107103 -46.551193) (xy 349.003739 -46.476095) (xy 348.905294 -46.394655) (xy 348.812158 -46.307194)
			(xy 348.724697 -46.214058) (xy 348.643257 -46.115613) (xy 348.568159 -46.012249) (xy 348.499699 -45.904374)
			(xy 348.438148 -45.792413) (xy 348.383748 -45.676808) (xy 348.336715 -45.558016) (xy 348.297234 -45.436504)
			(xy 348.26546 -45.312754) (xy 348.241519 -45.187252) (xy 348.225506 -45.060495) (xy 348.217484 -44.932982)
			(xy 340.854798 -44.932982) (xy 340.854798 -44.933038) (xy 340.846769 -45.060662) (xy 340.830741 -45.18753)
			(xy 340.80678 -45.313142) (xy 340.774978 -45.437) (xy 340.735462 -45.558618) (xy 340.688388 -45.677515)
			(xy 340.633941 -45.793221) (xy 340.572336 -45.90528) (xy 340.503816 -46.013249) (xy 340.428652 -46.116703)
			(xy 340.347141 -46.215234) (xy 340.259604 -46.308452) (xy 340.166386 -46.395989) (xy 340.067855 -46.4775)
			(xy 339.964401 -46.552664) (xy 339.856432 -46.621184) (xy 339.744373 -46.682789) (xy 339.628667 -46.737236)
			(xy 339.50977 -46.78431) (xy 339.388152 -46.823826) (xy 339.264294 -46.855628) (xy 339.138682 -46.879589)
			(xy 339.011814 -46.895617) (xy 338.88419 -46.903646) (xy 338.756314 -46.903646) (xy 338.62869 -46.895617)
			(xy 338.501822 -46.879589) (xy 338.37621 -46.855628) (xy 338.252352 -46.823826) (xy 338.130734 -46.78431)
			(xy 338.011837 -46.737236) (xy 337.896131 -46.682789) (xy 337.784072 -46.621184) (xy 337.676103 -46.552664)
			(xy 337.572649 -46.4775) (xy 337.474118 -46.395989) (xy 337.3809 -46.308452) (xy 337.293363 -46.215234)
			(xy 337.211852 -46.116703) (xy 337.136688 -46.013249) (xy 337.068168 -45.90528) (xy 337.006563 -45.793221)
			(xy 336.952116 -45.677515) (xy 336.905042 -45.558618) (xy 336.865526 -45.437) (xy 336.833724 -45.313142)
			(xy 336.809763 -45.18753) (xy 336.793735 -45.060662) (xy 336.785706 -44.933038) (xy 303.202858 -44.933038)
			(xy 303.222406 -44.952158) (xy 303.282384 -45.009613) (xy 303.39747 -45.129397) (xy 303.506758 -45.254493)
			(xy 303.610004 -45.38462) (xy 303.706976 -45.519488) (xy 303.797458 -45.658794) (xy 303.881246 -45.802225)
			(xy 303.958152 -45.94946) (xy 304.028005 -46.10017) (xy 304.090648 -46.254017) (xy 304.14594 -46.410656)
			(xy 304.193758 -46.569735) (xy 304.233994 -46.7309) (xy 304.266558 -46.893788) (xy 304.291378 -47.058034)
			(xy 304.308397 -47.223271) (xy 304.317578 -47.389128) (xy 304.3189 -47.555234) (xy 304.31236 -47.721216)
			(xy 304.297972 -47.886703) (xy 304.27577 -48.051324) (xy 304.245802 -48.21471) (xy 304.208136 -48.376494)
			(xy 304.162856 -48.536315) (xy 304.110064 -48.693814) (xy 304.049878 -48.848638) (xy 303.982433 -49.00044)
			(xy 303.907879 -49.148881) (xy 303.826385 -49.293628) (xy 303.738132 -49.434356) (xy 303.643319 -49.57075)
			(xy 303.542157 -49.702504) (xy 303.434873 -49.829323) (xy 303.378616 -49.890426) (xy 303.363538 -49.907371)
			(xy 303.339036 -49.945536) (xy 303.321697 -49.987445) (xy 303.312072 -50.031765) (xy 303.310467 -50.07709)
			(xy 303.316932 -50.121981) (xy 303.331262 -50.165011) (xy 303.353003 -50.204814) (xy 303.381463 -50.240126)
			(xy 303.41574 -50.269826) (xy 303.454743 -50.292971) (xy 303.497236 -50.308825) (xy 303.541867 -50.316884)
			(xy 303.564544 -50.3174) (xy 313.3344 -50.3174) (xy 315.8617 -47.7901) (xy 333.883 -47.7901) (xy 336.5881 -50.4952)
			(xy 352.2726 -50.4952) (xy 354.965 -47.8028) (xy 372.0846 -47.8028) (xy 374.1674 -49.8856) (xy 379.5014 -49.8856)
			(xy 380.9492 -48.4378) (xy 424.5864 -48.4378) (xy 425.069 -47.9552) (xy 425.069 -43.688) (xy 423.0624 -41.6814)
			(xy 423.0624 -31.496) (xy 426.3136 -28.2448) (xy 426.3136 -19.9898) (xy 425.6786 -19.3548) (xy 420.0652 -19.3548)
			(xy 419.5572 -19.8628) (xy 419.5572 -32.0548) (xy 419.29939 -32.31261) (xy 419.283515 -32.329184)
			(xy 419.257426 -32.366936) (xy 419.238543 -32.40876) (xy 419.227481 -32.453296) (xy 419.224601 -32.499095)
			(xy 419.229995 -32.544667) (xy 419.243488 -32.588528) (xy 419.264642 -32.629251) (xy 419.292767 -32.665511)
			(xy 419.30955 -32.681164) (xy 419.346134 -32.714639) (xy 419.414353 -32.786619) (xy 419.476504 -32.863899)
			(xy 419.532177 -32.945969) (xy 419.581005 -33.032287) (xy 419.622665 -33.122283) (xy 419.656883 -33.215364)
			(xy 419.683433 -33.310915) (xy 419.70214 -33.408306) (xy 419.71288 -33.506894) (xy 419.715582 -33.606029)
			(xy 419.710229 -33.705055) (xy 419.696856 -33.803321) (xy 419.675551 -33.900176) (xy 419.646455 -33.994983)
			(xy 419.609759 -34.087115) (xy 419.565706 -34.175965) (xy 419.514587 -34.260946) (xy 419.456738 -34.341497)
			(xy 419.392543 -34.417087) (xy 419.322424 -34.487217) (xy 419.246843 -34.551424) (xy 419.166301 -34.609285)
			(xy 419.081328 -34.660417) (xy 418.992485 -34.704483) (xy 418.900358 -34.741193) (xy 418.805555 -34.770304)
			(xy 418.708703 -34.791624) (xy 418.61044 -34.805012) (xy 418.511414 -34.81038) (xy 418.412279 -34.807693)
			(xy 418.313689 -34.796968) (xy 418.216296 -34.778276) (xy 418.12074 -34.75174) (xy 418.027654 -34.717536)
			(xy 417.937652 -34.675889) (xy 417.851327 -34.627074) (xy 417.769248 -34.571414) (xy 417.691959 -34.509275)
			(xy 417.619968 -34.441067) (xy 417.586414 -34.404554) (xy 417.570733 -34.387774) (xy 417.534455 -34.359616)
			(xy 417.493707 -34.338437) (xy 417.449816 -34.324926) (xy 417.404211 -34.319523) (xy 417.358378 -34.322406)
			(xy 417.313809 -34.333478) (xy 417.271957 -34.352381) (xy 417.234183 -34.378498) (xy 417.217606 -34.394394)
			(xy 415.925 -35.687) (xy 387.4262 -35.687) (xy 380.7714 -29.0322) (xy 380.7714 -23.0124) (xy 379.476 -21.717)
			(xy 355.4984 -21.717) (xy 354.7364 -22.479) (xy 362.685582 -22.479) (xy 362.689653 -22.423378) (xy 362.701779 -22.368941)
			(xy 362.721702 -22.31685) (xy 362.748998 -22.268215) (xy 362.783084 -22.224072) (xy 362.823233 -22.185363)
			(xy 362.868591 -22.152912) (xy 362.918191 -22.127411) (xy 362.970975 -22.109404) (xy 363.025818 -22.099274)
			(xy 363.081552 -22.097237) (xy 363.136989 -22.103337) (xy 363.190946 -22.117443) (xy 363.242275 -22.139255)
			(xy 363.289881 -22.168309) (xy 363.332749 -22.203984) (xy 363.369966 -22.245521) (xy 363.400739 -22.292034)
			(xy 363.424411 -22.342531) (xy 363.434902 -22.3774) (xy 363.904782 -22.3774) (xy 363.908853 -22.321778)
			(xy 363.920979 -22.267341) (xy 363.940902 -22.21525) (xy 363.968198 -22.166615) (xy 364.002284 -22.122472)
			(xy 364.042433 -22.083763) (xy 364.087791 -22.051312) (xy 364.137391 -22.025811) (xy 364.190175 -22.007804)
			(xy 364.245018 -21.997674) (xy 364.300752 -21.995637) (xy 364.356189 -22.001737) (xy 364.410146 -22.015843)
			(xy 364.461475 -22.037655) (xy 364.509081 -22.066709) (xy 364.551949 -22.102384) (xy 364.589166 -22.143921)
			(xy 364.619939 -22.190434) (xy 364.643611 -22.240931) (xy 364.659679 -22.294338) (xy 364.667799 -22.349514)
			(xy 364.668308 -22.3774) (xy 364.667799 -22.405286) (xy 364.659679 -22.460462) (xy 364.643611 -22.513869)
			(xy 364.619939 -22.564366) (xy 364.589166 -22.610879) (xy 364.551949 -22.652416) (xy 364.509081 -22.688091)
			(xy 364.461475 -22.717145) (xy 364.410146 -22.738957) (xy 364.356189 -22.753063) (xy 364.300752 -22.759163)
			(xy 364.245018 -22.757126) (xy 364.190175 -22.746996) (xy 364.137391 -22.728989) (xy 364.087791 -22.703488)
			(xy 364.042433 -22.671037) (xy 364.002284 -22.632328) (xy 363.968198 -22.588185) (xy 363.940902 -22.53955)
			(xy 363.920979 -22.487459) (xy 363.908853 -22.433022) (xy 363.904782 -22.3774) (xy 363.434902 -22.3774)
			(xy 363.440479 -22.395938) (xy 363.448599 -22.451114) (xy 363.449108 -22.479) (xy 363.448599 -22.506886)
			(xy 363.440479 -22.562062) (xy 363.424411 -22.615469) (xy 363.400739 -22.665966) (xy 363.369966 -22.712479)
			(xy 363.332749 -22.754016) (xy 363.289881 -22.789691) (xy 363.242275 -22.818745) (xy 363.190946 -22.840557)
			(xy 363.136989 -22.854663) (xy 363.081552 -22.860763) (xy 363.025818 -22.858726) (xy 362.970975 -22.848596)
			(xy 362.918191 -22.830589) (xy 362.868591 -22.805088) (xy 362.823233 -22.772637) (xy 362.783084 -22.733928)
			(xy 362.748998 -22.689785) (xy 362.721702 -22.64115) (xy 362.701779 -22.589059) (xy 362.689653 -22.534622)
			(xy 362.685582 -22.479) (xy 354.7364 -22.479) (xy 353.773486 -23.441914) (xy 353.7712 -23.490936)
			(xy 353.769268 -23.521631) (xy 353.7582 -23.582131) (xy 353.739129 -23.640603) (xy 353.726658 -23.666446)
			(xy 376.656582 -23.666446) (xy 376.656582 -23.60651) (xy 376.664405 -23.547088) (xy 376.679918 -23.489195)
			(xy 376.702854 -23.433822) (xy 376.732821 -23.381916) (xy 376.769308 -23.334366) (xy 376.811688 -23.291986)
			(xy 376.859238 -23.255499) (xy 376.911144 -23.225532) (xy 376.966517 -23.202596) (xy 377.02441 -23.187083)
			(xy 377.083832 -23.17926) (xy 377.143768 -23.17926) (xy 377.20319 -23.187083) (xy 377.261083 -23.202596)
			(xy 377.316456 -23.225532) (xy 377.368362 -23.255499) (xy 377.415912 -23.291986) (xy 377.458292 -23.334366)
			(xy 377.494779 -23.381916) (xy 377.524746 -23.433822) (xy 377.547682 -23.489195) (xy 377.563195 -23.547088)
			(xy 377.571018 -23.60651) (xy 377.571508 -23.636478) (xy 377.571018 -23.666446) (xy 377.563195 -23.725868)
			(xy 377.547682 -23.783761) (xy 377.524746 -23.839134) (xy 377.494779 -23.89104) (xy 377.458292 -23.93859)
			(xy 377.415912 -23.98097) (xy 377.368362 -24.017457) (xy 377.316456 -24.047424) (xy 377.261083 -24.07036)
			(xy 377.20319 -24.085873) (xy 377.143768 -24.093696) (xy 377.083832 -24.093696) (xy 377.02441 -24.085873)
			(xy 376.966517 -24.07036) (xy 376.911144 -24.047424) (xy 376.859238 -24.017457) (xy 376.811688 -23.98097)
			(xy 376.769308 -23.93859) (xy 376.732821 -23.89104) (xy 376.702854 -23.839134) (xy 376.679918 -23.783761)
			(xy 376.664405 -23.725868) (xy 376.656582 -23.666446) (xy 353.726658 -23.666446) (xy 353.712399 -23.695995)
			(xy 353.678492 -23.747309) (xy 353.638019 -23.793619) (xy 353.591709 -23.834092) (xy 353.540395 -23.867999)
			(xy 353.485003 -23.894729) (xy 353.426531 -23.9138) (xy 353.366031 -23.924868) (xy 353.335336 -23.9268)
			(xy 353.286314 -23.929086) (xy 353.217226 -23.998174) (xy 353.201214 -24.014914) (xy 353.174942 -24.053061)
			(xy 353.156017 -24.095337) (xy 353.145063 -24.140342) (xy 353.142444 -24.186586) (xy 353.148247 -24.23254)
			(xy 353.162278 -24.276682) (xy 353.184075 -24.317552) (xy 353.212915 -24.353796) (xy 353.247845 -24.384216)
			(xy 353.267518 -24.396446) (xy 353.293155 -24.412155) (xy 353.340459 -24.44927) (xy 353.382496 -24.492259)
			(xy 353.418542 -24.540383) (xy 353.447975 -24.592813) (xy 353.470289 -24.648646) (xy 353.4851 -24.706919)
			(xy 353.492153 -24.766631) (xy 353.491325 -24.826752) (xy 353.482632 -24.886246) (xy 353.466223 -24.94409)
			(xy 353.442381 -24.999288) (xy 353.411516 -25.050888) (xy 353.37416 -25.098001) (xy 353.330956 -25.139818)
			(xy 353.282648 -25.175616) (xy 353.230068 -25.204781) (xy 353.174122 -25.226809) (xy 353.115773 -25.241322)
			(xy 353.056027 -25.248068) (xy 352.995911 -25.246933) (xy 352.936461 -25.237936) (xy 352.878702 -25.221231)
			(xy 352.823628 -25.197106) (xy 352.772186 -25.165978) (xy 352.725264 -25.128381) (xy 352.68367 -25.084963)
			(xy 352.648119 -25.036473) (xy 352.619224 -24.983744) (xy 352.597482 -24.927686) (xy 352.589846 -24.898604)
			(xy 352.581464 -24.86406) (xy 352.556318 -24.83866) (xy 352.544147 -24.827307) (xy 352.515308 -24.810718)
			(xy 352.483164 -24.802133) (xy 352.449894 -24.802133) (xy 352.41775 -24.810718) (xy 352.388911 -24.827307)
			(xy 352.37674 -24.83866) (xy 352.2726 -24.9428) (xy 352.2726 -25.302968) (xy 353.923582 -25.302968)
			(xy 353.923582 -25.243032) (xy 353.931405 -25.18361) (xy 353.946918 -25.125717) (xy 353.969854 -25.070344)
			(xy 353.999821 -25.018438) (xy 354.036308 -24.970888) (xy 354.078688 -24.928508) (xy 354.126238 -24.892021)
			(xy 354.178144 -24.862054) (xy 354.233517 -24.839118) (xy 354.29141 -24.823605) (xy 354.350832 -24.815782)
			(xy 354.410768 -24.815782) (xy 354.47019 -24.823605) (xy 354.528083 -24.839118) (xy 354.583456 -24.862054)
			(xy 354.635362 -24.892021) (xy 354.682912 -24.928508) (xy 354.69085 -24.936446) (xy 376.732782 -24.936446)
			(xy 376.732782 -24.87651) (xy 376.740605 -24.817088) (xy 376.756118 -24.759195) (xy 376.779054 -24.703822)
			(xy 376.809021 -24.651916) (xy 376.845508 -24.604366) (xy 376.887888 -24.561986) (xy 376.935438 -24.525499)
			(xy 376.987344 -24.495532) (xy 377.042717 -24.472596) (xy 377.10061 -24.457083) (xy 377.160032 -24.44926)
			(xy 377.219968 -24.44926) (xy 377.27939 -24.457083) (xy 377.337283 -24.472596) (xy 377.392656 -24.495532)
			(xy 377.444562 -24.525499) (xy 377.492112 -24.561986) (xy 377.534492 -24.604366) (xy 377.570979 -24.651916)
			(xy 377.600946 -24.703822) (xy 377.623882 -24.759195) (xy 377.639395 -24.817088) (xy 377.647218 -24.87651)
			(xy 377.647708 -24.906478) (xy 377.647218 -24.936446) (xy 377.639395 -24.995868) (xy 377.623882 -25.053761)
			(xy 377.600946 -25.109134) (xy 377.570979 -25.16104) (xy 377.534492 -25.20859) (xy 377.492112 -25.25097)
			(xy 377.444562 -25.287457) (xy 377.392656 -25.317424) (xy 377.337283 -25.34036) (xy 377.27939 -25.355873)
			(xy 377.219968 -25.363696) (xy 377.160032 -25.363696) (xy 377.10061 -25.355873) (xy 377.042717 -25.34036)
			(xy 376.987344 -25.317424) (xy 376.935438 -25.287457) (xy 376.887888 -25.25097) (xy 376.845508 -25.20859)
			(xy 376.809021 -25.16104) (xy 376.779054 -25.109134) (xy 376.756118 -25.053761) (xy 376.740605 -24.995868)
			(xy 376.732782 -24.936446) (xy 354.69085 -24.936446) (xy 354.725292 -24.970888) (xy 354.761779 -25.018438)
			(xy 354.791746 -25.070344) (xy 354.814682 -25.125717) (xy 354.830195 -25.18361) (xy 354.838018 -25.243032)
			(xy 354.838508 -25.273) (xy 354.838018 -25.302968) (xy 354.830195 -25.36239) (xy 354.814682 -25.420283)
			(xy 354.791746 -25.475656) (xy 354.761779 -25.527562) (xy 354.725292 -25.575112) (xy 354.682912 -25.617492)
			(xy 354.635362 -25.653979) (xy 354.583456 -25.683946) (xy 354.528083 -25.706882) (xy 354.47019 -25.722395)
			(xy 354.410768 -25.730218) (xy 354.350832 -25.730218) (xy 354.29141 -25.722395) (xy 354.233517 -25.706882)
			(xy 354.178144 -25.683946) (xy 354.126238 -25.653979) (xy 354.078688 -25.617492) (xy 354.036308 -25.575112)
			(xy 353.999821 -25.527562) (xy 353.969854 -25.475656) (xy 353.946918 -25.420283) (xy 353.931405 -25.36239)
			(xy 353.923582 -25.302968) (xy 352.2726 -25.302968) (xy 352.2726 -26.0858) (xy 373.607582 -26.0858)
			(xy 373.611653 -26.030178) (xy 373.623779 -25.975741) (xy 373.643702 -25.92365) (xy 373.670998 -25.875015)
			(xy 373.705084 -25.830872) (xy 373.745233 -25.792163) (xy 373.790591 -25.759712) (xy 373.840191 -25.734211)
			(xy 373.892975 -25.716204) (xy 373.947818 -25.706074) (xy 374.003552 -25.704037) (xy 374.058989 -25.710137)
			(xy 374.112946 -25.724243) (xy 374.164275 -25.746055) (xy 374.211881 -25.775109) (xy 374.254749 -25.810784)
			(xy 374.291966 -25.852321) (xy 374.322739 -25.898834) (xy 374.346411 -25.949331) (xy 374.362479 -26.002738)
			(xy 374.370599 -26.057914) (xy 374.371108 -26.0858) (xy 374.370599 -26.113686) (xy 374.362479 -26.168862)
			(xy 374.346411 -26.222269) (xy 374.330014 -26.257246) (xy 376.707382 -26.257246) (xy 376.707382 -26.19731)
			(xy 376.715205 -26.137888) (xy 376.730718 -26.079995) (xy 376.753654 -26.024622) (xy 376.783621 -25.972716)
			(xy 376.820108 -25.925166) (xy 376.862488 -25.882786) (xy 376.910038 -25.846299) (xy 376.961944 -25.816332)
			(xy 377.017317 -25.793396) (xy 377.07521 -25.777883) (xy 377.134632 -25.77006) (xy 377.194568 -25.77006)
			(xy 377.25399 -25.777883) (xy 377.311883 -25.793396) (xy 377.367256 -25.816332) (xy 377.419162 -25.846299)
			(xy 377.466712 -25.882786) (xy 377.509092 -25.925166) (xy 377.545579 -25.972716) (xy 377.575546 -26.024622)
			(xy 377.598482 -26.079995) (xy 377.613995 -26.137888) (xy 377.621818 -26.19731) (xy 377.622308 -26.227278)
			(xy 377.621818 -26.257246) (xy 377.613995 -26.316668) (xy 377.598482 -26.374561) (xy 377.575546 -26.429934)
			(xy 377.545579 -26.48184) (xy 377.509092 -26.52939) (xy 377.466712 -26.57177) (xy 377.419162 -26.608257)
			(xy 377.367256 -26.638224) (xy 377.311883 -26.66116) (xy 377.25399 -26.676673) (xy 377.194568 -26.684496)
			(xy 377.134632 -26.684496) (xy 377.07521 -26.676673) (xy 377.017317 -26.66116) (xy 376.961944 -26.638224)
			(xy 376.910038 -26.608257) (xy 376.862488 -26.57177) (xy 376.820108 -26.52939) (xy 376.783621 -26.48184)
			(xy 376.753654 -26.429934) (xy 376.730718 -26.374561) (xy 376.715205 -26.316668) (xy 376.707382 -26.257246)
			(xy 374.330014 -26.257246) (xy 374.322739 -26.272766) (xy 374.291966 -26.319279) (xy 374.254749 -26.360816)
			(xy 374.211881 -26.396491) (xy 374.164275 -26.425545) (xy 374.112946 -26.447357) (xy 374.058989 -26.461463)
			(xy 374.003552 -26.467563) (xy 373.947818 -26.465526) (xy 373.892975 -26.455396) (xy 373.840191 -26.437389)
			(xy 373.790591 -26.411888) (xy 373.745233 -26.379437) (xy 373.705084 -26.340728) (xy 373.670998 -26.296585)
			(xy 373.643702 -26.24795) (xy 373.623779 -26.195859) (xy 373.611653 -26.141422) (xy 373.607582 -26.0858)
			(xy 352.2726 -26.0858) (xy 352.2726 -27.0764) (xy 374.064782 -27.0764) (xy 374.068853 -27.020778)
			(xy 374.080979 -26.966341) (xy 374.100902 -26.91425) (xy 374.128198 -26.865615) (xy 374.162284 -26.821472)
			(xy 374.202433 -26.782763) (xy 374.247791 -26.750312) (xy 374.297391 -26.724811) (xy 374.350175 -26.706804)
			(xy 374.405018 -26.696674) (xy 374.460752 -26.694637) (xy 374.516189 -26.700737) (xy 374.570146 -26.714843)
			(xy 374.621475 -26.736655) (xy 374.669081 -26.765709) (xy 374.711949 -26.801384) (xy 374.749166 -26.842921)
			(xy 374.779939 -26.889434) (xy 374.803611 -26.939931) (xy 374.819679 -26.993338) (xy 374.827799 -27.048514)
			(xy 374.828308 -27.0764) (xy 374.827799 -27.104286) (xy 374.819679 -27.159462) (xy 374.803611 -27.212869)
			(xy 374.779939 -27.263366) (xy 374.749166 -27.309879) (xy 374.711949 -27.351416) (xy 374.669081 -27.387091)
			(xy 374.621475 -27.416145) (xy 374.570146 -27.437957) (xy 374.516189 -27.452063) (xy 374.460752 -27.458163)
			(xy 374.405018 -27.456126) (xy 374.350175 -27.445996) (xy 374.297391 -27.427989) (xy 374.247791 -27.402488)
			(xy 374.202433 -27.370037) (xy 374.162284 -27.331328) (xy 374.128198 -27.287185) (xy 374.100902 -27.23855)
			(xy 374.080979 -27.186459) (xy 374.068853 -27.132022) (xy 374.064782 -27.0764) (xy 352.2726 -27.0764)
			(xy 352.2726 -27.806646) (xy 376.681982 -27.806646) (xy 376.681982 -27.74671) (xy 376.689805 -27.687288)
			(xy 376.705318 -27.629395) (xy 376.728254 -27.574022) (xy 376.758221 -27.522116) (xy 376.794708 -27.474566)
			(xy 376.837088 -27.432186) (xy 376.884638 -27.395699) (xy 376.936544 -27.365732) (xy 376.991917 -27.342796)
			(xy 377.04981 -27.327283) (xy 377.109232 -27.31946) (xy 377.169168 -27.31946) (xy 377.22859 -27.327283)
			(xy 377.286483 -27.342796) (xy 377.341856 -27.365732) (xy 377.393762 -27.395699) (xy 377.441312 -27.432186)
			(xy 377.483692 -27.474566) (xy 377.520179 -27.522116) (xy 377.550146 -27.574022) (xy 377.573082 -27.629395)
			(xy 377.588595 -27.687288) (xy 377.596418 -27.74671) (xy 377.596908 -27.776678) (xy 377.596418 -27.806646)
			(xy 377.588595 -27.866068) (xy 377.573082 -27.923961) (xy 377.550146 -27.979334) (xy 377.520179 -28.03124)
			(xy 377.483692 -28.07879) (xy 377.441312 -28.12117) (xy 377.393762 -28.157657) (xy 377.341856 -28.187624)
			(xy 377.286483 -28.21056) (xy 377.22859 -28.226073) (xy 377.169168 -28.233896) (xy 377.109232 -28.233896)
			(xy 377.04981 -28.226073) (xy 376.991917 -28.21056) (xy 376.936544 -28.187624) (xy 376.884638 -28.157657)
			(xy 376.837088 -28.12117) (xy 376.794708 -28.07879) (xy 376.758221 -28.03124) (xy 376.728254 -27.979334)
			(xy 376.705318 -27.923961) (xy 376.689805 -27.866068) (xy 376.681982 -27.806646) (xy 352.2726 -27.806646)
			(xy 352.2726 -29.8897) (xy 378.586982 -29.8897) (xy 378.586982 -29.829764) (xy 378.594805 -29.770342)
			(xy 378.610318 -29.712449) (xy 378.633254 -29.657076) (xy 378.663221 -29.60517) (xy 378.699708 -29.55762)
			(xy 378.742088 -29.51524) (xy 378.789638 -29.478753) (xy 378.841544 -29.448786) (xy 378.896917 -29.42585)
			(xy 378.95481 -29.410337) (xy 379.014232 -29.402514) (xy 379.074168 -29.402514) (xy 379.13359 -29.410337)
			(xy 379.191483 -29.42585) (xy 379.246856 -29.448786) (xy 379.298762 -29.478753) (xy 379.346312 -29.51524)
			(xy 379.388692 -29.55762) (xy 379.425179 -29.60517) (xy 379.455146 -29.657076) (xy 379.478082 -29.712449)
			(xy 379.493595 -29.770342) (xy 379.501418 -29.829764) (xy 379.501908 -29.859732) (xy 379.501418 -29.8897)
			(xy 379.493595 -29.949122) (xy 379.478082 -30.007015) (xy 379.455146 -30.062388) (xy 379.425179 -30.114294)
			(xy 379.388692 -30.161844) (xy 379.346312 -30.204224) (xy 379.298762 -30.240711) (xy 379.246856 -30.270678)
			(xy 379.191483 -30.293614) (xy 379.13359 -30.309127) (xy 379.074168 -30.31695) (xy 379.014232 -30.31695)
			(xy 378.95481 -30.309127) (xy 378.896917 -30.293614) (xy 378.841544 -30.270678) (xy 378.789638 -30.240711)
			(xy 378.742088 -30.204224) (xy 378.699708 -30.161844) (xy 378.663221 -30.114294) (xy 378.633254 -30.062388)
			(xy 378.610318 -30.007015) (xy 378.594805 -29.949122) (xy 378.586982 -29.8897) (xy 352.2726 -29.8897)
			(xy 352.2726 -32.1249) (xy 378.52145 -32.1249) (xy 378.52145 -32.064964) (xy 378.529273 -32.005542)
			(xy 378.544786 -31.947649) (xy 378.567722 -31.892276) (xy 378.597689 -31.84037) (xy 378.634176 -31.79282)
			(xy 378.676556 -31.75044) (xy 378.724106 -31.713953) (xy 378.776012 -31.683986) (xy 378.831385 -31.66105)
			(xy 378.889278 -31.645537) (xy 378.9487 -31.637714) (xy 379.008636 -31.637714) (xy 379.068058 -31.645537)
			(xy 379.125951 -31.66105) (xy 379.181324 -31.683986) (xy 379.23323 -31.713953) (xy 379.28078 -31.75044)
			(xy 379.32316 -31.79282) (xy 379.359647 -31.84037) (xy 379.389614 -31.892276) (xy 379.41255 -31.947649)
			(xy 379.428063 -32.005542) (xy 379.435886 -32.064964) (xy 379.436376 -32.094932) (xy 379.435886 -32.1249)
			(xy 379.428063 -32.184322) (xy 379.41255 -32.242215) (xy 379.389614 -32.297588) (xy 379.359647 -32.349494)
			(xy 379.32316 -32.397044) (xy 379.28078 -32.439424) (xy 379.23323 -32.475911) (xy 379.181324 -32.505878)
			(xy 379.125951 -32.528814) (xy 379.068058 -32.544327) (xy 379.008636 -32.55215) (xy 378.9487 -32.55215)
			(xy 378.889278 -32.544327) (xy 378.831385 -32.528814) (xy 378.776012 -32.505878) (xy 378.724106 -32.475911)
			(xy 378.676556 -32.439424) (xy 378.634176 -32.397044) (xy 378.597689 -32.349494) (xy 378.567722 -32.297588)
			(xy 378.544786 -32.242215) (xy 378.529273 -32.184322) (xy 378.52145 -32.1249) (xy 352.2726 -32.1249)
			(xy 352.2726 -37.367968) (xy 377.393182 -37.367968) (xy 377.393182 -37.308032) (xy 377.401005 -37.24861)
			(xy 377.416518 -37.190717) (xy 377.439454 -37.135344) (xy 377.469421 -37.083438) (xy 377.505908 -37.035888)
			(xy 377.548288 -36.993508) (xy 377.595838 -36.957021) (xy 377.647744 -36.927054) (xy 377.703117 -36.904118)
			(xy 377.76101 -36.888605) (xy 377.820432 -36.880782) (xy 377.880368 -36.880782) (xy 377.93979 -36.888605)
			(xy 377.997683 -36.904118) (xy 378.053056 -36.927054) (xy 378.104962 -36.957021) (xy 378.152512 -36.993508)
			(xy 378.194892 -37.035888) (xy 378.231379 -37.083438) (xy 378.261346 -37.135344) (xy 378.284282 -37.190717)
			(xy 378.299795 -37.24861) (xy 378.307618 -37.308032) (xy 378.308108 -37.338) (xy 378.307618 -37.367968)
			(xy 378.299795 -37.42739) (xy 378.284282 -37.485283) (xy 378.261346 -37.540656) (xy 378.24373 -37.571168)
			(xy 379.475982 -37.571168) (xy 379.475982 -37.511232) (xy 379.483805 -37.45181) (xy 379.499318 -37.393917)
			(xy 379.522254 -37.338544) (xy 379.552221 -37.286638) (xy 379.588708 -37.239088) (xy 379.631088 -37.196708)
			(xy 379.678638 -37.160221) (xy 379.730544 -37.130254) (xy 379.785917 -37.107318) (xy 379.84381 -37.091805)
			(xy 379.903232 -37.083982) (xy 379.963168 -37.083982) (xy 380.02259 -37.091805) (xy 380.080483 -37.107318)
			(xy 380.135856 -37.130254) (xy 380.187762 -37.160221) (xy 380.235312 -37.196708) (xy 380.277692 -37.239088)
			(xy 380.314179 -37.286638) (xy 380.344146 -37.338544) (xy 380.367082 -37.393917) (xy 380.382595 -37.45181)
			(xy 380.390418 -37.511232) (xy 380.390908 -37.5412) (xy 380.390418 -37.571168) (xy 380.382595 -37.63059)
			(xy 380.367082 -37.688483) (xy 380.344146 -37.743856) (xy 380.314179 -37.795762) (xy 380.277692 -37.843312)
			(xy 380.235312 -37.885692) (xy 380.187762 -37.922179) (xy 380.135856 -37.952146) (xy 380.080483 -37.975082)
			(xy 380.02259 -37.990595) (xy 379.963168 -37.998418) (xy 379.903232 -37.998418) (xy 379.84381 -37.990595)
			(xy 379.785917 -37.975082) (xy 379.730544 -37.952146) (xy 379.678638 -37.922179) (xy 379.631088 -37.885692)
			(xy 379.588708 -37.843312) (xy 379.552221 -37.795762) (xy 379.522254 -37.743856) (xy 379.499318 -37.688483)
			(xy 379.483805 -37.63059) (xy 379.475982 -37.571168) (xy 378.24373 -37.571168) (xy 378.231379 -37.592562)
			(xy 378.194892 -37.640112) (xy 378.152512 -37.682492) (xy 378.104962 -37.718979) (xy 378.053056 -37.748946)
			(xy 377.997683 -37.771882) (xy 377.93979 -37.787395) (xy 377.880368 -37.795218) (xy 377.820432 -37.795218)
			(xy 377.76101 -37.787395) (xy 377.703117 -37.771882) (xy 377.647744 -37.748946) (xy 377.595838 -37.718979)
			(xy 377.548288 -37.682492) (xy 377.505908 -37.640112) (xy 377.469421 -37.592562) (xy 377.439454 -37.540656)
			(xy 377.416518 -37.485283) (xy 377.401005 -37.42739) (xy 377.393182 -37.367968) (xy 352.2726 -37.367968)
			(xy 352.2726 -37.8968) (xy 350.012 -40.1574) (xy 340.9696 -40.1574) (xy 338.3026 -37.4904) (xy 338.3026 -21.073618)
			(xy 338.3026 -21.039582) (xy 338.3026 -20.835874) (xy 338.302122 -20.819551) (xy 338.293878 -20.787963)
			(xy 338.277887 -20.759503) (xy 338.255194 -20.736034) (xy 338.227288 -20.719094) (xy 338.195996 -20.709793)
			(xy 338.163367 -20.70874) (xy 338.13154 -20.716003) (xy 338.102599 -20.731108) (xy 338.078441 -20.753065)
			(xy 338.060647 -20.780434) (xy 338.05495 -20.795742) (xy 338.045664 -20.822136) (xy 338.020455 -20.872088)
			(xy 337.98822 -20.917821) (xy 337.949648 -20.958353) (xy 337.905568 -20.992815) (xy 337.856927 -21.020467)
			(xy 337.804767 -21.040715) (xy 337.750209 -21.053126) (xy 337.694423 -21.057432) (xy 337.638606 -21.053541)
			(xy 337.583957 -21.041538) (xy 337.531648 -21.021678) (xy 337.482802 -20.99439) (xy 337.438466 -20.960257)
			(xy 337.399594 -20.920013) (xy 337.367018 -20.874522) (xy 337.341438 -20.82476) (xy 337.323404 -20.771794)
			(xy 337.313301 -20.716761) (xy 337.311347 -20.660844) (xy 337.317584 -20.60524) (xy 337.331877 -20.551145)
			(xy 337.353921 -20.499718) (xy 337.383242 -20.452064) (xy 337.41921 -20.409205) (xy 337.461055 -20.372061)
			(xy 337.507877 -20.341429) (xy 337.558672 -20.317967) (xy 337.61235 -20.302178) (xy 337.667759 -20.2944)
			(xy 337.72371 -20.294802) (xy 337.779001 -20.303374) (xy 337.832447 -20.319932) (xy 337.8829 -20.344121)
			(xy 337.90636 -20.35937) (xy 337.925641 -20.371807) (xy 337.967644 -20.390256) (xy 338.012277 -20.400867)
			(xy 338.05809 -20.403294) (xy 338.103595 -20.39746) (xy 338.147313 -20.383554) (xy 338.187825 -20.362026)
			(xy 338.223816 -20.333577) (xy 338.254117 -20.299131) (xy 338.277743 -20.259805) (xy 338.293927 -20.216878)
			(xy 338.302144 -20.171743) (xy 338.3026 -20.148804) (xy 338.3026 -18.8722) (xy 334.7212 -15.2908)
			(xy 331.095858 -15.2908) (xy 331.078818 -15.291352) (xy 331.045956 -15.300384) (xy 331.016657 -15.317792)
			(xy 331.004418 -15.329662) (xy 330.975722 -15.358793) (xy 330.913954 -15.412384) (xy 330.847649 -15.460249)
			(xy 330.777338 -15.502007) (xy 330.703581 -15.537323) (xy 330.626966 -15.565916) (xy 330.548105 -15.587558)
			(xy 330.467628 -15.602077) (xy 330.386176 -15.609356) (xy 330.345288 -15.609824) (xy 330.305637 -15.609389)
			(xy 330.226667 -15.602146) (xy 330.148693 -15.587697) (xy 330.072372 -15.566161) (xy 329.998346 -15.53772)
			(xy 329.927238 -15.502614) (xy 329.859647 -15.461138) (xy 329.796143 -15.413642) (xy 329.737259 -15.360525)
			(xy 329.710034 -15.331694) (xy 329.69778 -15.3192) (xy 329.667975 -15.300884) (xy 329.634308 -15.291378)
			(xy 329.616816 -15.2908) (xy 324.6882 -15.2908) (xy 321.437 -12.0396) (xy 321.437 -7.2644) (xy 315.9506 -1.778)
			(xy 204.9018 -1.778) (xy 203.847446 -2.832354) (xy 203.847446 -3.921861) (xy 269.544792 -3.921861)
			(xy 269.544792 -3.850539) (xy 269.552778 -3.779665) (xy 269.568648 -3.71013) (xy 269.592205 -3.64281)
			(xy 269.62315 -3.578551) (xy 269.661096 -3.51816) (xy 269.705565 -3.462398) (xy 269.755998 -3.411965)
			(xy 269.81176 -3.367496) (xy 269.872151 -3.32955) (xy 269.93641 -3.298605) (xy 270.00373 -3.275048)
			(xy 270.073265 -3.259178) (xy 270.144139 -3.251192) (xy 270.215461 -3.251192) (xy 270.286335 -3.259178)
			(xy 270.35587 -3.275048) (xy 270.42319 -3.298605) (xy 270.487449 -3.32955) (xy 270.54784 -3.367496)
			(xy 270.603602 -3.411965) (xy 270.654035 -3.462398) (xy 270.698504 -3.51816) (xy 270.73645 -3.578551)
			(xy 270.767395 -3.64281) (xy 270.790952 -3.71013) (xy 270.806822 -3.779665) (xy 270.814808 -3.850539)
			(xy 270.815308 -3.8862) (xy 270.814808 -3.921861) (xy 270.806822 -3.992735) (xy 270.790952 -4.06227)
			(xy 270.767395 -4.12959) (xy 270.73645 -4.193849) (xy 270.698504 -4.25424) (xy 270.654035 -4.310002)
			(xy 270.603602 -4.360435) (xy 270.54784 -4.404904) (xy 270.487449 -4.44285) (xy 270.42319 -4.473795)
			(xy 270.35587 -4.497352) (xy 270.286335 -4.513222) (xy 270.215461 -4.521208) (xy 270.144139 -4.521208)
			(xy 270.073265 -4.513222) (xy 270.00373 -4.497352) (xy 269.93641 -4.473795) (xy 269.872151 -4.44285)
			(xy 269.81176 -4.404904) (xy 269.755998 -4.360435) (xy 269.705565 -4.310002) (xy 269.661096 -4.25424)
			(xy 269.62315 -4.193849) (xy 269.592205 -4.12959) (xy 269.568648 -4.06227) (xy 269.552778 -3.992735)
			(xy 269.544792 -3.921861) (xy 203.847446 -3.921861) (xy 203.847446 -4.607661) (xy 242.950992 -4.607661)
			(xy 242.950992 -4.536339) (xy 242.958978 -4.465465) (xy 242.974848 -4.39593) (xy 242.998405 -4.32861)
			(xy 243.02935 -4.264351) (xy 243.067296 -4.20396) (xy 243.111765 -4.148198) (xy 243.162198 -4.097765)
			(xy 243.21796 -4.053296) (xy 243.278351 -4.01535) (xy 243.34261 -3.984405) (xy 243.40993 -3.960848)
			(xy 243.479465 -3.944978) (xy 243.550339 -3.936992) (xy 243.621661 -3.936992) (xy 243.692535 -3.944978)
			(xy 243.76207 -3.960848) (xy 243.82939 -3.984405) (xy 243.893649 -4.01535) (xy 243.95404 -4.053296)
			(xy 244.009802 -4.097765) (xy 244.060235 -4.148198) (xy 244.104704 -4.20396) (xy 244.14265 -4.264351)
			(xy 244.173595 -4.32861) (xy 244.197152 -4.39593) (xy 244.213022 -4.465465) (xy 244.221008 -4.536339)
			(xy 244.221508 -4.572) (xy 244.221008 -4.607661) (xy 244.213022 -4.678535) (xy 244.197152 -4.74807)
			(xy 244.173595 -4.81539) (xy 244.14265 -4.879649) (xy 244.104704 -4.94004) (xy 244.060235 -4.995802)
			(xy 244.009802 -5.046235) (xy 243.95404 -5.090704) (xy 243.893649 -5.12865) (xy 243.82939 -5.159595)
			(xy 243.76207 -5.183152) (xy 243.692535 -5.199022) (xy 243.621661 -5.207008) (xy 243.550339 -5.207008)
			(xy 243.479465 -5.199022) (xy 243.40993 -5.183152) (xy 243.34261 -5.159595) (xy 243.278351 -5.12865)
			(xy 243.21796 -5.090704) (xy 243.162198 -5.046235) (xy 243.111765 -4.995802) (xy 243.067296 -4.94004)
			(xy 243.02935 -4.879649) (xy 242.998405 -4.81539) (xy 242.974848 -4.74807) (xy 242.958978 -4.678535)
			(xy 242.950992 -4.607661) (xy 203.847446 -4.607661) (xy 203.847446 -11.186261) (xy 206.044792 -11.186261)
			(xy 206.044792 -11.114939) (xy 206.052778 -11.044065) (xy 206.068648 -10.97453) (xy 206.092205 -10.90721)
			(xy 206.12315 -10.842951) (xy 206.161096 -10.78256) (xy 206.205565 -10.726798) (xy 206.255998 -10.676365)
			(xy 206.31176 -10.631896) (xy 206.372151 -10.59395) (xy 206.43641 -10.563005) (xy 206.50373 -10.539448)
			(xy 206.573265 -10.523578) (xy 206.644139 -10.515592) (xy 206.715461 -10.515592) (xy 206.786335 -10.523578)
			(xy 206.85587 -10.539448) (xy 206.92319 -10.563005) (xy 206.987449 -10.59395) (xy 207.04784 -10.631896)
			(xy 207.103602 -10.676365) (xy 207.154035 -10.726798) (xy 207.192829 -10.775444) (xy 276.301877 -10.775444)
			(xy 276.302267 -10.608177) (xy 276.310628 -10.441119) (xy 276.32694 -10.274649) (xy 276.351167 -10.109145)
			(xy 276.383252 -9.944984) (xy 276.423124 -9.782538) (xy 276.470691 -9.622177) (xy 276.525847 -9.464265)
			(xy 276.588464 -9.30916) (xy 276.658401 -9.157216) (xy 276.7355 -9.008776) (xy 276.819584 -8.86418)
			(xy 276.910463 -8.723754) (xy 277.007931 -8.587819) (xy 277.111766 -8.456682) (xy 277.221731 -8.330643)
			(xy 277.337578 -8.209987) (xy 277.397972 -8.15213) (xy 277.421756 -8.128827) (xy 277.463472 -8.076928)
			(xy 277.497794 -8.019869) (xy 277.524093 -7.958697) (xy 277.541887 -7.894533) (xy 277.55085 -7.828553)
			(xy 277.551388 -7.79526) (xy 277.551388 -4.700016) (xy 277.551884 -4.633065) (xy 277.559817 -4.499398)
			(xy 277.575654 -4.366435) (xy 277.59934 -4.234645) (xy 277.630791 -4.104489) (xy 277.669899 -3.976425)
			(xy 277.716523 -3.850902) (xy 277.770503 -3.728362) (xy 277.831646 -3.609235) (xy 277.89974 -3.493939)
			(xy 277.974544 -3.38288) (xy 278.055796 -3.276447) (xy 278.14321 -3.175015) (xy 278.23648 -3.078939)
			(xy 278.335277 -2.988557) (xy 278.439256 -2.904187) (xy 278.548049 -2.826125) (xy 278.661276 -2.754645)
			(xy 278.778539 -2.689998) (xy 278.899426 -2.632411) (xy 279.023512 -2.582087) (xy 279.150361 -2.539202)
			(xy 279.279528 -2.503907) (xy 279.410559 -2.476326) (xy 279.542993 -2.456556) (xy 279.676367 -2.444666)
			(xy 279.81021 -2.440698) (xy 279.944053 -2.444666) (xy 280.077427 -2.456556) (xy 280.209861 -2.476326)
			(xy 280.340892 -2.503907) (xy 280.470059 -2.539202) (xy 280.596908 -2.582087) (xy 280.720994 -2.632411)
			(xy 280.841881 -2.689998) (xy 280.959144 -2.754645) (xy 281.072371 -2.826125) (xy 281.181164 -2.904187)
			(xy 281.285143 -2.988557) (xy 281.297367 -2.99974) (xy 311.607711 -2.99974) (xy 311.611746 -2.924036)
			(xy 311.623805 -2.849191) (xy 311.643751 -2.77605) (xy 311.671358 -2.705445) (xy 311.706314 -2.638174)
			(xy 311.748222 -2.574999) (xy 311.796608 -2.516637) (xy 311.850924 -2.463749) (xy 311.910553 -2.416934)
			(xy 311.974821 -2.376722) (xy 312.042998 -2.34357) (xy 312.114314 -2.317852) (xy 312.187959 -2.29986)
			(xy 312.263099 -2.289798) (xy 312.338883 -2.287779) (xy 312.414453 -2.293828) (xy 312.488951 -2.307875)
			(xy 312.561534 -2.329761) (xy 312.63138 -2.359238) (xy 312.697697 -2.395973) (xy 312.759733 -2.439548)
			(xy 312.816786 -2.48947) (xy 312.86821 -2.545174) (xy 312.913421 -2.606029) (xy 312.951908 -2.671344)
			(xy 312.983234 -2.74038) (xy 313.007044 -2.812355) (xy 313.023069 -2.886453) (xy 313.031128 -2.961834)
			(xy 313.031632 -2.99974) (xy 313.607707 -2.99974) (xy 313.611742 -2.924036) (xy 313.623801 -2.849191)
			(xy 313.643747 -2.77605) (xy 313.671354 -2.705445) (xy 313.70631 -2.638174) (xy 313.748218 -2.574999)
			(xy 313.796604 -2.516637) (xy 313.85092 -2.463749) (xy 313.910549 -2.416934) (xy 313.974817 -2.376722)
			(xy 314.042994 -2.34357) (xy 314.11431 -2.317852) (xy 314.187955 -2.29986) (xy 314.263095 -2.289798)
			(xy 314.338879 -2.287779) (xy 314.414449 -2.293828) (xy 314.488947 -2.307875) (xy 314.56153 -2.329761)
			(xy 314.631376 -2.359238) (xy 314.697693 -2.395973) (xy 314.759729 -2.439548) (xy 314.816782 -2.48947)
			(xy 314.868206 -2.545174) (xy 314.913417 -2.606029) (xy 314.951904 -2.671344) (xy 314.98323 -2.74038)
			(xy 315.00704 -2.812355) (xy 315.023065 -2.886453) (xy 315.031124 -2.961834) (xy 315.031628 -2.99974)
			(xy 315.031124 -3.037646) (xy 315.023065 -3.113027) (xy 315.00704 -3.187125) (xy 314.98323 -3.2591)
			(xy 314.951904 -3.328136) (xy 314.913417 -3.393451) (xy 314.868206 -3.454306) (xy 314.816782 -3.51001)
			(xy 314.759729 -3.559932) (xy 314.697693 -3.603507) (xy 314.631376 -3.640242) (xy 314.56153 -3.669719)
			(xy 314.488947 -3.691605) (xy 314.414449 -3.705652) (xy 314.338879 -3.711701) (xy 314.263095 -3.709682)
			(xy 314.187955 -3.69962) (xy 314.11431 -3.681628) (xy 314.042994 -3.65591) (xy 313.974817 -3.622758)
			(xy 313.910549 -3.582546) (xy 313.85092 -3.535731) (xy 313.796604 -3.482843) (xy 313.748218 -3.424481)
			(xy 313.70631 -3.361306) (xy 313.671354 -3.294035) (xy 313.643747 -3.22343) (xy 313.623801 -3.150289)
			(xy 313.611742 -3.075444) (xy 313.607707 -2.99974) (xy 313.031632 -2.99974) (xy 313.031128 -3.037646)
			(xy 313.023069 -3.113027) (xy 313.007044 -3.187125) (xy 312.983234 -3.2591) (xy 312.951908 -3.328136)
			(xy 312.913421 -3.393451) (xy 312.86821 -3.454306) (xy 312.816786 -3.51001) (xy 312.759733 -3.559932)
			(xy 312.697697 -3.603507) (xy 312.63138 -3.640242) (xy 312.561534 -3.669719) (xy 312.488951 -3.691605)
			(xy 312.414453 -3.705652) (xy 312.338883 -3.711701) (xy 312.263099 -3.709682) (xy 312.187959 -3.69962)
			(xy 312.114314 -3.681628) (xy 312.042998 -3.65591) (xy 311.974821 -3.622758) (xy 311.910553 -3.582546)
			(xy 311.850924 -3.535731) (xy 311.796608 -3.482843) (xy 311.748222 -3.424481) (xy 311.706314 -3.361306)
			(xy 311.671358 -3.294035) (xy 311.643751 -3.22343) (xy 311.623805 -3.150289) (xy 311.611746 -3.075444)
			(xy 311.607711 -2.99974) (xy 281.297367 -2.99974) (xy 281.38394 -3.078939) (xy 281.47721 -3.175015)
			(xy 281.564624 -3.276447) (xy 281.645876 -3.38288) (xy 281.72068 -3.493939) (xy 281.788774 -3.609235)
			(xy 281.849917 -3.728362) (xy 281.903897 -3.850902) (xy 281.950521 -3.976425) (xy 281.989629 -4.104489)
			(xy 282.02108 -4.234645) (xy 282.044766 -4.366435) (xy 282.060603 -4.499398) (xy 282.068536 -4.633065)
			(xy 282.069032 -4.700016) (xy 282.069032 -4.999736) (xy 311.607711 -4.999736) (xy 311.611746 -4.924032)
			(xy 311.623805 -4.849187) (xy 311.643751 -4.776046) (xy 311.671358 -4.705441) (xy 311.706314 -4.63817)
			(xy 311.748222 -4.574995) (xy 311.796608 -4.516633) (xy 311.850924 -4.463745) (xy 311.910553 -4.41693)
			(xy 311.974821 -4.376718) (xy 312.042998 -4.343566) (xy 312.114314 -4.317848) (xy 312.187959 -4.299856)
			(xy 312.263099 -4.289794) (xy 312.338883 -4.287775) (xy 312.414453 -4.293824) (xy 312.488951 -4.307871)
			(xy 312.561534 -4.329757) (xy 312.63138 -4.359234) (xy 312.697697 -4.395969) (xy 312.759733 -4.439544)
			(xy 312.816786 -4.489466) (xy 312.86821 -4.54517) (xy 312.913421 -4.606025) (xy 312.951908 -4.67134)
			(xy 312.983234 -4.740376) (xy 313.007044 -4.812351) (xy 313.023069 -4.886449) (xy 313.031128 -4.96183)
			(xy 313.031632 -4.999736) (xy 313.607707 -4.999736) (xy 313.611742 -4.924032) (xy 313.623801 -4.849187)
			(xy 313.643747 -4.776046) (xy 313.671354 -4.705441) (xy 313.70631 -4.63817) (xy 313.748218 -4.574995)
			(xy 313.796604 -4.516633) (xy 313.85092 -4.463745) (xy 313.910549 -4.41693) (xy 313.974817 -4.376718)
			(xy 314.042994 -4.343566) (xy 314.11431 -4.317848) (xy 314.187955 -4.299856) (xy 314.263095 -4.289794)
			(xy 314.338879 -4.287775) (xy 314.414449 -4.293824) (xy 314.488947 -4.307871) (xy 314.56153 -4.329757)
			(xy 314.631376 -4.359234) (xy 314.697693 -4.395969) (xy 314.759729 -4.439544) (xy 314.816782 -4.489466)
			(xy 314.868206 -4.54517) (xy 314.913417 -4.606025) (xy 314.951904 -4.67134) (xy 314.98323 -4.740376)
			(xy 315.00704 -4.812351) (xy 315.023065 -4.886449) (xy 315.031124 -4.96183) (xy 315.031628 -4.999736)
			(xy 315.031124 -5.037642) (xy 315.023065 -5.113023) (xy 315.00704 -5.187121) (xy 314.98323 -5.259096)
			(xy 314.951904 -5.328132) (xy 314.913417 -5.393447) (xy 314.868206 -5.454302) (xy 314.816782 -5.510006)
			(xy 314.759729 -5.559928) (xy 314.697693 -5.603503) (xy 314.631376 -5.640238) (xy 314.56153 -5.669715)
			(xy 314.488947 -5.691601) (xy 314.414449 -5.705648) (xy 314.338879 -5.711697) (xy 314.263095 -5.709678)
			(xy 314.187955 -5.699616) (xy 314.11431 -5.681624) (xy 314.042994 -5.655906) (xy 313.974817 -5.622754)
			(xy 313.910549 -5.582542) (xy 313.85092 -5.535727) (xy 313.796604 -5.482839) (xy 313.748218 -5.424477)
			(xy 313.70631 -5.361302) (xy 313.671354 -5.294031) (xy 313.643747 -5.223426) (xy 313.623801 -5.150285)
			(xy 313.611742 -5.07544) (xy 313.607707 -4.999736) (xy 313.031632 -4.999736) (xy 313.031128 -5.037642)
			(xy 313.023069 -5.113023) (xy 313.007044 -5.187121) (xy 312.983234 -5.259096) (xy 312.951908 -5.328132)
			(xy 312.913421 -5.393447) (xy 312.86821 -5.454302) (xy 312.816786 -5.510006) (xy 312.759733 -5.559928)
			(xy 312.697697 -5.603503) (xy 312.63138 -5.640238) (xy 312.561534 -5.669715) (xy 312.488951 -5.691601)
			(xy 312.414453 -5.705648) (xy 312.338883 -5.711697) (xy 312.263099 -5.709678) (xy 312.187959 -5.699616)
			(xy 312.114314 -5.681624) (xy 312.042998 -5.655906) (xy 311.974821 -5.622754) (xy 311.910553 -5.582542)
			(xy 311.850924 -5.535727) (xy 311.796608 -5.482839) (xy 311.748222 -5.424477) (xy 311.706314 -5.361302)
			(xy 311.671358 -5.294031) (xy 311.643751 -5.223426) (xy 311.623805 -5.150285) (xy 311.611746 -5.07544)
			(xy 311.607711 -4.999736) (xy 282.069032 -4.999736) (xy 282.069032 -6.999732) (xy 311.607711 -6.999732)
			(xy 311.611746 -6.924028) (xy 311.623805 -6.849183) (xy 311.643751 -6.776042) (xy 311.671358 -6.705437)
			(xy 311.706314 -6.638166) (xy 311.748222 -6.574991) (xy 311.796608 -6.516629) (xy 311.850924 -6.463741)
			(xy 311.910553 -6.416926) (xy 311.974821 -6.376714) (xy 312.042998 -6.343562) (xy 312.114314 -6.317844)
			(xy 312.187959 -6.299852) (xy 312.263099 -6.28979) (xy 312.338883 -6.287771) (xy 312.414453 -6.29382)
			(xy 312.488951 -6.307867) (xy 312.561534 -6.329753) (xy 312.63138 -6.35923) (xy 312.697697 -6.395965)
			(xy 312.759733 -6.43954) (xy 312.816786 -6.489462) (xy 312.86821 -6.545166) (xy 312.913421 -6.606021)
			(xy 312.951908 -6.671336) (xy 312.983234 -6.740372) (xy 313.007044 -6.812347) (xy 313.023069 -6.886445)
			(xy 313.031128 -6.961826) (xy 313.031632 -6.999732) (xy 313.607707 -6.999732) (xy 313.611742 -6.924028)
			(xy 313.623801 -6.849183) (xy 313.643747 -6.776042) (xy 313.671354 -6.705437) (xy 313.70631 -6.638166)
			(xy 313.748218 -6.574991) (xy 313.796604 -6.516629) (xy 313.85092 -6.463741) (xy 313.910549 -6.416926)
			(xy 313.974817 -6.376714) (xy 314.042994 -6.343562) (xy 314.11431 -6.317844) (xy 314.187955 -6.299852)
			(xy 314.263095 -6.28979) (xy 314.338879 -6.287771) (xy 314.414449 -6.29382) (xy 314.488947 -6.307867)
			(xy 314.56153 -6.329753) (xy 314.631376 -6.35923) (xy 314.697693 -6.395965) (xy 314.759729 -6.43954)
			(xy 314.816782 -6.489462) (xy 314.868206 -6.545166) (xy 314.913417 -6.606021) (xy 314.951904 -6.671336)
			(xy 314.98323 -6.740372) (xy 315.00704 -6.812347) (xy 315.023065 -6.886445) (xy 315.031124 -6.961826)
			(xy 315.031628 -6.999732) (xy 315.031124 -7.037638) (xy 315.023065 -7.113019) (xy 315.00704 -7.187117)
			(xy 314.98323 -7.259092) (xy 314.951904 -7.328128) (xy 314.913417 -7.393443) (xy 314.868206 -7.454298)
			(xy 314.816782 -7.510002) (xy 314.759729 -7.559924) (xy 314.697693 -7.603499) (xy 314.631376 -7.640234)
			(xy 314.56153 -7.669711) (xy 314.488947 -7.691597) (xy 314.414449 -7.705644) (xy 314.338879 -7.711693)
			(xy 314.263095 -7.709674) (xy 314.187955 -7.699612) (xy 314.11431 -7.68162) (xy 314.042994 -7.655902)
			(xy 313.974817 -7.62275) (xy 313.910549 -7.582538) (xy 313.85092 -7.535723) (xy 313.796604 -7.482835)
			(xy 313.748218 -7.424473) (xy 313.70631 -7.361298) (xy 313.671354 -7.294027) (xy 313.643747 -7.223422)
			(xy 313.623801 -7.150281) (xy 313.611742 -7.075436) (xy 313.607707 -6.999732) (xy 313.031632 -6.999732)
			(xy 313.031128 -7.037638) (xy 313.023069 -7.113019) (xy 313.007044 -7.187117) (xy 312.983234 -7.259092)
			(xy 312.951908 -7.328128) (xy 312.913421 -7.393443) (xy 312.86821 -7.454298) (xy 312.816786 -7.510002)
			(xy 312.759733 -7.559924) (xy 312.697697 -7.603499) (xy 312.63138 -7.640234) (xy 312.561534 -7.669711)
			(xy 312.488951 -7.691597) (xy 312.414453 -7.705644) (xy 312.338883 -7.711693) (xy 312.263099 -7.709674)
			(xy 312.187959 -7.699612) (xy 312.114314 -7.68162) (xy 312.042998 -7.655902) (xy 311.974821 -7.62275)
			(xy 311.910553 -7.582538) (xy 311.850924 -7.535723) (xy 311.796608 -7.482835) (xy 311.748222 -7.424473)
			(xy 311.706314 -7.361298) (xy 311.671358 -7.294027) (xy 311.643751 -7.223422) (xy 311.623805 -7.150281)
			(xy 311.611746 -7.075436) (xy 311.607711 -6.999732) (xy 282.069032 -6.999732) (xy 282.069032 -7.79526)
			(xy 282.069585 -7.828553) (xy 282.078547 -7.894532) (xy 282.096338 -7.958696) (xy 282.122633 -8.019869)
			(xy 282.15695 -8.076929) (xy 282.19866 -8.128831) (xy 282.222448 -8.15213) (xy 282.282842 -8.209987)
			(xy 282.398689 -8.330643) (xy 282.508654 -8.456682) (xy 282.612489 -8.587819) (xy 282.709957 -8.723754)
			(xy 282.800836 -8.86418) (xy 282.88492 -9.008776) (xy 282.962019 -9.157216) (xy 283.031956 -9.30916)
			(xy 283.094573 -9.464265) (xy 283.125883 -9.553905) (xy 308.834016 -9.553905) (xy 308.834016 -9.445295)
			(xy 308.841944 -9.336976) (xy 308.857758 -9.229523) (xy 308.881373 -9.123512) (xy 308.912663 -9.019508)
			(xy 308.951462 -8.918065) (xy 308.997562 -8.819725) (xy 309.050717 -8.725012) (xy 309.110644 -8.634432)
			(xy 309.177023 -8.548468) (xy 309.249501 -8.467578) (xy 309.327689 -8.392195) (xy 309.411171 -8.322721)
			(xy 309.499502 -8.259525) (xy 309.592211 -8.202946) (xy 309.688802 -8.153285) (xy 309.78876 -8.110808)
			(xy 309.891552 -8.07574) (xy 309.99663 -8.048269) (xy 310.103433 -8.028541) (xy 310.211391 -8.016663)
			(xy 310.319928 -8.012696) (xy 310.428465 -8.016663) (xy 310.536423 -8.028541) (xy 310.643226 -8.048269)
			(xy 310.748304 -8.07574) (xy 310.851096 -8.110808) (xy 310.951054 -8.153285) (xy 311.047645 -8.202946)
			(xy 311.140354 -8.259525) (xy 311.228685 -8.322721) (xy 311.312167 -8.392195) (xy 311.390355 -8.467578)
			(xy 311.462833 -8.548468) (xy 311.529212 -8.634432) (xy 311.589139 -8.725012) (xy 311.642294 -8.819725)
			(xy 311.688394 -8.918065) (xy 311.727193 -9.019508) (xy 311.758483 -9.123512) (xy 311.782098 -9.229523)
			(xy 311.797912 -9.336976) (xy 311.80584 -9.445295) (xy 311.806336 -9.4996) (xy 311.80584 -9.553905)
			(xy 311.797912 -9.662224) (xy 311.782098 -9.769677) (xy 311.758483 -9.875688) (xy 311.727193 -9.979692)
			(xy 311.688394 -10.081135) (xy 311.642294 -10.179475) (xy 311.589139 -10.274188) (xy 311.529212 -10.364768)
			(xy 311.462833 -10.450732) (xy 311.390355 -10.531622) (xy 311.312167 -10.607005) (xy 311.228685 -10.676479)
			(xy 311.140354 -10.739675) (xy 311.047645 -10.796254) (xy 310.951054 -10.845915) (xy 310.851096 -10.888392)
			(xy 310.748304 -10.92346) (xy 310.643226 -10.950931) (xy 310.536423 -10.970659) (xy 310.428465 -10.982537)
			(xy 310.319928 -10.986504) (xy 310.211391 -10.982537) (xy 310.103433 -10.970659) (xy 309.99663 -10.950931)
			(xy 309.891552 -10.92346) (xy 309.78876 -10.888392) (xy 309.688802 -10.845915) (xy 309.592211 -10.796254)
			(xy 309.499502 -10.739675) (xy 309.411171 -10.676479) (xy 309.327689 -10.607005) (xy 309.249501 -10.531622)
			(xy 309.177023 -10.450732) (xy 309.110644 -10.364768) (xy 309.050717 -10.274188) (xy 308.997562 -10.179475)
			(xy 308.951462 -10.081135) (xy 308.912663 -9.979692) (xy 308.881373 -9.875688) (xy 308.857758 -9.769677)
			(xy 308.841944 -9.662224) (xy 308.834016 -9.553905) (xy 283.125883 -9.553905) (xy 283.149729 -9.622177)
			(xy 283.197296 -9.782538) (xy 283.237168 -9.944984) (xy 283.269253 -10.109145) (xy 283.29348 -10.274649)
			(xy 283.309792 -10.441119) (xy 283.318153 -10.608177) (xy 283.318543 -10.775444) (xy 283.310963 -10.94254)
			(xy 283.305629 -10.999724) (xy 311.607711 -10.999724) (xy 311.611746 -10.92402) (xy 311.623805 -10.849175)
			(xy 311.643751 -10.776034) (xy 311.671358 -10.705429) (xy 311.706314 -10.638158) (xy 311.748222 -10.574983)
			(xy 311.796608 -10.516621) (xy 311.850924 -10.463733) (xy 311.910553 -10.416918) (xy 311.974821 -10.376706)
			(xy 312.042998 -10.343554) (xy 312.114314 -10.317836) (xy 312.187959 -10.299844) (xy 312.263099 -10.289782)
			(xy 312.338883 -10.287763) (xy 312.414453 -10.293812) (xy 312.488951 -10.307859) (xy 312.561534 -10.329745)
			(xy 312.63138 -10.359222) (xy 312.697697 -10.395957) (xy 312.759733 -10.439532) (xy 312.816786 -10.489454)
			(xy 312.86821 -10.545158) (xy 312.913421 -10.606013) (xy 312.951908 -10.671328) (xy 312.983234 -10.740364)
			(xy 313.007044 -10.812339) (xy 313.023069 -10.886437) (xy 313.031128 -10.961818) (xy 313.031632 -10.999724)
			(xy 313.607707 -10.999724) (xy 313.611742 -10.92402) (xy 313.623801 -10.849175) (xy 313.643747 -10.776034)
			(xy 313.671354 -10.705429) (xy 313.70631 -10.638158) (xy 313.748218 -10.574983) (xy 313.796604 -10.516621)
			(xy 313.85092 -10.463733) (xy 313.910549 -10.416918) (xy 313.974817 -10.376706) (xy 314.042994 -10.343554)
			(xy 314.11431 -10.317836) (xy 314.187955 -10.299844) (xy 314.263095 -10.289782) (xy 314.338879 -10.287763)
			(xy 314.414449 -10.293812) (xy 314.488947 -10.307859) (xy 314.56153 -10.329745) (xy 314.631376 -10.359222)
			(xy 314.697693 -10.395957) (xy 314.759729 -10.439532) (xy 314.816782 -10.489454) (xy 314.868206 -10.545158)
			(xy 314.913417 -10.606013) (xy 314.951904 -10.671328) (xy 314.98323 -10.740364) (xy 315.00704 -10.812339)
			(xy 315.023065 -10.886437) (xy 315.031124 -10.961818) (xy 315.031628 -10.999724) (xy 315.031124 -11.03763)
			(xy 315.023065 -11.113011) (xy 315.00704 -11.187109) (xy 314.98323 -11.259084) (xy 314.951904 -11.32812)
			(xy 314.913417 -11.393435) (xy 314.868206 -11.45429) (xy 314.816782 -11.509994) (xy 314.759729 -11.559916)
			(xy 314.697693 -11.603491) (xy 314.631376 -11.640226) (xy 314.56153 -11.669703) (xy 314.488947 -11.691589)
			(xy 314.414449 -11.705636) (xy 314.338879 -11.711685) (xy 314.263095 -11.709666) (xy 314.187955 -11.699604)
			(xy 314.11431 -11.681612) (xy 314.042994 -11.655894) (xy 313.974817 -11.622742) (xy 313.910549 -11.58253)
			(xy 313.85092 -11.535715) (xy 313.796604 -11.482827) (xy 313.748218 -11.424465) (xy 313.70631 -11.36129)
			(xy 313.671354 -11.294019) (xy 313.643747 -11.223414) (xy 313.623801 -11.150273) (xy 313.611742 -11.075428)
			(xy 313.607707 -10.999724) (xy 313.031632 -10.999724) (xy 313.031128 -11.03763) (xy 313.023069 -11.113011)
			(xy 313.007044 -11.187109) (xy 312.983234 -11.259084) (xy 312.951908 -11.32812) (xy 312.913421 -11.393435)
			(xy 312.86821 -11.45429) (xy 312.816786 -11.509994) (xy 312.759733 -11.559916) (xy 312.697697 -11.603491)
			(xy 312.63138 -11.640226) (xy 312.561534 -11.669703) (xy 312.488951 -11.691589) (xy 312.414453 -11.705636)
			(xy 312.338883 -11.711685) (xy 312.263099 -11.709666) (xy 312.187959 -11.699604) (xy 312.114314 -11.681612)
			(xy 312.042998 -11.655894) (xy 311.974821 -11.622742) (xy 311.910553 -11.58253) (xy 311.850924 -11.535715)
			(xy 311.796608 -11.482827) (xy 311.748222 -11.424465) (xy 311.706314 -11.36129) (xy 311.671358 -11.294019)
			(xy 311.643751 -11.223414) (xy 311.623805 -11.150273) (xy 311.611746 -11.075428) (xy 311.607711 -10.999724)
			(xy 283.305629 -10.999724) (xy 283.295428 -11.109084) (xy 283.271975 -11.274699) (xy 283.240657 -11.439009)
			(xy 283.201544 -11.601639) (xy 283.154727 -11.76222) (xy 283.10031 -11.920389) (xy 283.038417 -12.075784)
			(xy 282.969191 -12.228054) (xy 282.892786 -12.376851) (xy 282.809378 -12.521839) (xy 282.719156 -12.662688)
			(xy 282.622324 -12.799077) (xy 282.519103 -12.930697) (xy 282.459449 -12.99972) (xy 311.607711 -12.99972)
			(xy 311.611746 -12.924016) (xy 311.623805 -12.849171) (xy 311.643751 -12.77603) (xy 311.671358 -12.705425)
			(xy 311.706314 -12.638154) (xy 311.748222 -12.574979) (xy 311.796608 -12.516617) (xy 311.850924 -12.463729)
			(xy 311.910553 -12.416914) (xy 311.974821 -12.376702) (xy 312.042998 -12.34355) (xy 312.114314 -12.317832)
			(xy 312.187959 -12.29984) (xy 312.263099 -12.289778) (xy 312.338883 -12.287759) (xy 312.414453 -12.293808)
			(xy 312.488951 -12.307855) (xy 312.561534 -12.329741) (xy 312.63138 -12.359218) (xy 312.697697 -12.395953)
			(xy 312.759733 -12.439528) (xy 312.816786 -12.48945) (xy 312.86821 -12.545154) (xy 312.913421 -12.606009)
			(xy 312.951908 -12.671324) (xy 312.983234 -12.74036) (xy 313.007044 -12.812335) (xy 313.023069 -12.886433)
			(xy 313.031128 -12.961814) (xy 313.031632 -12.99972) (xy 313.607707 -12.99972) (xy 313.611742 -12.924016)
			(xy 313.623801 -12.849171) (xy 313.643747 -12.77603) (xy 313.671354 -12.705425) (xy 313.70631 -12.638154)
			(xy 313.748218 -12.574979) (xy 313.796604 -12.516617) (xy 313.85092 -12.463729) (xy 313.910549 -12.416914)
			(xy 313.974817 -12.376702) (xy 314.042994 -12.34355) (xy 314.11431 -12.317832) (xy 314.187955 -12.29984)
			(xy 314.263095 -12.289778) (xy 314.338879 -12.287759) (xy 314.414449 -12.293808) (xy 314.488947 -12.307855)
			(xy 314.56153 -12.329741) (xy 314.631376 -12.359218) (xy 314.697693 -12.395953) (xy 314.759729 -12.439528)
			(xy 314.816782 -12.48945) (xy 314.868206 -12.545154) (xy 314.913417 -12.606009) (xy 314.951904 -12.671324)
			(xy 314.98323 -12.74036) (xy 315.00704 -12.812335) (xy 315.023065 -12.886433) (xy 315.031124 -12.961814)
			(xy 315.031628 -12.99972) (xy 315.031124 -13.037626) (xy 315.023065 -13.113007) (xy 315.00704 -13.187105)
			(xy 314.98323 -13.25908) (xy 314.951904 -13.328116) (xy 314.913417 -13.393431) (xy 314.868206 -13.454286)
			(xy 314.816782 -13.50999) (xy 314.759729 -13.559912) (xy 314.697693 -13.603487) (xy 314.631376 -13.640222)
			(xy 314.56153 -13.669699) (xy 314.488947 -13.691585) (xy 314.414449 -13.705632) (xy 314.338879 -13.711681)
			(xy 314.263095 -13.709662) (xy 314.187955 -13.6996) (xy 314.11431 -13.681608) (xy 314.042994 -13.65589)
			(xy 313.974817 -13.622738) (xy 313.910549 -13.582526) (xy 313.85092 -13.535711) (xy 313.796604 -13.482823)
			(xy 313.748218 -13.424461) (xy 313.70631 -13.361286) (xy 313.671354 -13.294015) (xy 313.643747 -13.22341)
			(xy 313.623801 -13.150269) (xy 313.611742 -13.075424) (xy 313.607707 -12.99972) (xy 313.031632 -12.99972)
			(xy 313.031128 -13.037626) (xy 313.023069 -13.113007) (xy 313.007044 -13.187105) (xy 312.983234 -13.25908)
			(xy 312.951908 -13.328116) (xy 312.913421 -13.393431) (xy 312.86821 -13.454286) (xy 312.816786 -13.50999)
			(xy 312.759733 -13.559912) (xy 312.697697 -13.603487) (xy 312.63138 -13.640222) (xy 312.561534 -13.669699)
			(xy 312.488951 -13.691585) (xy 312.414453 -13.705632) (xy 312.338883 -13.711681) (xy 312.263099 -13.709662)
			(xy 312.187959 -13.6996) (xy 312.114314 -13.681608) (xy 312.042998 -13.65589) (xy 311.974821 -13.622738)
			(xy 311.910553 -13.582526) (xy 311.850924 -13.535711) (xy 311.796608 -13.482823) (xy 311.748222 -13.424461)
			(xy 311.706314 -13.361286) (xy 311.671358 -13.294015) (xy 311.643751 -13.22341) (xy 311.623805 -13.150269)
			(xy 311.611746 -13.075424) (xy 311.607711 -12.99972) (xy 282.459449 -12.99972) (xy 282.409728 -13.057249)
			(xy 282.294446 -13.178445) (xy 282.173519 -13.294009) (xy 282.047223 -13.40368) (xy 281.915845 -13.507208)
			(xy 281.779682 -13.604358) (xy 281.639045 -13.694909) (xy 281.494252 -13.778656) (xy 281.345633 -13.855407)
			(xy 281.193526 -13.92499) (xy 281.038275 -13.987245) (xy 280.880235 -14.042031) (xy 280.719763 -14.089223)
			(xy 280.557224 -14.128716) (xy 280.392989 -14.160418) (xy 280.227429 -14.184258) (xy 280.060921 -14.200181)
			(xy 279.893844 -14.208152) (xy 279.726576 -14.208152) (xy 279.559499 -14.200181) (xy 279.392991 -14.184258)
			(xy 279.227431 -14.160418) (xy 279.063196 -14.128716) (xy 278.900657 -14.089223) (xy 278.740185 -14.042031)
			(xy 278.582145 -13.987245) (xy 278.426894 -13.92499) (xy 278.274787 -13.855407) (xy 278.126168 -13.778656)
			(xy 277.981375 -13.694909) (xy 277.840738 -13.604358) (xy 277.704575 -13.507208) (xy 277.573197 -13.40368)
			(xy 277.446901 -13.294009) (xy 277.325974 -13.178445) (xy 277.210692 -13.057249) (xy 277.101317 -12.930697)
			(xy 276.998096 -12.799077) (xy 276.901264 -12.662688) (xy 276.811042 -12.521839) (xy 276.727634 -12.376851)
			(xy 276.651229 -12.228054) (xy 276.582003 -12.075784) (xy 276.52011 -11.920389) (xy 276.465693 -11.76222)
			(xy 276.418876 -11.601639) (xy 276.379763 -11.439009) (xy 276.348445 -11.274699) (xy 276.324992 -11.109084)
			(xy 276.309457 -10.94254) (xy 276.301877 -10.775444) (xy 207.192829 -10.775444) (xy 207.198504 -10.78256)
			(xy 207.23645 -10.842951) (xy 207.267395 -10.90721) (xy 207.290952 -10.97453) (xy 207.306822 -11.044065)
			(xy 207.314808 -11.114939) (xy 207.315308 -11.1506) (xy 207.314808 -11.186261) (xy 207.306822 -11.257135)
			(xy 207.290952 -11.32667) (xy 207.267395 -11.39399) (xy 207.23645 -11.458249) (xy 207.198504 -11.51864)
			(xy 207.154035 -11.574402) (xy 207.135776 -11.592661) (xy 264.286992 -11.592661) (xy 264.286992 -11.521339)
			(xy 264.294978 -11.450465) (xy 264.310848 -11.38093) (xy 264.334405 -11.31361) (xy 264.36535 -11.249351)
			(xy 264.403296 -11.18896) (xy 264.447765 -11.133198) (xy 264.498198 -11.082765) (xy 264.55396 -11.038296)
			(xy 264.614351 -11.00035) (xy 264.67861 -10.969405) (xy 264.74593 -10.945848) (xy 264.815465 -10.929978)
			(xy 264.886339 -10.921992) (xy 264.957661 -10.921992) (xy 265.028535 -10.929978) (xy 265.09807 -10.945848)
			(xy 265.16539 -10.969405) (xy 265.229649 -11.00035) (xy 265.29004 -11.038296) (xy 265.345802 -11.082765)
			(xy 265.396235 -11.133198) (xy 265.440704 -11.18896) (xy 265.47865 -11.249351) (xy 265.509595 -11.31361)
			(xy 265.533152 -11.38093) (xy 265.549022 -11.450465) (xy 265.557008 -11.521339) (xy 265.557508 -11.557)
			(xy 265.557008 -11.592661) (xy 271.906992 -11.592661) (xy 271.906992 -11.521339) (xy 271.914978 -11.450465)
			(xy 271.930848 -11.38093) (xy 271.954405 -11.31361) (xy 271.98535 -11.249351) (xy 272.023296 -11.18896)
			(xy 272.067765 -11.133198) (xy 272.118198 -11.082765) (xy 272.17396 -11.038296) (xy 272.234351 -11.00035)
			(xy 272.29861 -10.969405) (xy 272.36593 -10.945848) (xy 272.435465 -10.929978) (xy 272.506339 -10.921992)
			(xy 272.577661 -10.921992) (xy 272.648535 -10.929978) (xy 272.71807 -10.945848) (xy 272.78539 -10.969405)
			(xy 272.849649 -11.00035) (xy 272.91004 -11.038296) (xy 272.965802 -11.082765) (xy 273.016235 -11.133198)
			(xy 273.060704 -11.18896) (xy 273.09865 -11.249351) (xy 273.129595 -11.31361) (xy 273.153152 -11.38093)
			(xy 273.169022 -11.450465) (xy 273.177008 -11.521339) (xy 273.177508 -11.557) (xy 273.177008 -11.592661)
			(xy 273.169022 -11.663535) (xy 273.153152 -11.73307) (xy 273.129595 -11.80039) (xy 273.09865 -11.864649)
			(xy 273.060704 -11.92504) (xy 273.016235 -11.980802) (xy 272.965802 -12.031235) (xy 272.91004 -12.075704)
			(xy 272.849649 -12.11365) (xy 272.78539 -12.144595) (xy 272.71807 -12.168152) (xy 272.648535 -12.184022)
			(xy 272.577661 -12.192008) (xy 272.506339 -12.192008) (xy 272.435465 -12.184022) (xy 272.36593 -12.168152)
			(xy 272.29861 -12.144595) (xy 272.234351 -12.11365) (xy 272.17396 -12.075704) (xy 272.118198 -12.031235)
			(xy 272.067765 -11.980802) (xy 272.023296 -11.92504) (xy 271.98535 -11.864649) (xy 271.954405 -11.80039)
			(xy 271.930848 -11.73307) (xy 271.914978 -11.663535) (xy 271.906992 -11.592661) (xy 265.557008 -11.592661)
			(xy 265.549022 -11.663535) (xy 265.533152 -11.73307) (xy 265.509595 -11.80039) (xy 265.47865 -11.864649)
			(xy 265.440704 -11.92504) (xy 265.396235 -11.980802) (xy 265.345802 -12.031235) (xy 265.29004 -12.075704)
			(xy 265.229649 -12.11365) (xy 265.16539 -12.144595) (xy 265.09807 -12.168152) (xy 265.028535 -12.184022)
			(xy 264.957661 -12.192008) (xy 264.886339 -12.192008) (xy 264.815465 -12.184022) (xy 264.74593 -12.168152)
			(xy 264.67861 -12.144595) (xy 264.614351 -12.11365) (xy 264.55396 -12.075704) (xy 264.498198 -12.031235)
			(xy 264.447765 -11.980802) (xy 264.403296 -11.92504) (xy 264.36535 -11.864649) (xy 264.334405 -11.80039)
			(xy 264.310848 -11.73307) (xy 264.294978 -11.663535) (xy 264.286992 -11.592661) (xy 207.135776 -11.592661)
			(xy 207.103602 -11.624835) (xy 207.04784 -11.669304) (xy 206.987449 -11.70725) (xy 206.92319 -11.738195)
			(xy 206.85587 -11.761752) (xy 206.786335 -11.777622) (xy 206.715461 -11.785608) (xy 206.644139 -11.785608)
			(xy 206.573265 -11.777622) (xy 206.50373 -11.761752) (xy 206.43641 -11.738195) (xy 206.372151 -11.70725)
			(xy 206.31176 -11.669304) (xy 206.255998 -11.624835) (xy 206.205565 -11.574402) (xy 206.161096 -11.51864)
			(xy 206.12315 -11.458249) (xy 206.092205 -11.39399) (xy 206.068648 -11.32667) (xy 206.052778 -11.257135)
			(xy 206.044792 -11.186261) (xy 203.847446 -11.186261) (xy 203.847446 -12.560554) (xy 201.408284 -14.999716)
			(xy 311.607711 -14.999716) (xy 311.611746 -14.924012) (xy 311.623805 -14.849167) (xy 311.643751 -14.776026)
			(xy 311.671358 -14.705421) (xy 311.706314 -14.63815) (xy 311.748222 -14.574975) (xy 311.796608 -14.516613)
			(xy 311.850924 -14.463725) (xy 311.910553 -14.41691) (xy 311.974821 -14.376698) (xy 312.042998 -14.343546)
			(xy 312.114314 -14.317828) (xy 312.187959 -14.299836) (xy 312.263099 -14.289774) (xy 312.338883 -14.287755)
			(xy 312.414453 -14.293804) (xy 312.488951 -14.307851) (xy 312.561534 -14.329737) (xy 312.63138 -14.359214)
			(xy 312.697697 -14.395949) (xy 312.759733 -14.439524) (xy 312.816786 -14.489446) (xy 312.86821 -14.54515)
			(xy 312.913421 -14.606005) (xy 312.951908 -14.67132) (xy 312.983234 -14.740356) (xy 313.007044 -14.812331)
			(xy 313.023069 -14.886429) (xy 313.031128 -14.96181) (xy 313.031632 -14.999716) (xy 313.607707 -14.999716)
			(xy 313.611742 -14.924012) (xy 313.623801 -14.849167) (xy 313.643747 -14.776026) (xy 313.671354 -14.705421)
			(xy 313.70631 -14.63815) (xy 313.748218 -14.574975) (xy 313.796604 -14.516613) (xy 313.85092 -14.463725)
			(xy 313.910549 -14.41691) (xy 313.974817 -14.376698) (xy 314.042994 -14.343546) (xy 314.11431 -14.317828)
			(xy 314.187955 -14.299836) (xy 314.263095 -14.289774) (xy 314.338879 -14.287755) (xy 314.414449 -14.293804)
			(xy 314.488947 -14.307851) (xy 314.56153 -14.329737) (xy 314.631376 -14.359214) (xy 314.697693 -14.395949)
			(xy 314.759352 -14.439259) (xy 319.550021 -14.439259) (xy 319.550021 -14.340973) (xy 319.55793 -14.243006)
			(xy 319.573696 -14.145993) (xy 319.597217 -14.050564) (xy 319.628341 -13.957336) (xy 319.666866 -13.866915)
			(xy 319.712541 -13.779888) (xy 319.765072 -13.696817) (xy 319.824116 -13.618244) (xy 319.889291 -13.544676)
			(xy 319.960175 -13.476591) (xy 320.036308 -13.41443) (xy 320.117195 -13.358598) (xy 320.202313 -13.309455)
			(xy 320.29111 -13.267321) (xy 320.383008 -13.232468) (xy 320.477414 -13.205123) (xy 320.573713 -13.185464)
			(xy 320.671282 -13.173617) (xy 320.769488 -13.169659) (xy 320.867694 -13.173617) (xy 320.965263 -13.185464)
			(xy 321.061562 -13.205123) (xy 321.155968 -13.232468) (xy 321.247866 -13.267321) (xy 321.336663 -13.309455)
			(xy 321.421781 -13.358598) (xy 321.502668 -13.41443) (xy 321.578801 -13.476591) (xy 321.649685 -13.544676)
			(xy 321.71486 -13.618244) (xy 321.773904 -13.696817) (xy 321.826435 -13.779888) (xy 321.87211 -13.866915)
			(xy 321.910635 -13.957336) (xy 321.941759 -14.050564) (xy 321.96528 -14.145993) (xy 321.981046 -14.243006)
			(xy 321.988955 -14.340973) (xy 321.98945 -14.390116) (xy 321.988955 -14.439259) (xy 321.981046 -14.537226)
			(xy 321.96528 -14.634239) (xy 321.941759 -14.729668) (xy 321.910635 -14.822896) (xy 321.87211 -14.913317)
			(xy 321.826435 -15.000345) (xy 321.773904 -15.083415) (xy 321.71486 -15.161988) (xy 321.649685 -15.235556)
			(xy 321.578801 -15.303641) (xy 321.502668 -15.365802) (xy 321.421781 -15.421634) (xy 321.336663 -15.470777)
			(xy 321.247866 -15.512911) (xy 321.155968 -15.547764) (xy 321.061562 -15.575109) (xy 320.965263 -15.594768)
			(xy 320.867694 -15.606615) (xy 320.769488 -15.610573) (xy 320.671282 -15.606615) (xy 320.573713 -15.594768)
			(xy 320.477414 -15.575109) (xy 320.383008 -15.547764) (xy 320.29111 -15.512911) (xy 320.202313 -15.470777)
			(xy 320.117195 -15.421634) (xy 320.036308 -15.365802) (xy 319.960175 -15.303641) (xy 319.889291 -15.235556)
			(xy 319.824116 -15.161988) (xy 319.765072 -15.083415) (xy 319.712541 -15.000345) (xy 319.666866 -14.913317)
			(xy 319.628341 -14.822896) (xy 319.597217 -14.729668) (xy 319.573696 -14.634239) (xy 319.55793 -14.537226)
			(xy 319.550021 -14.439259) (xy 314.759352 -14.439259) (xy 314.759729 -14.439524) (xy 314.816782 -14.489446)
			(xy 314.868206 -14.54515) (xy 314.913417 -14.606005) (xy 314.951904 -14.67132) (xy 314.98323 -14.740356)
			(xy 315.00704 -14.812331) (xy 315.023065 -14.886429) (xy 315.031124 -14.96181) (xy 315.031628 -14.999716)
			(xy 315.031124 -15.037622) (xy 315.023065 -15.113003) (xy 315.00704 -15.187101) (xy 314.98323 -15.259076)
			(xy 314.951904 -15.328112) (xy 314.913417 -15.393427) (xy 314.868206 -15.454282) (xy 314.816782 -15.509986)
			(xy 314.759729 -15.559908) (xy 314.697693 -15.603483) (xy 314.631376 -15.640218) (xy 314.56153 -15.669695)
			(xy 314.488947 -15.691581) (xy 314.414449 -15.705628) (xy 314.338879 -15.711677) (xy 314.263095 -15.709658)
			(xy 314.187955 -15.699596) (xy 314.11431 -15.681604) (xy 314.042994 -15.655886) (xy 313.974817 -15.622734)
			(xy 313.910549 -15.582522) (xy 313.85092 -15.535707) (xy 313.796604 -15.482819) (xy 313.748218 -15.424457)
			(xy 313.70631 -15.361282) (xy 313.671354 -15.294011) (xy 313.643747 -15.223406) (xy 313.623801 -15.150265)
			(xy 313.611742 -15.07542) (xy 313.607707 -14.999716) (xy 313.031632 -14.999716) (xy 313.031128 -15.037622)
			(xy 313.023069 -15.113003) (xy 313.007044 -15.187101) (xy 312.983234 -15.259076) (xy 312.951908 -15.328112)
			(xy 312.913421 -15.393427) (xy 312.86821 -15.454282) (xy 312.816786 -15.509986) (xy 312.759733 -15.559908)
			(xy 312.697697 -15.603483) (xy 312.63138 -15.640218) (xy 312.561534 -15.669695) (xy 312.488951 -15.691581)
			(xy 312.414453 -15.705628) (xy 312.338883 -15.711677) (xy 312.263099 -15.709658) (xy 312.187959 -15.699596)
			(xy 312.114314 -15.681604) (xy 312.042998 -15.655886) (xy 311.974821 -15.622734) (xy 311.910553 -15.582522)
			(xy 311.850924 -15.535707) (xy 311.796608 -15.482819) (xy 311.748222 -15.424457) (xy 311.706314 -15.361282)
			(xy 311.671358 -15.294011) (xy 311.643751 -15.223406) (xy 311.623805 -15.150265) (xy 311.611746 -15.07542)
			(xy 311.607711 -14.999716) (xy 201.408284 -14.999716) (xy 199.989339 -16.418661) (xy 284.073592 -16.418661)
			(xy 284.073592 -16.347339) (xy 284.081578 -16.276465) (xy 284.097448 -16.20693) (xy 284.121005 -16.13961)
			(xy 284.15195 -16.075351) (xy 284.189896 -16.01496) (xy 284.234365 -15.959198) (xy 284.284798 -15.908765)
			(xy 284.34056 -15.864296) (xy 284.400951 -15.82635) (xy 284.46521 -15.795405) (xy 284.53253 -15.771848)
			(xy 284.602065 -15.755978) (xy 284.672939 -15.747992) (xy 284.744261 -15.747992) (xy 284.815135 -15.755978)
			(xy 284.88467 -15.771848) (xy 284.95199 -15.795405) (xy 285.016249 -15.82635) (xy 285.07664 -15.864296)
			(xy 285.132402 -15.908765) (xy 285.182835 -15.959198) (xy 285.227304 -16.01496) (xy 285.26525 -16.075351)
			(xy 285.296195 -16.13961) (xy 285.319752 -16.20693) (xy 285.335622 -16.276465) (xy 285.343608 -16.347339)
			(xy 285.344108 -16.383) (xy 285.343608 -16.418661) (xy 290.728392 -16.418661) (xy 290.728392 -16.347339)
			(xy 290.736378 -16.276465) (xy 290.752248 -16.20693) (xy 290.775805 -16.13961) (xy 290.80675 -16.075351)
			(xy 290.844696 -16.01496) (xy 290.889165 -15.959198) (xy 290.939598 -15.908765) (xy 290.99536 -15.864296)
			(xy 291.055751 -15.82635) (xy 291.12001 -15.795405) (xy 291.18733 -15.771848) (xy 291.256865 -15.755978)
			(xy 291.327739 -15.747992) (xy 291.399061 -15.747992) (xy 291.469935 -15.755978) (xy 291.53947 -15.771848)
			(xy 291.60679 -15.795405) (xy 291.671049 -15.82635) (xy 291.73144 -15.864296) (xy 291.787202 -15.908765)
			(xy 291.837635 -15.959198) (xy 291.882104 -16.01496) (xy 291.92005 -16.075351) (xy 291.950995 -16.13961)
			(xy 291.974552 -16.20693) (xy 291.990422 -16.276465) (xy 291.998408 -16.347339) (xy 291.998908 -16.383)
			(xy 291.998408 -16.418661) (xy 291.990422 -16.489535) (xy 291.974552 -16.55907) (xy 291.950995 -16.62639)
			(xy 291.92005 -16.690649) (xy 291.882104 -16.75104) (xy 291.837635 -16.806802) (xy 291.787202 -16.857235)
			(xy 291.73144 -16.901704) (xy 291.671049 -16.93965) (xy 291.60679 -16.970595) (xy 291.53947 -16.994152)
			(xy 291.469935 -17.010022) (xy 291.399061 -17.018008) (xy 291.327739 -17.018008) (xy 291.256865 -17.010022)
			(xy 291.18733 -16.994152) (xy 291.12001 -16.970595) (xy 291.055751 -16.93965) (xy 290.99536 -16.901704)
			(xy 290.939598 -16.857235) (xy 290.889165 -16.806802) (xy 290.844696 -16.75104) (xy 290.80675 -16.690649)
			(xy 290.775805 -16.62639) (xy 290.752248 -16.55907) (xy 290.736378 -16.489535) (xy 290.728392 -16.418661)
			(xy 285.343608 -16.418661) (xy 285.335622 -16.489535) (xy 285.319752 -16.55907) (xy 285.296195 -16.62639)
			(xy 285.26525 -16.690649) (xy 285.227304 -16.75104) (xy 285.182835 -16.806802) (xy 285.132402 -16.857235)
			(xy 285.07664 -16.901704) (xy 285.016249 -16.93965) (xy 284.95199 -16.970595) (xy 284.88467 -16.994152)
			(xy 284.815135 -17.010022) (xy 284.744261 -17.018008) (xy 284.672939 -17.018008) (xy 284.602065 -17.010022)
			(xy 284.53253 -16.994152) (xy 284.46521 -16.970595) (xy 284.400951 -16.93965) (xy 284.34056 -16.901704)
			(xy 284.284798 -16.857235) (xy 284.234365 -16.806802) (xy 284.189896 -16.75104) (xy 284.15195 -16.690649)
			(xy 284.121005 -16.62639) (xy 284.097448 -16.55907) (xy 284.081578 -16.489535) (xy 284.073592 -16.418661)
			(xy 199.989339 -16.418661) (xy 199.4408 -16.9672) (xy 199.4408 -20.707863) (xy 254.837941 -20.707863)
			(xy 254.837941 -20.592537) (xy 254.845986 -20.477491) (xy 254.862036 -20.363287) (xy 254.886014 -20.250481)
			(xy 254.917802 -20.139622) (xy 254.957246 -20.03125) (xy 255.004154 -19.925894) (xy 255.058296 -19.824067)
			(xy 255.11941 -19.726265) (xy 255.187197 -19.632964) (xy 255.261327 -19.544619) (xy 255.34144 -19.46166)
			(xy 255.427144 -19.384491) (xy 255.518023 -19.313489) (xy 255.613633 -19.248999) (xy 255.713508 -19.191336)
			(xy 255.817163 -19.14078) (xy 255.924092 -19.097578) (xy 256.033774 -19.06194) (xy 256.145675 -19.03404)
			(xy 256.259249 -19.014014) (xy 256.373944 -19.001959) (xy 256.4892 -18.997935) (xy 256.604456 -19.001959)
			(xy 256.719151 -19.014014) (xy 256.832725 -19.03404) (xy 256.944626 -19.06194) (xy 257.054308 -19.097578)
			(xy 257.161237 -19.14078) (xy 257.264892 -19.191336) (xy 257.364767 -19.248999) (xy 257.460377 -19.313489)
			(xy 257.551256 -19.384491) (xy 257.63696 -19.46166) (xy 257.717073 -19.544619) (xy 257.791203 -19.632964)
			(xy 257.85899 -19.726265) (xy 257.920104 -19.824067) (xy 257.967709 -19.9136) (xy 322.188076 -19.9136)
			(xy 322.192147 -19.857978) (xy 322.204273 -19.803541) (xy 322.224196 -19.75145) (xy 322.251492 -19.702815)
			(xy 322.285578 -19.658672) (xy 322.325727 -19.619963) (xy 322.371085 -19.587512) (xy 322.420685 -19.562011)
			(xy 322.473469 -19.544004) (xy 322.528312 -19.533874) (xy 322.584046 -19.531837) (xy 322.639483 -19.537937)
			(xy 322.69344 -19.552043) (xy 322.744769 -19.573855) (xy 322.792375 -19.602909) (xy 322.835243 -19.638584)
			(xy 322.87246 -19.680121) (xy 322.903233 -19.726634) (xy 322.926905 -19.777131) (xy 322.942973 -19.830538)
			(xy 322.951093 -19.885714) (xy 322.951602 -19.9136) (xy 322.951093 -19.941486) (xy 322.942973 -19.996662)
			(xy 322.926905 -20.050069) (xy 322.919437 -20.066) (xy 323.788022 -20.066) (xy 323.792093 -20.010378)
			(xy 323.804219 -19.955941) (xy 323.824142 -19.90385) (xy 323.851438 -19.855215) (xy 323.885524 -19.811072)
			(xy 323.925673 -19.772363) (xy 323.971031 -19.739912) (xy 324.020631 -19.714411) (xy 324.073415 -19.696404)
			(xy 324.128258 -19.686274) (xy 324.183992 -19.684237) (xy 324.239429 -19.690337) (xy 324.293386 -19.704443)
			(xy 324.344715 -19.726255) (xy 324.392321 -19.755309) (xy 324.435189 -19.790984) (xy 324.472406 -19.832521)
			(xy 324.503179 -19.879034) (xy 324.526851 -19.929531) (xy 324.528894 -19.93632) (xy 326.988772 -19.93632)
			(xy 326.989454 -19.881244) (xy 326.998047 -19.826839) (xy 327.014373 -19.774234) (xy 327.038092 -19.724522)
			(xy 327.068712 -19.678738) (xy 327.105597 -19.637831) (xy 327.14798 -19.602652) (xy 327.19498 -19.573933)
			(xy 327.24562 -19.552269) (xy 327.29885 -19.538111) (xy 327.353562 -19.531752) (xy 327.408619 -19.533326)
			(xy 327.462879 -19.5428) (xy 327.515212 -19.559976) (xy 327.564533 -19.584497) (xy 327.609816 -19.615855)
			(xy 327.650119 -19.653398) (xy 327.684607 -19.696345) (xy 327.712561 -19.743804) (xy 327.733402 -19.794789)
			(xy 327.740518 -19.821398) (xy 327.746536 -19.843457) (xy 327.765331 -19.885134) (xy 327.791274 -19.92278)
			(xy 327.823529 -19.955182) (xy 327.861056 -19.981296) (xy 327.902647 -20.000281) (xy 327.946962 -20.011526)
			(xy 327.992573 -20.014667) (xy 328.038011 -20.009605) (xy 328.06005 -20.003516) (xy 328.086558 -19.996038)
			(xy 328.141032 -19.987915) (xy 328.196108 -19.987708) (xy 328.250642 -19.995422) (xy 328.3035 -20.010896)
			(xy 328.353584 -20.033809) (xy 328.399853 -20.063685) (xy 328.441347 -20.099903) (xy 328.477202 -20.141709)
			(xy 328.506674 -20.188237) (xy 328.529151 -20.238518) (xy 328.544165 -20.291509) (xy 328.551404 -20.346108)
			(xy 328.550719 -20.40118) (xy 328.542122 -20.455582) (xy 328.525794 -20.508182) (xy 328.502073 -20.557888)
			(xy 328.471451 -20.603668) (xy 328.434566 -20.644569) (xy 328.392184 -20.679743) (xy 328.345185 -20.708457)
			(xy 328.294546 -20.730116) (xy 328.241319 -20.74427) (xy 328.18661 -20.750624) (xy 328.131557 -20.749046)
			(xy 328.077301 -20.739569) (xy 328.024972 -20.722391) (xy 327.975657 -20.697867) (xy 327.930379 -20.666508)
			(xy 327.890081 -20.628966) (xy 327.855599 -20.586019) (xy 327.827649 -20.538561) (xy 327.806814 -20.487578)
			(xy 327.7997 -20.46097) (xy 327.79368 -20.438912) (xy 327.774882 -20.397238) (xy 327.748938 -20.359594)
			(xy 327.716683 -20.327195) (xy 327.679156 -20.301082) (xy 327.637567 -20.282097) (xy 327.593254 -20.270851)
			(xy 327.547644 -20.267707) (xy 327.502207 -20.272766) (xy 327.480168 -20.278852) (xy 327.453674 -20.286381)
			(xy 327.399196 -20.294508) (xy 327.344117 -20.294719) (xy 327.289579 -20.287008) (xy 327.236716 -20.271537)
			(xy 327.186627 -20.248626) (xy 327.140353 -20.218751) (xy 327.098854 -20.182534) (xy 327.062993 -20.140727)
			(xy 327.033516 -20.094198) (xy 327.011034 -20.043915) (xy 326.996016 -19.990922) (xy 326.988772 -19.93632)
			(xy 324.528894 -19.93632) (xy 324.542919 -19.982938) (xy 324.551039 -20.038114) (xy 324.551548 -20.066)
			(xy 324.551039 -20.093886) (xy 324.542919 -20.149062) (xy 324.526851 -20.202469) (xy 324.503179 -20.252966)
			(xy 324.472406 -20.299479) (xy 324.435189 -20.341016) (xy 324.392321 -20.376691) (xy 324.344715 -20.405745)
			(xy 324.293386 -20.427557) (xy 324.239429 -20.441663) (xy 324.183992 -20.447763) (xy 324.128258 -20.445726)
			(xy 324.073415 -20.435596) (xy 324.020631 -20.417589) (xy 323.971031 -20.392088) (xy 323.925673 -20.359637)
			(xy 323.885524 -20.320928) (xy 323.851438 -20.276785) (xy 323.824142 -20.22815) (xy 323.804219 -20.176059)
			(xy 323.792093 -20.121622) (xy 323.788022 -20.066) (xy 322.919437 -20.066) (xy 322.903233 -20.100566)
			(xy 322.87246 -20.147079) (xy 322.835243 -20.188616) (xy 322.792375 -20.224291) (xy 322.744769 -20.253345)
			(xy 322.69344 -20.275157) (xy 322.639483 -20.289263) (xy 322.584046 -20.295363) (xy 322.528312 -20.293326)
			(xy 322.473469 -20.283196) (xy 322.420685 -20.265189) (xy 322.371085 -20.239688) (xy 322.325727 -20.207237)
			(xy 322.285578 -20.168528) (xy 322.251492 -20.124385) (xy 322.224196 -20.07575) (xy 322.204273 -20.023659)
			(xy 322.192147 -19.969222) (xy 322.188076 -19.9136) (xy 257.967709 -19.9136) (xy 257.974246 -19.925894)
			(xy 258.021154 -20.03125) (xy 258.060598 -20.139622) (xy 258.092386 -20.250481) (xy 258.116364 -20.363287)
			(xy 258.132414 -20.477491) (xy 258.140459 -20.592537) (xy 258.140962 -20.6502) (xy 258.140459 -20.707863)
			(xy 258.132414 -20.822909) (xy 258.116364 -20.937113) (xy 258.092386 -21.049919) (xy 258.060598 -21.160778)
			(xy 258.021154 -21.26915) (xy 257.974246 -21.374506) (xy 257.962253 -21.397061) (xy 261.467592 -21.397061)
			(xy 261.467592 -21.325739) (xy 261.475578 -21.254865) (xy 261.491448 -21.18533) (xy 261.515005 -21.11801)
			(xy 261.54595 -21.053751) (xy 261.583896 -20.99336) (xy 261.628365 -20.937598) (xy 261.678798 -20.887165)
			(xy 261.73456 -20.842696) (xy 261.794951 -20.80475) (xy 261.85921 -20.773805) (xy 261.92653 -20.750248)
			(xy 261.996065 -20.734378) (xy 262.066939 -20.726392) (xy 262.138261 -20.726392) (xy 262.209135 -20.734378)
			(xy 262.27867 -20.750248) (xy 262.34599 -20.773805) (xy 262.410249 -20.80475) (xy 262.47064 -20.842696)
			(xy 262.526402 -20.887165) (xy 262.576835 -20.937598) (xy 262.621304 -20.99336) (xy 262.65925 -21.053751)
			(xy 262.690195 -21.11801) (xy 262.713752 -21.18533) (xy 262.729622 -21.254865) (xy 262.737608 -21.325739)
			(xy 262.738108 -21.3614) (xy 262.737608 -21.397061) (xy 269.087592 -21.397061) (xy 269.087592 -21.325739)
			(xy 269.095578 -21.254865) (xy 269.111448 -21.18533) (xy 269.135005 -21.11801) (xy 269.16595 -21.053751)
			(xy 269.203896 -20.99336) (xy 269.248365 -20.937598) (xy 269.298798 -20.887165) (xy 269.35456 -20.842696)
			(xy 269.414951 -20.80475) (xy 269.47921 -20.773805) (xy 269.54653 -20.750248) (xy 269.616065 -20.734378)
			(xy 269.686939 -20.726392) (xy 269.758261 -20.726392) (xy 269.829135 -20.734378) (xy 269.89867 -20.750248)
			(xy 269.96599 -20.773805) (xy 270.030249 -20.80475) (xy 270.09064 -20.842696) (xy 270.146402 -20.887165)
			(xy 270.196835 -20.937598) (xy 270.241304 -20.99336) (xy 270.27925 -21.053751) (xy 270.310195 -21.11801)
			(xy 270.333752 -21.18533) (xy 270.349622 -21.254865) (xy 270.357608 -21.325739) (xy 270.358108 -21.3614)
			(xy 270.357608 -21.397061) (xy 276.707592 -21.397061) (xy 276.707592 -21.325739) (xy 276.715578 -21.254865)
			(xy 276.731448 -21.18533) (xy 276.755005 -21.11801) (xy 276.78595 -21.053751) (xy 276.823896 -20.99336)
			(xy 276.868365 -20.937598) (xy 276.918798 -20.887165) (xy 276.97456 -20.842696) (xy 277.034951 -20.80475)
			(xy 277.09921 -20.773805) (xy 277.16653 -20.750248) (xy 277.236065 -20.734378) (xy 277.306939 -20.726392)
			(xy 277.378261 -20.726392) (xy 277.449135 -20.734378) (xy 277.51867 -20.750248) (xy 277.58599 -20.773805)
			(xy 277.650249 -20.80475) (xy 277.71064 -20.842696) (xy 277.766402 -20.887165) (xy 277.816835 -20.937598)
			(xy 277.861304 -20.99336) (xy 277.89925 -21.053751) (xy 277.930195 -21.11801) (xy 277.953752 -21.18533)
			(xy 277.969622 -21.254865) (xy 277.977608 -21.325739) (xy 277.978108 -21.3614) (xy 277.977608 -21.397061)
			(xy 284.327592 -21.397061) (xy 284.327592 -21.325739) (xy 284.335578 -21.254865) (xy 284.351448 -21.18533)
			(xy 284.375005 -21.11801) (xy 284.40595 -21.053751) (xy 284.443896 -20.99336) (xy 284.488365 -20.937598)
			(xy 284.538798 -20.887165) (xy 284.59456 -20.842696) (xy 284.654951 -20.80475) (xy 284.71921 -20.773805)
			(xy 284.78653 -20.750248) (xy 284.856065 -20.734378) (xy 284.926939 -20.726392) (xy 284.998261 -20.726392)
			(xy 285.069135 -20.734378) (xy 285.13867 -20.750248) (xy 285.20599 -20.773805) (xy 285.270249 -20.80475)
			(xy 285.33064 -20.842696) (xy 285.386402 -20.887165) (xy 285.436835 -20.937598) (xy 285.481304 -20.99336)
			(xy 285.51925 -21.053751) (xy 285.550195 -21.11801) (xy 285.573752 -21.18533) (xy 285.589622 -21.254865)
			(xy 285.597608 -21.325739) (xy 285.598108 -21.3614) (xy 285.597608 -21.397061) (xy 291.947592 -21.397061)
			(xy 291.947592 -21.325739) (xy 291.955578 -21.254865) (xy 291.971448 -21.18533) (xy 291.995005 -21.11801)
			(xy 292.02595 -21.053751) (xy 292.063896 -20.99336) (xy 292.108365 -20.937598) (xy 292.158798 -20.887165)
			(xy 292.21456 -20.842696) (xy 292.274951 -20.80475) (xy 292.33921 -20.773805) (xy 292.40653 -20.750248)
			(xy 292.476065 -20.734378) (xy 292.546939 -20.726392) (xy 292.618261 -20.726392) (xy 292.689135 -20.734378)
			(xy 292.75867 -20.750248) (xy 292.82599 -20.773805) (xy 292.890249 -20.80475) (xy 292.95064 -20.842696)
			(xy 293.006402 -20.887165) (xy 293.056835 -20.937598) (xy 293.101304 -20.99336) (xy 293.111991 -21.010368)
			(xy 335.203782 -21.010368) (xy 335.203782 -20.950432) (xy 335.211605 -20.89101) (xy 335.227118 -20.833117)
			(xy 335.250054 -20.777744) (xy 335.280021 -20.725838) (xy 335.316508 -20.678288) (xy 335.358888 -20.635908)
			(xy 335.406438 -20.599421) (xy 335.458344 -20.569454) (xy 335.513717 -20.546518) (xy 335.57161 -20.531005)
			(xy 335.631032 -20.523182) (xy 335.690968 -20.523182) (xy 335.75039 -20.531005) (xy 335.808283 -20.546518)
			(xy 335.863656 -20.569454) (xy 335.915562 -20.599421) (xy 335.963112 -20.635908) (xy 336.005492 -20.678288)
			(xy 336.041979 -20.725838) (xy 336.071946 -20.777744) (xy 336.094882 -20.833117) (xy 336.110395 -20.89101)
			(xy 336.118218 -20.950432) (xy 336.118708 -20.9804) (xy 336.118218 -21.010368) (xy 336.110395 -21.06979)
			(xy 336.094882 -21.127683) (xy 336.071946 -21.183056) (xy 336.041979 -21.234962) (xy 336.005492 -21.282512)
			(xy 335.963112 -21.324892) (xy 335.915562 -21.361379) (xy 335.863656 -21.391346) (xy 335.808283 -21.414282)
			(xy 335.75039 -21.429795) (xy 335.690968 -21.437618) (xy 335.631032 -21.437618) (xy 335.57161 -21.429795)
			(xy 335.513717 -21.414282) (xy 335.458344 -21.391346) (xy 335.406438 -21.361379) (xy 335.358888 -21.324892)
			(xy 335.316508 -21.282512) (xy 335.280021 -21.234962) (xy 335.250054 -21.183056) (xy 335.227118 -21.127683)
			(xy 335.211605 -21.06979) (xy 335.203782 -21.010368) (xy 293.111991 -21.010368) (xy 293.13925 -21.053751)
			(xy 293.170195 -21.11801) (xy 293.193752 -21.18533) (xy 293.209622 -21.254865) (xy 293.217608 -21.325739)
			(xy 293.218108 -21.3614) (xy 293.217608 -21.397061) (xy 293.209622 -21.467935) (xy 293.193752 -21.53747)
			(xy 293.170195 -21.60479) (xy 293.13925 -21.669049) (xy 293.101304 -21.72944) (xy 293.056835 -21.785202)
			(xy 293.006402 -21.835635) (xy 292.95064 -21.880104) (xy 292.890249 -21.91805) (xy 292.82599 -21.948995)
			(xy 292.75867 -21.972552) (xy 292.689135 -21.988422) (xy 292.618261 -21.996408) (xy 292.546939 -21.996408)
			(xy 292.476065 -21.988422) (xy 292.40653 -21.972552) (xy 292.33921 -21.948995) (xy 292.274951 -21.91805)
			(xy 292.21456 -21.880104) (xy 292.158798 -21.835635) (xy 292.108365 -21.785202) (xy 292.063896 -21.72944)
			(xy 292.02595 -21.669049) (xy 291.995005 -21.60479) (xy 291.971448 -21.53747) (xy 291.955578 -21.467935)
			(xy 291.947592 -21.397061) (xy 285.597608 -21.397061) (xy 285.589622 -21.467935) (xy 285.573752 -21.53747)
			(xy 285.550195 -21.60479) (xy 285.51925 -21.669049) (xy 285.481304 -21.72944) (xy 285.436835 -21.785202)
			(xy 285.386402 -21.835635) (xy 285.33064 -21.880104) (xy 285.270249 -21.91805) (xy 285.20599 -21.948995)
			(xy 285.13867 -21.972552) (xy 285.069135 -21.988422) (xy 284.998261 -21.996408) (xy 284.926939 -21.996408)
			(xy 284.856065 -21.988422) (xy 284.78653 -21.972552) (xy 284.71921 -21.948995) (xy 284.654951 -21.91805)
			(xy 284.59456 -21.880104) (xy 284.538798 -21.835635) (xy 284.488365 -21.785202) (xy 284.443896 -21.72944)
			(xy 284.40595 -21.669049) (xy 284.375005 -21.60479) (xy 284.351448 -21.53747) (xy 284.335578 -21.467935)
			(xy 284.327592 -21.397061) (xy 277.977608 -21.397061) (xy 277.969622 -21.467935) (xy 277.953752 -21.53747)
			(xy 277.930195 -21.60479) (xy 277.89925 -21.669049) (xy 277.861304 -21.72944) (xy 277.816835 -21.785202)
			(xy 277.766402 -21.835635) (xy 277.71064 -21.880104) (xy 277.650249 -21.91805) (xy 277.58599 -21.948995)
			(xy 277.51867 -21.972552) (xy 277.449135 -21.988422) (xy 277.378261 -21.996408) (xy 277.306939 -21.996408)
			(xy 277.236065 -21.988422) (xy 277.16653 -21.972552) (xy 277.09921 -21.948995) (xy 277.034951 -21.91805)
			(xy 276.97456 -21.880104) (xy 276.918798 -21.835635) (xy 276.868365 -21.785202) (xy 276.823896 -21.72944)
			(xy 276.78595 -21.669049) (xy 276.755005 -21.60479) (xy 276.731448 -21.53747) (xy 276.715578 -21.467935)
			(xy 276.707592 -21.397061) (xy 270.357608 -21.397061) (xy 270.349622 -21.467935) (xy 270.333752 -21.53747)
			(xy 270.310195 -21.60479) (xy 270.27925 -21.669049) (xy 270.241304 -21.72944) (xy 270.196835 -21.785202)
			(xy 270.146402 -21.835635) (xy 270.09064 -21.880104) (xy 270.030249 -21.91805) (xy 269.96599 -21.948995)
			(xy 269.89867 -21.972552) (xy 269.829135 -21.988422) (xy 269.758261 -21.996408) (xy 269.686939 -21.996408)
			(xy 269.616065 -21.988422) (xy 269.54653 -21.972552) (xy 269.47921 -21.948995) (xy 269.414951 -21.91805)
			(xy 269.35456 -21.880104) (xy 269.298798 -21.835635) (xy 269.248365 -21.785202) (xy 269.203896 -21.72944)
			(xy 269.16595 -21.669049) (xy 269.135005 -21.60479) (xy 269.111448 -21.53747) (xy 269.095578 -21.467935)
			(xy 269.087592 -21.397061) (xy 262.737608 -21.397061) (xy 262.729622 -21.467935) (xy 262.713752 -21.53747)
			(xy 262.690195 -21.60479) (xy 262.65925 -21.669049) (xy 262.621304 -21.72944) (xy 262.576835 -21.785202)
			(xy 262.526402 -21.835635) (xy 262.47064 -21.880104) (xy 262.410249 -21.91805) (xy 262.34599 -21.948995)
			(xy 262.27867 -21.972552) (xy 262.209135 -21.988422) (xy 262.138261 -21.996408) (xy 262.066939 -21.996408)
			(xy 261.996065 -21.988422) (xy 261.92653 -21.972552) (xy 261.85921 -21.948995) (xy 261.794951 -21.91805)
			(xy 261.73456 -21.880104) (xy 261.678798 -21.835635) (xy 261.628365 -21.785202) (xy 261.583896 -21.72944)
			(xy 261.54595 -21.669049) (xy 261.515005 -21.60479) (xy 261.491448 -21.53747) (xy 261.475578 -21.467935)
			(xy 261.467592 -21.397061) (xy 257.962253 -21.397061) (xy 257.920104 -21.476333) (xy 257.85899 -21.574135)
			(xy 257.791203 -21.667436) (xy 257.717073 -21.755781) (xy 257.63696 -21.83874) (xy 257.551256 -21.915909)
			(xy 257.460377 -21.986911) (xy 257.364767 -22.051401) (xy 257.264892 -22.109064) (xy 257.236881 -22.122726)
			(xy 324.588785 -22.122726) (xy 324.596651 -22.0674) (xy 324.612502 -22.013812) (xy 324.636 -21.96311)
			(xy 324.666643 -21.916377) (xy 324.703774 -21.874614) (xy 324.7466 -21.838713) (xy 324.794204 -21.809443)
			(xy 324.845569 -21.78743) (xy 324.899595 -21.773144) (xy 324.955127 -21.766891) (xy 325.010977 -21.768805)
			(xy 325.065951 -21.778845) (xy 325.092568 -21.787358) (xy 325.113341 -21.793944) (xy 325.156385 -21.800725)
			(xy 325.199954 -21.80006) (xy 325.242771 -21.791968) (xy 325.283578 -21.776687) (xy 325.321178 -21.754664)
			(xy 325.354467 -21.726547) (xy 325.382469 -21.693161) (xy 325.404362 -21.655485) (xy 325.412354 -21.635212)
			(xy 325.422178 -21.610045) (xy 325.447917 -21.562546) (xy 325.4801 -21.519154) (xy 325.518085 -21.480736)
			(xy 325.561109 -21.448063) (xy 325.608314 -21.421788) (xy 325.658754 -21.402436) (xy 325.711419 -21.390394)
			(xy 325.765257 -21.385904) (xy 325.81919 -21.389056) (xy 325.872138 -21.399786) (xy 325.897748 -21.40839)
			(xy 325.918143 -21.415091) (xy 325.960426 -21.422477) (xy 326.003349 -21.422649) (xy 326.045689 -21.415601)
			(xy 326.086242 -21.401534) (xy 326.123852 -21.380849) (xy 326.157449 -21.354135) (xy 326.186076 -21.322152)
			(xy 326.208917 -21.285811) (xy 326.217534 -21.26615) (xy 326.228615 -21.240652) (xy 326.257115 -21.192918)
			(xy 326.292241 -21.149826) (xy 326.333249 -21.112288) (xy 326.379272 -21.0811) (xy 326.429334 -21.056922)
			(xy 326.482375 -21.040267) (xy 326.537272 -21.031486) (xy 326.592862 -21.030766) (xy 326.647968 -21.038123)
			(xy 326.701423 -21.053399) (xy 326.752094 -21.076273) (xy 326.798909 -21.106259) (xy 326.840876 -21.142722)
			(xy 326.877106 -21.18489) (xy 326.906831 -21.231871) (xy 326.929424 -21.282668) (xy 326.944404 -21.336206)
			(xy 326.951454 -21.391352) (xy 326.950427 -21.446938) (xy 326.941342 -21.501785) (xy 326.924392 -21.554733)
			(xy 326.899937 -21.60466) (xy 326.868495 -21.650509) (xy 326.83073 -21.691309) (xy 326.787444 -21.726196)
			(xy 326.739552 -21.75443) (xy 326.68807 -21.775415) (xy 326.634087 -21.788704) (xy 326.578747 -21.794018)
			(xy 326.523222 -21.791243) (xy 326.468687 -21.780439) (xy 326.442324 -21.77161) (xy 326.421939 -21.764877)
			(xy 326.379652 -21.757495) (xy 326.336727 -21.757327) (xy 326.294385 -21.764379) (xy 326.25383 -21.77845)
			(xy 326.216219 -21.799139) (xy 326.182622 -21.825857) (xy 326.153996 -21.857843) (xy 326.131155 -21.894188)
			(xy 326.122538 -21.91385) (xy 326.111086 -21.940199) (xy 326.08139 -21.98938) (xy 326.044657 -22.033553)
			(xy 326.001718 -22.071721) (xy 325.953542 -22.103022) (xy 325.901218 -22.126747) (xy 325.84593 -22.142361)
			(xy 325.788925 -22.149511) (xy 325.731493 -22.148035) (xy 325.674931 -22.137966) (xy 325.647558 -22.129242)
			(xy 325.626776 -22.122685) (xy 325.583736 -22.1159) (xy 325.540169 -22.116562) (xy 325.497354 -22.12465)
			(xy 325.456548 -22.139928) (xy 325.418949 -22.161947) (xy 325.385659 -22.19006) (xy 325.357657 -22.223443)
			(xy 325.335764 -22.261116) (xy 325.327772 -22.281388) (xy 325.317579 -22.307409) (xy 325.304552 -22.331168)
			(xy 335.457782 -22.331168) (xy 335.457782 -22.271232) (xy 335.465605 -22.21181) (xy 335.481118 -22.153917)
			(xy 335.504054 -22.098544) (xy 335.534021 -22.046638) (xy 335.570508 -21.999088) (xy 335.612888 -21.956708)
			(xy 335.660438 -21.920221) (xy 335.712344 -21.890254) (xy 335.767717 -21.867318) (xy 335.82561 -21.851805)
			(xy 335.885032 -21.843982) (xy 335.944968 -21.843982) (xy 336.00439 -21.851805) (xy 336.062283 -21.867318)
			(xy 336.117656 -21.890254) (xy 336.169562 -21.920221) (xy 336.217112 -21.956708) (xy 336.259492 -21.999088)
			(xy 336.295979 -22.046638) (xy 336.325946 -22.098544) (xy 336.348882 -22.153917) (xy 336.364395 -22.21181)
			(xy 336.372218 -22.271232) (xy 336.372708 -22.3012) (xy 336.372218 -22.331168) (xy 336.364395 -22.39059)
			(xy 336.348882 -22.448483) (xy 336.325946 -22.503856) (xy 336.295979 -22.555762) (xy 336.259492 -22.603312)
			(xy 336.217112 -22.645692) (xy 336.169562 -22.682179) (xy 336.117656 -22.712146) (xy 336.062283 -22.735082)
			(xy 336.00439 -22.750595) (xy 335.944968 -22.758418) (xy 335.885032 -22.758418) (xy 335.82561 -22.750595)
			(xy 335.767717 -22.735082) (xy 335.712344 -22.712146) (xy 335.660438 -22.682179) (xy 335.612888 -22.645692)
			(xy 335.570508 -22.603312) (xy 335.534021 -22.555762) (xy 335.504054 -22.503856) (xy 335.481118 -22.448483)
			(xy 335.465605 -22.39059) (xy 335.457782 -22.331168) (xy 325.304552 -22.331168) (xy 325.290712 -22.35641)
			(xy 325.256985 -22.400968) (xy 325.21712 -22.44013) (xy 325.171969 -22.473058) (xy 325.122498 -22.499048)
			(xy 325.069764 -22.517545) (xy 325.014897 -22.528152) (xy 324.95907 -22.530642) (xy 324.903476 -22.524963)
			(xy 324.849306 -22.511236) (xy 324.797717 -22.489754) (xy 324.749813 -22.460977) (xy 324.706618 -22.425521)
			(xy 324.669058 -22.384143) (xy 324.637935 -22.337729) (xy 324.613914 -22.287272) (xy 324.59751 -22.233851)
			(xy 324.589074 -22.178609) (xy 324.588785 -22.122726) (xy 257.236881 -22.122726) (xy 257.161237 -22.15962)
			(xy 257.054308 -22.202822) (xy 256.944626 -22.23846) (xy 256.832725 -22.26636) (xy 256.719151 -22.286386)
			(xy 256.604456 -22.298441) (xy 256.4892 -22.302466) (xy 256.373944 -22.298441) (xy 256.259249 -22.286386)
			(xy 256.145675 -22.26636) (xy 256.033774 -22.23846) (xy 255.924092 -22.202822) (xy 255.817163 -22.15962)
			(xy 255.713508 -22.109064) (xy 255.613633 -22.051401) (xy 255.518023 -21.986911) (xy 255.427144 -21.915909)
			(xy 255.34144 -21.83874) (xy 255.261327 -21.755781) (xy 255.187197 -21.667436) (xy 255.11941 -21.574135)
			(xy 255.058296 -21.476333) (xy 255.004154 -21.374506) (xy 254.957246 -21.26915) (xy 254.917802 -21.160778)
			(xy 254.886014 -21.049919) (xy 254.862036 -20.937113) (xy 254.845986 -20.822909) (xy 254.837941 -20.707863)
			(xy 199.4408 -20.707863) (xy 199.4408 -22.006661) (xy 205.028792 -22.006661) (xy 205.028792 -21.935339)
			(xy 205.036778 -21.864465) (xy 205.052648 -21.79493) (xy 205.076205 -21.72761) (xy 205.10715 -21.663351)
			(xy 205.145096 -21.60296) (xy 205.189565 -21.547198) (xy 205.239998 -21.496765) (xy 205.29576 -21.452296)
			(xy 205.356151 -21.41435) (xy 205.42041 -21.383405) (xy 205.48773 -21.359848) (xy 205.557265 -21.343978)
			(xy 205.628139 -21.335992) (xy 205.699461 -21.335992) (xy 205.770335 -21.343978) (xy 205.83987 -21.359848)
			(xy 205.90719 -21.383405) (xy 205.971449 -21.41435) (xy 206.03184 -21.452296) (xy 206.087602 -21.496765)
			(xy 206.138035 -21.547198) (xy 206.182504 -21.60296) (xy 206.22045 -21.663351) (xy 206.251395 -21.72761)
			(xy 206.274952 -21.79493) (xy 206.290822 -21.864465) (xy 206.298808 -21.935339) (xy 206.299308 -21.971)
			(xy 206.298808 -22.006661) (xy 212.648792 -22.006661) (xy 212.648792 -21.935339) (xy 212.656778 -21.864465)
			(xy 212.672648 -21.79493) (xy 212.696205 -21.72761) (xy 212.72715 -21.663351) (xy 212.765096 -21.60296)
			(xy 212.809565 -21.547198) (xy 212.859998 -21.496765) (xy 212.91576 -21.452296) (xy 212.976151 -21.41435)
			(xy 213.04041 -21.383405) (xy 213.10773 -21.359848) (xy 213.177265 -21.343978) (xy 213.248139 -21.335992)
			(xy 213.319461 -21.335992) (xy 213.390335 -21.343978) (xy 213.45987 -21.359848) (xy 213.52719 -21.383405)
			(xy 213.591449 -21.41435) (xy 213.65184 -21.452296) (xy 213.707602 -21.496765) (xy 213.758035 -21.547198)
			(xy 213.802504 -21.60296) (xy 213.84045 -21.663351) (xy 213.871395 -21.72761) (xy 213.894952 -21.79493)
			(xy 213.910822 -21.864465) (xy 213.918808 -21.935339) (xy 213.919308 -21.971) (xy 213.918808 -22.006661)
			(xy 220.268792 -22.006661) (xy 220.268792 -21.935339) (xy 220.276778 -21.864465) (xy 220.292648 -21.79493)
			(xy 220.316205 -21.72761) (xy 220.34715 -21.663351) (xy 220.385096 -21.60296) (xy 220.429565 -21.547198)
			(xy 220.479998 -21.496765) (xy 220.53576 -21.452296) (xy 220.596151 -21.41435) (xy 220.66041 -21.383405)
			(xy 220.72773 -21.359848) (xy 220.797265 -21.343978) (xy 220.868139 -21.335992) (xy 220.939461 -21.335992)
			(xy 221.010335 -21.343978) (xy 221.07987 -21.359848) (xy 221.14719 -21.383405) (xy 221.211449 -21.41435)
			(xy 221.27184 -21.452296) (xy 221.327602 -21.496765) (xy 221.378035 -21.547198) (xy 221.422504 -21.60296)
			(xy 221.46045 -21.663351) (xy 221.491395 -21.72761) (xy 221.514952 -21.79493) (xy 221.530822 -21.864465)
			(xy 221.538808 -21.935339) (xy 221.539308 -21.971) (xy 221.538808 -22.006661) (xy 227.888792 -22.006661)
			(xy 227.888792 -21.935339) (xy 227.896778 -21.864465) (xy 227.912648 -21.79493) (xy 227.936205 -21.72761)
			(xy 227.96715 -21.663351) (xy 228.005096 -21.60296) (xy 228.049565 -21.547198) (xy 228.099998 -21.496765)
			(xy 228.15576 -21.452296) (xy 228.216151 -21.41435) (xy 228.28041 -21.383405) (xy 228.34773 -21.359848)
			(xy 228.417265 -21.343978) (xy 228.488139 -21.335992) (xy 228.559461 -21.335992) (xy 228.630335 -21.343978)
			(xy 228.69987 -21.359848) (xy 228.76719 -21.383405) (xy 228.831449 -21.41435) (xy 228.89184 -21.452296)
			(xy 228.947602 -21.496765) (xy 228.998035 -21.547198) (xy 229.042504 -21.60296) (xy 229.08045 -21.663351)
			(xy 229.111395 -21.72761) (xy 229.134952 -21.79493) (xy 229.150822 -21.864465) (xy 229.158808 -21.935339)
			(xy 229.159308 -21.971) (xy 229.158808 -22.006661) (xy 235.508792 -22.006661) (xy 235.508792 -21.935339)
			(xy 235.516778 -21.864465) (xy 235.532648 -21.79493) (xy 235.556205 -21.72761) (xy 235.58715 -21.663351)
			(xy 235.625096 -21.60296) (xy 235.669565 -21.547198) (xy 235.719998 -21.496765) (xy 235.77576 -21.452296)
			(xy 235.836151 -21.41435) (xy 235.90041 -21.383405) (xy 235.96773 -21.359848) (xy 236.037265 -21.343978)
			(xy 236.108139 -21.335992) (xy 236.179461 -21.335992) (xy 236.250335 -21.343978) (xy 236.31987 -21.359848)
			(xy 236.38719 -21.383405) (xy 236.451449 -21.41435) (xy 236.51184 -21.452296) (xy 236.567602 -21.496765)
			(xy 236.618035 -21.547198) (xy 236.662504 -21.60296) (xy 236.70045 -21.663351) (xy 236.731395 -21.72761)
			(xy 236.754952 -21.79493) (xy 236.770822 -21.864465) (xy 236.778808 -21.935339) (xy 236.779308 -21.971)
			(xy 236.778808 -22.006661) (xy 243.128792 -22.006661) (xy 243.128792 -21.935339) (xy 243.136778 -21.864465)
			(xy 243.152648 -21.79493) (xy 243.176205 -21.72761) (xy 243.20715 -21.663351) (xy 243.245096 -21.60296)
			(xy 243.289565 -21.547198) (xy 243.339998 -21.496765) (xy 243.39576 -21.452296) (xy 243.456151 -21.41435)
			(xy 243.52041 -21.383405) (xy 243.58773 -21.359848) (xy 243.657265 -21.343978) (xy 243.728139 -21.335992)
			(xy 243.799461 -21.335992) (xy 243.870335 -21.343978) (xy 243.93987 -21.359848) (xy 244.00719 -21.383405)
			(xy 244.071449 -21.41435) (xy 244.13184 -21.452296) (xy 244.187602 -21.496765) (xy 244.238035 -21.547198)
			(xy 244.282504 -21.60296) (xy 244.32045 -21.663351) (xy 244.351395 -21.72761) (xy 244.374952 -21.79493)
			(xy 244.390822 -21.864465) (xy 244.398808 -21.935339) (xy 244.399308 -21.971) (xy 244.398808 -22.006661)
			(xy 250.748792 -22.006661) (xy 250.748792 -21.935339) (xy 250.756778 -21.864465) (xy 250.772648 -21.79493)
			(xy 250.796205 -21.72761) (xy 250.82715 -21.663351) (xy 250.865096 -21.60296) (xy 250.909565 -21.547198)
			(xy 250.959998 -21.496765) (xy 251.01576 -21.452296) (xy 251.076151 -21.41435) (xy 251.14041 -21.383405)
			(xy 251.20773 -21.359848) (xy 251.277265 -21.343978) (xy 251.348139 -21.335992) (xy 251.419461 -21.335992)
			(xy 251.490335 -21.343978) (xy 251.55987 -21.359848) (xy 251.62719 -21.383405) (xy 251.691449 -21.41435)
			(xy 251.75184 -21.452296) (xy 251.807602 -21.496765) (xy 251.858035 -21.547198) (xy 251.902504 -21.60296)
			(xy 251.94045 -21.663351) (xy 251.971395 -21.72761) (xy 251.994952 -21.79493) (xy 252.010822 -21.864465)
			(xy 252.018808 -21.935339) (xy 252.019308 -21.971) (xy 252.018808 -22.006661) (xy 252.010822 -22.077535)
			(xy 251.994952 -22.14707) (xy 251.971395 -22.21439) (xy 251.94045 -22.278649) (xy 251.902504 -22.33904)
			(xy 251.858035 -22.394802) (xy 251.807602 -22.445235) (xy 251.75184 -22.489704) (xy 251.691449 -22.52765)
			(xy 251.62719 -22.558595) (xy 251.55987 -22.582152) (xy 251.490335 -22.598022) (xy 251.419461 -22.606008)
			(xy 251.348139 -22.606008) (xy 251.277265 -22.598022) (xy 251.20773 -22.582152) (xy 251.14041 -22.558595)
			(xy 251.076151 -22.52765) (xy 251.01576 -22.489704) (xy 250.959998 -22.445235) (xy 250.909565 -22.394802)
			(xy 250.865096 -22.33904) (xy 250.82715 -22.278649) (xy 250.796205 -22.21439) (xy 250.772648 -22.14707)
			(xy 250.756778 -22.077535) (xy 250.748792 -22.006661) (xy 244.398808 -22.006661) (xy 244.390822 -22.077535)
			(xy 244.374952 -22.14707) (xy 244.351395 -22.21439) (xy 244.32045 -22.278649) (xy 244.282504 -22.33904)
			(xy 244.238035 -22.394802) (xy 244.187602 -22.445235) (xy 244.13184 -22.489704) (xy 244.071449 -22.52765)
			(xy 244.00719 -22.558595) (xy 243.93987 -22.582152) (xy 243.870335 -22.598022) (xy 243.799461 -22.606008)
			(xy 243.728139 -22.606008) (xy 243.657265 -22.598022) (xy 243.58773 -22.582152) (xy 243.52041 -22.558595)
			(xy 243.456151 -22.52765) (xy 243.39576 -22.489704) (xy 243.339998 -22.445235) (xy 243.289565 -22.394802)
			(xy 243.245096 -22.33904) (xy 243.20715 -22.278649) (xy 243.176205 -22.21439) (xy 243.152648 -22.14707)
			(xy 243.136778 -22.077535) (xy 243.128792 -22.006661) (xy 236.778808 -22.006661) (xy 236.770822 -22.077535)
			(xy 236.754952 -22.14707) (xy 236.731395 -22.21439) (xy 236.70045 -22.278649) (xy 236.662504 -22.33904)
			(xy 236.618035 -22.394802) (xy 236.567602 -22.445235) (xy 236.51184 -22.489704) (xy 236.451449 -22.52765)
			(xy 236.38719 -22.558595) (xy 236.31987 -22.582152) (xy 236.250335 -22.598022) (xy 236.179461 -22.606008)
			(xy 236.108139 -22.606008) (xy 236.037265 -22.598022) (xy 235.96773 -22.582152) (xy 235.90041 -22.558595)
			(xy 235.836151 -22.52765) (xy 235.77576 -22.489704) (xy 235.719998 -22.445235) (xy 235.669565 -22.394802)
			(xy 235.625096 -22.33904) (xy 235.58715 -22.278649) (xy 235.556205 -22.21439) (xy 235.532648 -22.14707)
			(xy 235.516778 -22.077535) (xy 235.508792 -22.006661) (xy 229.158808 -22.006661) (xy 229.150822 -22.077535)
			(xy 229.134952 -22.14707) (xy 229.111395 -22.21439) (xy 229.08045 -22.278649) (xy 229.042504 -22.33904)
			(xy 228.998035 -22.394802) (xy 228.947602 -22.445235) (xy 228.89184 -22.489704) (xy 228.831449 -22.52765)
			(xy 228.76719 -22.558595) (xy 228.69987 -22.582152) (xy 228.630335 -22.598022) (xy 228.559461 -22.606008)
			(xy 228.488139 -22.606008) (xy 228.417265 -22.598022) (xy 228.34773 -22.582152) (xy 228.28041 -22.558595)
			(xy 228.216151 -22.52765) (xy 228.15576 -22.489704) (xy 228.099998 -22.445235) (xy 228.049565 -22.394802)
			(xy 228.005096 -22.33904) (xy 227.96715 -22.278649) (xy 227.936205 -22.21439) (xy 227.912648 -22.14707)
			(xy 227.896778 -22.077535) (xy 227.888792 -22.006661) (xy 221.538808 -22.006661) (xy 221.530822 -22.077535)
			(xy 221.514952 -22.14707) (xy 221.491395 -22.21439) (xy 221.46045 -22.278649) (xy 221.422504 -22.33904)
			(xy 221.378035 -22.394802) (xy 221.327602 -22.445235) (xy 221.27184 -22.489704) (xy 221.211449 -22.52765)
			(xy 221.14719 -22.558595) (xy 221.07987 -22.582152) (xy 221.010335 -22.598022) (xy 220.939461 -22.606008)
			(xy 220.868139 -22.606008) (xy 220.797265 -22.598022) (xy 220.72773 -22.582152) (xy 220.66041 -22.558595)
			(xy 220.596151 -22.52765) (xy 220.53576 -22.489704) (xy 220.479998 -22.445235) (xy 220.429565 -22.394802)
			(xy 220.385096 -22.33904) (xy 220.34715 -22.278649) (xy 220.316205 -22.21439) (xy 220.292648 -22.14707)
			(xy 220.276778 -22.077535) (xy 220.268792 -22.006661) (xy 213.918808 -22.006661) (xy 213.910822 -22.077535)
			(xy 213.894952 -22.14707) (xy 213.871395 -22.21439) (xy 213.84045 -22.278649) (xy 213.802504 -22.33904)
			(xy 213.758035 -22.394802) (xy 213.707602 -22.445235) (xy 213.65184 -22.489704) (xy 213.591449 -22.52765)
			(xy 213.52719 -22.558595) (xy 213.45987 -22.582152) (xy 213.390335 -22.598022) (xy 213.319461 -22.606008)
			(xy 213.248139 -22.606008) (xy 213.177265 -22.598022) (xy 213.10773 -22.582152) (xy 213.04041 -22.558595)
			(xy 212.976151 -22.52765) (xy 212.91576 -22.489704) (xy 212.859998 -22.445235) (xy 212.809565 -22.394802)
			(xy 212.765096 -22.33904) (xy 212.72715 -22.278649) (xy 212.696205 -22.21439) (xy 212.672648 -22.14707)
			(xy 212.656778 -22.077535) (xy 212.648792 -22.006661) (xy 206.298808 -22.006661) (xy 206.290822 -22.077535)
			(xy 206.274952 -22.14707) (xy 206.251395 -22.21439) (xy 206.22045 -22.278649) (xy 206.182504 -22.33904)
			(xy 206.138035 -22.394802) (xy 206.087602 -22.445235) (xy 206.03184 -22.489704) (xy 205.971449 -22.52765)
			(xy 205.90719 -22.558595) (xy 205.83987 -22.582152) (xy 205.770335 -22.598022) (xy 205.699461 -22.606008)
			(xy 205.628139 -22.606008) (xy 205.557265 -22.598022) (xy 205.48773 -22.582152) (xy 205.42041 -22.558595)
			(xy 205.356151 -22.52765) (xy 205.29576 -22.489704) (xy 205.239998 -22.445235) (xy 205.189565 -22.394802)
			(xy 205.145096 -22.33904) (xy 205.10715 -22.278649) (xy 205.076205 -22.21439) (xy 205.052648 -22.14707)
			(xy 205.036778 -22.077535) (xy 205.028792 -22.006661) (xy 199.4408 -22.006661) (xy 199.4408 -22.6314)
			(xy 322.988176 -22.6314) (xy 322.992247 -22.575778) (xy 323.004373 -22.521341) (xy 323.024296 -22.46925)
			(xy 323.051592 -22.420615) (xy 323.085678 -22.376472) (xy 323.125827 -22.337763) (xy 323.171185 -22.305312)
			(xy 323.220785 -22.279811) (xy 323.273569 -22.261804) (xy 323.328412 -22.251674) (xy 323.384146 -22.249637)
			(xy 323.439583 -22.255737) (xy 323.49354 -22.269843) (xy 323.544869 -22.291655) (xy 323.592475 -22.320709)
			(xy 323.635343 -22.356384) (xy 323.67256 -22.397921) (xy 323.703333 -22.444434) (xy 323.727005 -22.494931)
			(xy 323.743073 -22.548338) (xy 323.751193 -22.603514) (xy 323.751702 -22.6314) (xy 323.751193 -22.659286)
			(xy 323.743073 -22.714462) (xy 323.727005 -22.767869) (xy 323.703333 -22.818366) (xy 323.67256 -22.864879)
			(xy 323.635343 -22.906416) (xy 323.592475 -22.942091) (xy 323.544869 -22.971145) (xy 323.49354 -22.992957)
			(xy 323.439583 -23.007063) (xy 323.384146 -23.013163) (xy 323.328412 -23.011126) (xy 323.273569 -23.000996)
			(xy 323.220785 -22.982989) (xy 323.171185 -22.957488) (xy 323.125827 -22.925037) (xy 323.085678 -22.886328)
			(xy 323.051592 -22.842185) (xy 323.024296 -22.79355) (xy 323.004373 -22.741459) (xy 322.992247 -22.687022)
			(xy 322.988176 -22.6314) (xy 199.4408 -22.6314) (xy 199.4408 -23.601168) (xy 335.178382 -23.601168)
			(xy 335.178382 -23.541232) (xy 335.186205 -23.48181) (xy 335.201718 -23.423917) (xy 335.224654 -23.368544)
			(xy 335.254621 -23.316638) (xy 335.291108 -23.269088) (xy 335.333488 -23.226708) (xy 335.381038 -23.190221)
			(xy 335.432944 -23.160254) (xy 335.488317 -23.137318) (xy 335.54621 -23.121805) (xy 335.605632 -23.113982)
			(xy 335.665568 -23.113982) (xy 335.72499 -23.121805) (xy 335.782883 -23.137318) (xy 335.838256 -23.160254)
			(xy 335.890162 -23.190221) (xy 335.937712 -23.226708) (xy 335.980092 -23.269088) (xy 336.016579 -23.316638)
			(xy 336.046546 -23.368544) (xy 336.069482 -23.423917) (xy 336.084995 -23.48181) (xy 336.092818 -23.541232)
			(xy 336.093308 -23.5712) (xy 336.092818 -23.601168) (xy 336.084995 -23.66059) (xy 336.069482 -23.718483)
			(xy 336.046546 -23.773856) (xy 336.016579 -23.825762) (xy 335.980092 -23.873312) (xy 335.937712 -23.915692)
			(xy 335.890162 -23.952179) (xy 335.838256 -23.982146) (xy 335.782883 -24.005082) (xy 335.72499 -24.020595)
			(xy 335.665568 -24.028418) (xy 335.605632 -24.028418) (xy 335.54621 -24.020595) (xy 335.488317 -24.005082)
			(xy 335.432944 -23.982146) (xy 335.381038 -23.952179) (xy 335.333488 -23.915692) (xy 335.291108 -23.873312)
			(xy 335.254621 -23.825762) (xy 335.224654 -23.773856) (xy 335.201718 -23.718483) (xy 335.186205 -23.66059)
			(xy 335.178382 -23.601168) (xy 199.4408 -23.601168) (xy 199.4408 -25.236674) (xy 335.584782 -25.236674)
			(xy 335.584782 -25.176738) (xy 335.592605 -25.117316) (xy 335.608118 -25.059423) (xy 335.631054 -25.00405)
			(xy 335.661021 -24.952144) (xy 335.697508 -24.904594) (xy 335.739888 -24.862214) (xy 335.787438 -24.825727)
			(xy 335.839344 -24.79576) (xy 335.894717 -24.772824) (xy 335.95261 -24.757311) (xy 336.012032 -24.749488)
			(xy 336.071968 -24.749488) (xy 336.13139 -24.757311) (xy 336.189283 -24.772824) (xy 336.244656 -24.79576)
			(xy 336.296562 -24.825727) (xy 336.344112 -24.862214) (xy 336.386492 -24.904594) (xy 336.422979 -24.952144)
			(xy 336.452946 -25.00405) (xy 336.475882 -25.059423) (xy 336.491395 -25.117316) (xy 336.499218 -25.176738)
			(xy 336.499708 -25.206706) (xy 336.499218 -25.236674) (xy 336.491395 -25.296096) (xy 336.475882 -25.353989)
			(xy 336.452946 -25.409362) (xy 336.422979 -25.461268) (xy 336.386492 -25.508818) (xy 336.344112 -25.551198)
			(xy 336.296562 -25.587685) (xy 336.244656 -25.617652) (xy 336.189283 -25.640588) (xy 336.13139 -25.656101)
			(xy 336.071968 -25.663924) (xy 336.012032 -25.663924) (xy 335.95261 -25.656101) (xy 335.894717 -25.640588)
			(xy 335.839344 -25.617652) (xy 335.787438 -25.587685) (xy 335.739888 -25.551198) (xy 335.697508 -25.508818)
			(xy 335.661021 -25.461268) (xy 335.631054 -25.409362) (xy 335.608118 -25.353989) (xy 335.592605 -25.296096)
			(xy 335.584782 -25.236674) (xy 199.4408 -25.236674) (xy 199.4408 -26.156662) (xy 311.226182 -26.156662)
			(xy 311.226182 -26.096726) (xy 311.234005 -26.037304) (xy 311.249518 -25.979411) (xy 311.272454 -25.924038)
			(xy 311.302421 -25.872132) (xy 311.338908 -25.824582) (xy 311.381288 -25.782202) (xy 311.428838 -25.745715)
			(xy 311.480744 -25.715748) (xy 311.536117 -25.692812) (xy 311.59401 -25.677299) (xy 311.653432 -25.669476)
			(xy 311.713368 -25.669476) (xy 311.77279 -25.677299) (xy 311.830683 -25.692812) (xy 311.886056 -25.715748)
			(xy 311.937962 -25.745715) (xy 311.985512 -25.782202) (xy 312.027892 -25.824582) (xy 312.064379 -25.872132)
			(xy 312.094346 -25.924038) (xy 312.117282 -25.979411) (xy 312.132795 -26.037304) (xy 312.140618 -26.096726)
			(xy 312.141108 -26.126694) (xy 312.140618 -26.156662) (xy 312.132795 -26.216084) (xy 312.117282 -26.273977)
			(xy 312.094346 -26.32935) (xy 312.064379 -26.381256) (xy 312.027892 -26.428806) (xy 311.985512 -26.471186)
			(xy 311.937962 -26.507673) (xy 311.886056 -26.53764) (xy 311.830683 -26.560576) (xy 311.77279 -26.576089)
			(xy 311.713368 -26.583912) (xy 311.653432 -26.583912) (xy 311.59401 -26.576089) (xy 311.536117 -26.560576)
			(xy 311.480744 -26.53764) (xy 311.428838 -26.507673) (xy 311.381288 -26.471186) (xy 311.338908 -26.428806)
			(xy 311.302421 -26.381256) (xy 311.272454 -26.32935) (xy 311.249518 -26.273977) (xy 311.234005 -26.216084)
			(xy 311.226182 -26.156662) (xy 199.4408 -26.156662) (xy 199.4408 -27.553662) (xy 311.200782 -27.553662)
			(xy 311.200782 -27.493726) (xy 311.208605 -27.434304) (xy 311.224118 -27.376411) (xy 311.247054 -27.321038)
			(xy 311.277021 -27.269132) (xy 311.313508 -27.221582) (xy 311.355888 -27.179202) (xy 311.403438 -27.142715)
			(xy 311.455344 -27.112748) (xy 311.510717 -27.089812) (xy 311.56861 -27.074299) (xy 311.628032 -27.066476)
			(xy 311.687968 -27.066476) (xy 311.74739 -27.074299) (xy 311.805283 -27.089812) (xy 311.860656 -27.112748)
			(xy 311.912562 -27.142715) (xy 311.960112 -27.179202) (xy 312.002492 -27.221582) (xy 312.038979 -27.269132)
			(xy 312.068946 -27.321038) (xy 312.091882 -27.376411) (xy 312.107395 -27.434304) (xy 312.115218 -27.493726)
			(xy 312.115708 -27.523694) (xy 312.115218 -27.553662) (xy 312.107395 -27.613084) (xy 312.091882 -27.670977)
			(xy 312.068946 -27.72635) (xy 312.038979 -27.778256) (xy 312.002492 -27.825806) (xy 311.960112 -27.868186)
			(xy 311.912562 -27.904673) (xy 311.860656 -27.93464) (xy 311.805283 -27.957576) (xy 311.74739 -27.973089)
			(xy 311.687968 -27.980912) (xy 311.628032 -27.980912) (xy 311.56861 -27.973089) (xy 311.510717 -27.957576)
			(xy 311.455344 -27.93464) (xy 311.403438 -27.904673) (xy 311.355888 -27.868186) (xy 311.313508 -27.825806)
			(xy 311.277021 -27.778256) (xy 311.247054 -27.72635) (xy 311.224118 -27.670977) (xy 311.208605 -27.613084)
			(xy 311.200782 -27.553662) (xy 199.4408 -27.553662) (xy 199.4408 -28.99689) (xy 311.175382 -28.99689)
			(xy 311.175382 -28.936954) (xy 311.183205 -28.877532) (xy 311.198718 -28.819639) (xy 311.221654 -28.764266)
			(xy 311.251621 -28.71236) (xy 311.288108 -28.66481) (xy 311.330488 -28.62243) (xy 311.378038 -28.585943)
			(xy 311.429944 -28.555976) (xy 311.485317 -28.53304) (xy 311.54321 -28.517527) (xy 311.602632 -28.509704)
			(xy 311.662568 -28.509704) (xy 311.72199 -28.517527) (xy 311.779883 -28.53304) (xy 311.835256 -28.555976)
			(xy 311.887162 -28.585943) (xy 311.934712 -28.62243) (xy 311.977092 -28.66481) (xy 312.013579 -28.71236)
			(xy 312.043546 -28.764266) (xy 312.066482 -28.819639) (xy 312.081995 -28.877532) (xy 312.089818 -28.936954)
			(xy 312.090308 -28.966922) (xy 312.089818 -28.99689) (xy 312.081995 -29.056312) (xy 312.066482 -29.114205)
			(xy 312.043546 -29.169578) (xy 312.013579 -29.221484) (xy 311.977092 -29.269034) (xy 311.934712 -29.311414)
			(xy 311.887162 -29.347901) (xy 311.835256 -29.377868) (xy 311.779883 -29.400804) (xy 311.72199 -29.416317)
			(xy 311.662568 -29.42414) (xy 311.602632 -29.42414) (xy 311.54321 -29.416317) (xy 311.485317 -29.400804)
			(xy 311.429944 -29.377868) (xy 311.378038 -29.347901) (xy 311.330488 -29.311414) (xy 311.288108 -29.269034)
			(xy 311.251621 -29.221484) (xy 311.221654 -29.169578) (xy 311.198718 -29.114205) (xy 311.183205 -29.056312)
			(xy 311.175382 -28.99689) (xy 199.4408 -28.99689) (xy 199.4408 -30.0228) (xy 199.065138 -30.398462)
			(xy 311.175382 -30.398462) (xy 311.175382 -30.338526) (xy 311.183205 -30.279104) (xy 311.198718 -30.221211)
			(xy 311.221654 -30.165838) (xy 311.251621 -30.113932) (xy 311.288108 -30.066382) (xy 311.330488 -30.024002)
			(xy 311.378038 -29.987515) (xy 311.429944 -29.957548) (xy 311.485317 -29.934612) (xy 311.54321 -29.919099)
			(xy 311.602632 -29.911276) (xy 311.662568 -29.911276) (xy 311.72199 -29.919099) (xy 311.779883 -29.934612)
			(xy 311.835256 -29.957548) (xy 311.887162 -29.987515) (xy 311.934712 -30.024002) (xy 311.977092 -30.066382)
			(xy 312.013579 -30.113932) (xy 312.043546 -30.165838) (xy 312.066482 -30.221211) (xy 312.081995 -30.279104)
			(xy 312.089818 -30.338526) (xy 312.090308 -30.368494) (xy 312.089818 -30.398462) (xy 312.081995 -30.457884)
			(xy 312.066482 -30.515777) (xy 312.043546 -30.57115) (xy 312.013579 -30.623056) (xy 311.977092 -30.670606)
			(xy 311.934712 -30.712986) (xy 311.887162 -30.749473) (xy 311.835256 -30.77944) (xy 311.779883 -30.802376)
			(xy 311.72199 -30.817889) (xy 311.662568 -30.825712) (xy 311.602632 -30.825712) (xy 311.54321 -30.817889)
			(xy 311.485317 -30.802376) (xy 311.429944 -30.77944) (xy 311.378038 -30.749473) (xy 311.330488 -30.712986)
			(xy 311.288108 -30.670606) (xy 311.251621 -30.623056) (xy 311.221654 -30.57115) (xy 311.198718 -30.515777)
			(xy 311.183205 -30.457884) (xy 311.175382 -30.398462) (xy 199.065138 -30.398462) (xy 197.963032 -31.500568)
			(xy 309.270382 -31.500568) (xy 309.270382 -31.440632) (xy 309.278205 -31.38121) (xy 309.293718 -31.323317)
			(xy 309.316654 -31.267944) (xy 309.346621 -31.216038) (xy 309.383108 -31.168488) (xy 309.425488 -31.126108)
			(xy 309.473038 -31.089621) (xy 309.524944 -31.059654) (xy 309.580317 -31.036718) (xy 309.63821 -31.021205)
			(xy 309.697632 -31.013382) (xy 309.757568 -31.013382) (xy 309.81699 -31.021205) (xy 309.874883 -31.036718)
			(xy 309.930256 -31.059654) (xy 309.982162 -31.089621) (xy 310.029712 -31.126108) (xy 310.072092 -31.168488)
			(xy 310.108579 -31.216038) (xy 310.138546 -31.267944) (xy 310.159362 -31.3182) (xy 314.298582 -31.3182)
			(xy 314.302653 -31.262578) (xy 314.314779 -31.208141) (xy 314.334702 -31.15605) (xy 314.361998 -31.107415)
			(xy 314.396084 -31.063272) (xy 314.436233 -31.024563) (xy 314.481591 -30.992112) (xy 314.531191 -30.966611)
			(xy 314.583975 -30.948604) (xy 314.638818 -30.938474) (xy 314.694552 -30.936437) (xy 314.749989 -30.942537)
			(xy 314.803946 -30.956643) (xy 314.855275 -30.978455) (xy 314.902881 -31.007509) (xy 314.945749 -31.043184)
			(xy 314.982966 -31.084721) (xy 315.013739 -31.131234) (xy 315.037411 -31.181731) (xy 315.053479 -31.235138)
			(xy 315.061599 -31.290314) (xy 315.062108 -31.3182) (xy 315.061599 -31.346086) (xy 315.053479 -31.401262)
			(xy 315.037411 -31.454669) (xy 315.013739 -31.505166) (xy 314.982966 -31.551679) (xy 314.945749 -31.593216)
			(xy 314.902881 -31.628891) (xy 314.855275 -31.657945) (xy 314.803946 -31.679757) (xy 314.749989 -31.693863)
			(xy 314.694552 -31.699963) (xy 314.638818 -31.697926) (xy 314.583975 -31.687796) (xy 314.531191 -31.669789)
			(xy 314.481591 -31.644288) (xy 314.436233 -31.611837) (xy 314.396084 -31.573128) (xy 314.361998 -31.528985)
			(xy 314.334702 -31.48035) (xy 314.314779 -31.428259) (xy 314.302653 -31.373822) (xy 314.298582 -31.3182)
			(xy 310.159362 -31.3182) (xy 310.161482 -31.323317) (xy 310.176995 -31.38121) (xy 310.184818 -31.440632)
			(xy 310.185308 -31.4706) (xy 310.184818 -31.500568) (xy 310.176995 -31.55999) (xy 310.161482 -31.617883)
			(xy 310.138546 -31.673256) (xy 310.108579 -31.725162) (xy 310.072092 -31.772712) (xy 310.029712 -31.815092)
			(xy 309.982162 -31.851579) (xy 309.930256 -31.881546) (xy 309.874883 -31.904482) (xy 309.81699 -31.919995)
			(xy 309.757568 -31.927818) (xy 309.697632 -31.927818) (xy 309.63821 -31.919995) (xy 309.580317 -31.904482)
			(xy 309.524944 -31.881546) (xy 309.473038 -31.851579) (xy 309.425488 -31.815092) (xy 309.383108 -31.772712)
			(xy 309.346621 -31.725162) (xy 309.316654 -31.673256) (xy 309.293718 -31.617883) (xy 309.278205 -31.55999)
			(xy 309.270382 -31.500568) (xy 197.963032 -31.500568) (xy 197.51421 -31.94939) (xy 197.499176 -31.965057)
			(xy 197.474146 -32.000535) (xy 197.45551 -32.039751) (xy 197.443811 -32.081564) (xy 197.439387 -32.124757)
			(xy 197.442368 -32.168073) (xy 197.452668 -32.210252) (xy 197.469986 -32.250068) (xy 197.493819 -32.286361)
			(xy 197.523473 -32.318075) (xy 197.558085 -32.344289) (xy 197.596649 -32.364239) (xy 197.638043 -32.377344)
			(xy 197.659498 -32.380682) (xy 197.708257 -32.387812) (xy 197.804515 -32.408939) (xy 197.898755 -32.437763)
			(xy 197.990363 -32.474096) (xy 198.078742 -32.517699) (xy 198.163315 -32.56829) (xy 198.17 -32.573061)
			(xy 212.293192 -32.573061) (xy 212.293192 -32.501739) (xy 212.301178 -32.430865) (xy 212.317048 -32.36133)
			(xy 212.340605 -32.29401) (xy 212.37155 -32.229751) (xy 212.409496 -32.16936) (xy 212.453965 -32.113598)
			(xy 212.504398 -32.063165) (xy 212.56016 -32.018696) (xy 212.620551 -31.98075) (xy 212.68481 -31.949805)
			(xy 212.75213 -31.926248) (xy 212.821665 -31.910378) (xy 212.892539 -31.902392) (xy 212.963861 -31.902392)
			(xy 213.034735 -31.910378) (xy 213.10427 -31.926248) (xy 213.17159 -31.949805) (xy 213.235849 -31.98075)
			(xy 213.29624 -32.018696) (xy 213.352002 -32.063165) (xy 213.402435 -32.113598) (xy 213.446904 -32.16936)
			(xy 213.48485 -32.229751) (xy 213.515795 -32.29401) (xy 213.539352 -32.36133) (xy 213.555222 -32.430865)
			(xy 213.563208 -32.501739) (xy 213.563708 -32.5374) (xy 213.563208 -32.573061) (xy 219.913192 -32.573061)
			(xy 219.913192 -32.501739) (xy 219.921178 -32.430865) (xy 219.937048 -32.36133) (xy 219.960605 -32.29401)
			(xy 219.99155 -32.229751) (xy 220.029496 -32.16936) (xy 220.073965 -32.113598) (xy 220.124398 -32.063165)
			(xy 220.18016 -32.018696) (xy 220.240551 -31.98075) (xy 220.30481 -31.949805) (xy 220.37213 -31.926248)
			(xy 220.441665 -31.910378) (xy 220.512539 -31.902392) (xy 220.583861 -31.902392) (xy 220.654735 -31.910378)
			(xy 220.72427 -31.926248) (xy 220.79159 -31.949805) (xy 220.855849 -31.98075) (xy 220.91624 -32.018696)
			(xy 220.972002 -32.063165) (xy 221.022435 -32.113598) (xy 221.066904 -32.16936) (xy 221.10485 -32.229751)
			(xy 221.135795 -32.29401) (xy 221.159352 -32.36133) (xy 221.175222 -32.430865) (xy 221.183208 -32.501739)
			(xy 221.183708 -32.5374) (xy 221.183208 -32.573061) (xy 227.533192 -32.573061) (xy 227.533192 -32.501739)
			(xy 227.541178 -32.430865) (xy 227.557048 -32.36133) (xy 227.580605 -32.29401) (xy 227.61155 -32.229751)
			(xy 227.649496 -32.16936) (xy 227.693965 -32.113598) (xy 227.744398 -32.063165) (xy 227.80016 -32.018696)
			(xy 227.860551 -31.98075) (xy 227.92481 -31.949805) (xy 227.99213 -31.926248) (xy 228.061665 -31.910378)
			(xy 228.132539 -31.902392) (xy 228.203861 -31.902392) (xy 228.274735 -31.910378) (xy 228.34427 -31.926248)
			(xy 228.41159 -31.949805) (xy 228.475849 -31.98075) (xy 228.53624 -32.018696) (xy 228.592002 -32.063165)
			(xy 228.642435 -32.113598) (xy 228.686904 -32.16936) (xy 228.72485 -32.229751) (xy 228.755795 -32.29401)
			(xy 228.779352 -32.36133) (xy 228.795222 -32.430865) (xy 228.803208 -32.501739) (xy 228.803708 -32.5374)
			(xy 228.803208 -32.573061) (xy 235.153192 -32.573061) (xy 235.153192 -32.501739) (xy 235.161178 -32.430865)
			(xy 235.177048 -32.36133) (xy 235.200605 -32.29401) (xy 235.23155 -32.229751) (xy 235.269496 -32.16936)
			(xy 235.313965 -32.113598) (xy 235.364398 -32.063165) (xy 235.42016 -32.018696) (xy 235.480551 -31.98075)
			(xy 235.54481 -31.949805) (xy 235.61213 -31.926248) (xy 235.681665 -31.910378) (xy 235.752539 -31.902392)
			(xy 235.823861 -31.902392) (xy 235.894735 -31.910378) (xy 235.96427 -31.926248) (xy 236.03159 -31.949805)
			(xy 236.095849 -31.98075) (xy 236.15624 -32.018696) (xy 236.212002 -32.063165) (xy 236.262435 -32.113598)
			(xy 236.306904 -32.16936) (xy 236.34485 -32.229751) (xy 236.375795 -32.29401) (xy 236.399352 -32.36133)
			(xy 236.415222 -32.430865) (xy 236.423208 -32.501739) (xy 236.423708 -32.5374) (xy 236.423208 -32.573061)
			(xy 242.773192 -32.573061) (xy 242.773192 -32.501739) (xy 242.781178 -32.430865) (xy 242.797048 -32.36133)
			(xy 242.820605 -32.29401) (xy 242.85155 -32.229751) (xy 242.889496 -32.16936) (xy 242.933965 -32.113598)
			(xy 242.984398 -32.063165) (xy 243.04016 -32.018696) (xy 243.100551 -31.98075) (xy 243.16481 -31.949805)
			(xy 243.23213 -31.926248) (xy 243.301665 -31.910378) (xy 243.372539 -31.902392) (xy 243.443861 -31.902392)
			(xy 243.514735 -31.910378) (xy 243.58427 -31.926248) (xy 243.65159 -31.949805) (xy 243.715849 -31.98075)
			(xy 243.77624 -32.018696) (xy 243.832002 -32.063165) (xy 243.882435 -32.113598) (xy 243.926904 -32.16936)
			(xy 243.96485 -32.229751) (xy 243.995795 -32.29401) (xy 244.019352 -32.36133) (xy 244.035222 -32.430865)
			(xy 244.043208 -32.501739) (xy 244.043708 -32.5374) (xy 244.043208 -32.573061) (xy 250.393192 -32.573061)
			(xy 250.393192 -32.501739) (xy 250.401178 -32.430865) (xy 250.417048 -32.36133) (xy 250.440605 -32.29401)
			(xy 250.47155 -32.229751) (xy 250.509496 -32.16936) (xy 250.553965 -32.113598) (xy 250.604398 -32.063165)
			(xy 250.66016 -32.018696) (xy 250.720551 -31.98075) (xy 250.78481 -31.949805) (xy 250.85213 -31.926248)
			(xy 250.921665 -31.910378) (xy 250.992539 -31.902392) (xy 251.063861 -31.902392) (xy 251.134735 -31.910378)
			(xy 251.20427 -31.926248) (xy 251.27159 -31.949805) (xy 251.335849 -31.98075) (xy 251.39624 -32.018696)
			(xy 251.452002 -32.063165) (xy 251.502435 -32.113598) (xy 251.546904 -32.16936) (xy 251.58485 -32.229751)
			(xy 251.615795 -32.29401) (xy 251.639352 -32.36133) (xy 251.655222 -32.430865) (xy 251.663208 -32.501739)
			(xy 251.663708 -32.5374) (xy 251.663208 -32.573061) (xy 258.013192 -32.573061) (xy 258.013192 -32.501739)
			(xy 258.021178 -32.430865) (xy 258.037048 -32.36133) (xy 258.060605 -32.29401) (xy 258.09155 -32.229751)
			(xy 258.129496 -32.16936) (xy 258.173965 -32.113598) (xy 258.224398 -32.063165) (xy 258.28016 -32.018696)
			(xy 258.340551 -31.98075) (xy 258.40481 -31.949805) (xy 258.47213 -31.926248) (xy 258.541665 -31.910378)
			(xy 258.612539 -31.902392) (xy 258.683861 -31.902392) (xy 258.754735 -31.910378) (xy 258.82427 -31.926248)
			(xy 258.89159 -31.949805) (xy 258.955849 -31.98075) (xy 259.01624 -32.018696) (xy 259.072002 -32.063165)
			(xy 259.122435 -32.113598) (xy 259.166904 -32.16936) (xy 259.20485 -32.229751) (xy 259.235795 -32.29401)
			(xy 259.259352 -32.36133) (xy 259.275222 -32.430865) (xy 259.283208 -32.501739) (xy 259.283708 -32.5374)
			(xy 259.283208 -32.573061) (xy 265.633192 -32.573061) (xy 265.633192 -32.501739) (xy 265.641178 -32.430865)
			(xy 265.657048 -32.36133) (xy 265.680605 -32.29401) (xy 265.71155 -32.229751) (xy 265.749496 -32.16936)
			(xy 265.793965 -32.113598) (xy 265.844398 -32.063165) (xy 265.90016 -32.018696) (xy 265.960551 -31.98075)
			(xy 266.02481 -31.949805) (xy 266.09213 -31.926248) (xy 266.161665 -31.910378) (xy 266.232539 -31.902392)
			(xy 266.303861 -31.902392) (xy 266.374735 -31.910378) (xy 266.44427 -31.926248) (xy 266.51159 -31.949805)
			(xy 266.575849 -31.98075) (xy 266.63624 -32.018696) (xy 266.692002 -32.063165) (xy 266.742435 -32.113598)
			(xy 266.786904 -32.16936) (xy 266.82485 -32.229751) (xy 266.855795 -32.29401) (xy 266.879352 -32.36133)
			(xy 266.895222 -32.430865) (xy 266.903208 -32.501739) (xy 266.903708 -32.5374) (xy 266.903208 -32.573061)
			(xy 273.253192 -32.573061) (xy 273.253192 -32.501739) (xy 273.261178 -32.430865) (xy 273.277048 -32.36133)
			(xy 273.300605 -32.29401) (xy 273.33155 -32.229751) (xy 273.369496 -32.16936) (xy 273.413965 -32.113598)
			(xy 273.464398 -32.063165) (xy 273.52016 -32.018696) (xy 273.580551 -31.98075) (xy 273.64481 -31.949805)
			(xy 273.71213 -31.926248) (xy 273.781665 -31.910378) (xy 273.852539 -31.902392) (xy 273.923861 -31.902392)
			(xy 273.994735 -31.910378) (xy 274.06427 -31.926248) (xy 274.13159 -31.949805) (xy 274.195849 -31.98075)
			(xy 274.25624 -32.018696) (xy 274.312002 -32.063165) (xy 274.362435 -32.113598) (xy 274.406904 -32.16936)
			(xy 274.44485 -32.229751) (xy 274.475795 -32.29401) (xy 274.499352 -32.36133) (xy 274.515222 -32.430865)
			(xy 274.523208 -32.501739) (xy 274.523708 -32.5374) (xy 274.523208 -32.573061) (xy 280.873192 -32.573061)
			(xy 280.873192 -32.501739) (xy 280.881178 -32.430865) (xy 280.897048 -32.36133) (xy 280.920605 -32.29401)
			(xy 280.95155 -32.229751) (xy 280.989496 -32.16936) (xy 281.033965 -32.113598) (xy 281.084398 -32.063165)
			(xy 281.14016 -32.018696) (xy 281.200551 -31.98075) (xy 281.26481 -31.949805) (xy 281.33213 -31.926248)
			(xy 281.401665 -31.910378) (xy 281.472539 -31.902392) (xy 281.543861 -31.902392) (xy 281.614735 -31.910378)
			(xy 281.68427 -31.926248) (xy 281.75159 -31.949805) (xy 281.815849 -31.98075) (xy 281.87624 -32.018696)
			(xy 281.932002 -32.063165) (xy 281.982435 -32.113598) (xy 282.026904 -32.16936) (xy 282.06485 -32.229751)
			(xy 282.095795 -32.29401) (xy 282.119352 -32.36133) (xy 282.135222 -32.430865) (xy 282.143208 -32.501739)
			(xy 282.143708 -32.5374) (xy 282.143208 -32.573061) (xy 282.135222 -32.643935) (xy 282.119352 -32.71347)
			(xy 282.095795 -32.78079) (xy 282.06485 -32.845049) (xy 282.03185 -32.897568) (xy 309.321182 -32.897568)
			(xy 309.321182 -32.837632) (xy 309.329005 -32.77821) (xy 309.344518 -32.720317) (xy 309.367454 -32.664944)
			(xy 309.397421 -32.613038) (xy 309.433908 -32.565488) (xy 309.476288 -32.523108) (xy 309.523838 -32.486621)
			(xy 309.575744 -32.456654) (xy 309.631117 -32.433718) (xy 309.68901 -32.418205) (xy 309.748432 -32.410382)
			(xy 309.808368 -32.410382) (xy 309.86779 -32.418205) (xy 309.925683 -32.433718) (xy 309.981056 -32.456654)
			(xy 310.032962 -32.486621) (xy 310.071989 -32.516568) (xy 314.020182 -32.516568) (xy 314.020182 -32.456632)
			(xy 314.028005 -32.39721) (xy 314.043518 -32.339317) (xy 314.066454 -32.283944) (xy 314.096421 -32.232038)
			(xy 314.132908 -32.184488) (xy 314.175288 -32.142108) (xy 314.222838 -32.105621) (xy 314.274744 -32.075654)
			(xy 314.330117 -32.052718) (xy 314.38801 -32.037205) (xy 314.447432 -32.029382) (xy 314.507368 -32.029382)
			(xy 314.56679 -32.037205) (xy 314.624683 -32.052718) (xy 314.680056 -32.075654) (xy 314.731962 -32.105621)
			(xy 314.779512 -32.142108) (xy 314.821892 -32.184488) (xy 314.858379 -32.232038) (xy 314.888346 -32.283944)
			(xy 314.911282 -32.339317) (xy 314.926795 -32.39721) (xy 314.934618 -32.456632) (xy 314.935108 -32.4866)
			(xy 314.934618 -32.516568) (xy 314.926795 -32.57599) (xy 314.911282 -32.633883) (xy 314.888346 -32.689256)
			(xy 314.858379 -32.741162) (xy 314.821892 -32.788712) (xy 314.779512 -32.831092) (xy 314.731962 -32.867579)
			(xy 314.680056 -32.897546) (xy 314.624683 -32.920482) (xy 314.56679 -32.935995) (xy 314.507368 -32.943818)
			(xy 314.447432 -32.943818) (xy 314.38801 -32.935995) (xy 314.330117 -32.920482) (xy 314.274744 -32.897546)
			(xy 314.222838 -32.867579) (xy 314.175288 -32.831092) (xy 314.132908 -32.788712) (xy 314.096421 -32.741162)
			(xy 314.066454 -32.689256) (xy 314.043518 -32.633883) (xy 314.028005 -32.57599) (xy 314.020182 -32.516568)
			(xy 310.071989 -32.516568) (xy 310.080512 -32.523108) (xy 310.122892 -32.565488) (xy 310.159379 -32.613038)
			(xy 310.189346 -32.664944) (xy 310.212282 -32.720317) (xy 310.227795 -32.77821) (xy 310.235618 -32.837632)
			(xy 310.236108 -32.8676) (xy 310.235618 -32.897568) (xy 310.227795 -32.95699) (xy 310.212282 -33.014883)
			(xy 310.189346 -33.070256) (xy 310.159379 -33.122162) (xy 310.122892 -33.169712) (xy 310.080512 -33.212092)
			(xy 310.032962 -33.248579) (xy 309.981056 -33.278546) (xy 309.925683 -33.301482) (xy 309.86779 -33.316995)
			(xy 309.808368 -33.324818) (xy 309.748432 -33.324818) (xy 309.68901 -33.316995) (xy 309.631117 -33.301482)
			(xy 309.575744 -33.278546) (xy 309.523838 -33.248579) (xy 309.476288 -33.212092) (xy 309.433908 -33.169712)
			(xy 309.397421 -33.122162) (xy 309.367454 -33.070256) (xy 309.344518 -33.014883) (xy 309.329005 -32.95699)
			(xy 309.321182 -32.897568) (xy 282.03185 -32.897568) (xy 282.026904 -32.90544) (xy 281.982435 -32.961202)
			(xy 281.932002 -33.011635) (xy 281.87624 -33.056104) (xy 281.815849 -33.09405) (xy 281.75159 -33.124995)
			(xy 281.68427 -33.148552) (xy 281.614735 -33.164422) (xy 281.543861 -33.172408) (xy 281.472539 -33.172408)
			(xy 281.401665 -33.164422) (xy 281.33213 -33.148552) (xy 281.26481 -33.124995) (xy 281.200551 -33.09405)
			(xy 281.14016 -33.056104) (xy 281.084398 -33.011635) (xy 281.033965 -32.961202) (xy 280.989496 -32.90544)
			(xy 280.95155 -32.845049) (xy 280.920605 -32.78079) (xy 280.897048 -32.71347) (xy 280.881178 -32.643935)
			(xy 280.873192 -32.573061) (xy 274.523208 -32.573061) (xy 274.515222 -32.643935) (xy 274.499352 -32.71347)
			(xy 274.475795 -32.78079) (xy 274.44485 -32.845049) (xy 274.406904 -32.90544) (xy 274.362435 -32.961202)
			(xy 274.312002 -33.011635) (xy 274.25624 -33.056104) (xy 274.195849 -33.09405) (xy 274.13159 -33.124995)
			(xy 274.06427 -33.148552) (xy 273.994735 -33.164422) (xy 273.923861 -33.172408) (xy 273.852539 -33.172408)
			(xy 273.781665 -33.164422) (xy 273.71213 -33.148552) (xy 273.64481 -33.124995) (xy 273.580551 -33.09405)
			(xy 273.52016 -33.056104) (xy 273.464398 -33.011635) (xy 273.413965 -32.961202) (xy 273.369496 -32.90544)
			(xy 273.33155 -32.845049) (xy 273.300605 -32.78079) (xy 273.277048 -32.71347) (xy 273.261178 -32.643935)
			(xy 273.253192 -32.573061) (xy 266.903208 -32.573061) (xy 266.895222 -32.643935) (xy 266.879352 -32.71347)
			(xy 266.855795 -32.78079) (xy 266.82485 -32.845049) (xy 266.786904 -32.90544) (xy 266.742435 -32.961202)
			(xy 266.692002 -33.011635) (xy 266.63624 -33.056104) (xy 266.575849 -33.09405) (xy 266.51159 -33.124995)
			(xy 266.44427 -33.148552) (xy 266.374735 -33.164422) (xy 266.303861 -33.172408) (xy 266.232539 -33.172408)
			(xy 266.161665 -33.164422) (xy 266.09213 -33.148552) (xy 266.02481 -33.124995) (xy 265.960551 -33.09405)
			(xy 265.90016 -33.056104) (xy 265.844398 -33.011635) (xy 265.793965 -32.961202) (xy 265.749496 -32.90544)
			(xy 265.71155 -32.845049) (xy 265.680605 -32.78079) (xy 265.657048 -32.71347) (xy 265.641178 -32.643935)
			(xy 265.633192 -32.573061) (xy 259.283208 -32.573061) (xy 259.275222 -32.643935) (xy 259.259352 -32.71347)
			(xy 259.235795 -32.78079) (xy 259.20485 -32.845049) (xy 259.166904 -32.90544) (xy 259.122435 -32.961202)
			(xy 259.072002 -33.011635) (xy 259.01624 -33.056104) (xy 258.955849 -33.09405) (xy 258.89159 -33.124995)
			(xy 258.82427 -33.148552) (xy 258.754735 -33.164422) (xy 258.683861 -33.172408) (xy 258.612539 -33.172408)
			(xy 258.541665 -33.164422) (xy 258.47213 -33.148552) (xy 258.40481 -33.124995) (xy 258.340551 -33.09405)
			(xy 258.28016 -33.056104) (xy 258.224398 -33.011635) (xy 258.173965 -32.961202) (xy 258.129496 -32.90544)
			(xy 258.09155 -32.845049) (xy 258.060605 -32.78079) (xy 258.037048 -32.71347) (xy 258.021178 -32.643935)
			(xy 258.013192 -32.573061) (xy 251.663208 -32.573061) (xy 251.655222 -32.643935) (xy 251.639352 -32.71347)
			(xy 251.615795 -32.78079) (xy 251.58485 -32.845049) (xy 251.546904 -32.90544) (xy 251.502435 -32.961202)
			(xy 251.452002 -33.011635) (xy 251.39624 -33.056104) (xy 251.335849 -33.09405) (xy 251.27159 -33.124995)
			(xy 251.20427 -33.148552) (xy 251.134735 -33.164422) (xy 251.063861 -33.172408) (xy 250.992539 -33.172408)
			(xy 250.921665 -33.164422) (xy 250.85213 -33.148552) (xy 250.78481 -33.124995) (xy 250.720551 -33.09405)
			(xy 250.66016 -33.056104) (xy 250.604398 -33.011635) (xy 250.553965 -32.961202) (xy 250.509496 -32.90544)
			(xy 250.47155 -32.845049) (xy 250.440605 -32.78079) (xy 250.417048 -32.71347) (xy 250.401178 -32.643935)
			(xy 250.393192 -32.573061) (xy 244.043208 -32.573061) (xy 244.035222 -32.643935) (xy 244.019352 -32.71347)
			(xy 243.995795 -32.78079) (xy 243.96485 -32.845049) (xy 243.926904 -32.90544) (xy 243.882435 -32.961202)
			(xy 243.832002 -33.011635) (xy 243.77624 -33.056104) (xy 243.715849 -33.09405) (xy 243.65159 -33.124995)
			(xy 243.58427 -33.148552) (xy 243.514735 -33.164422) (xy 243.443861 -33.172408) (xy 243.372539 -33.172408)
			(xy 243.301665 -33.164422) (xy 243.23213 -33.148552) (xy 243.16481 -33.124995) (xy 243.100551 -33.09405)
			(xy 243.04016 -33.056104) (xy 242.984398 -33.011635) (xy 242.933965 -32.961202) (xy 242.889496 -32.90544)
			(xy 242.85155 -32.845049) (xy 242.820605 -32.78079) (xy 242.797048 -32.71347) (xy 242.781178 -32.643935)
			(xy 242.773192 -32.573061) (xy 236.423208 -32.573061) (xy 236.415222 -32.643935) (xy 236.399352 -32.71347)
			(xy 236.375795 -32.78079) (xy 236.34485 -32.845049) (xy 236.306904 -32.90544) (xy 236.262435 -32.961202)
			(xy 236.212002 -33.011635) (xy 236.15624 -33.056104) (xy 236.095849 -33.09405) (xy 236.03159 -33.124995)
			(xy 235.96427 -33.148552) (xy 235.894735 -33.164422) (xy 235.823861 -33.172408) (xy 235.752539 -33.172408)
			(xy 235.681665 -33.164422) (xy 235.61213 -33.148552) (xy 235.54481 -33.124995) (xy 235.480551 -33.09405)
			(xy 235.42016 -33.056104) (xy 235.364398 -33.011635) (xy 235.313965 -32.961202) (xy 235.269496 -32.90544)
			(xy 235.23155 -32.845049) (xy 235.200605 -32.78079) (xy 235.177048 -32.71347) (xy 235.161178 -32.643935)
			(xy 235.153192 -32.573061) (xy 228.803208 -32.573061) (xy 228.795222 -32.643935) (xy 228.779352 -32.71347)
			(xy 228.755795 -32.78079) (xy 228.72485 -32.845049) (xy 228.686904 -32.90544) (xy 228.642435 -32.961202)
			(xy 228.592002 -33.011635) (xy 228.53624 -33.056104) (xy 228.475849 -33.09405) (xy 228.41159 -33.124995)
			(xy 228.34427 -33.148552) (xy 228.274735 -33.164422) (xy 228.203861 -33.172408) (xy 228.132539 -33.172408)
			(xy 228.061665 -33.164422) (xy 227.99213 -33.148552) (xy 227.92481 -33.124995) (xy 227.860551 -33.09405)
			(xy 227.80016 -33.056104) (xy 227.744398 -33.011635) (xy 227.693965 -32.961202) (xy 227.649496 -32.90544)
			(xy 227.61155 -32.845049) (xy 227.580605 -32.78079) (xy 227.557048 -32.71347) (xy 227.541178 -32.643935)
			(xy 227.533192 -32.573061) (xy 221.183208 -32.573061) (xy 221.175222 -32.643935) (xy 221.159352 -32.71347)
			(xy 221.135795 -32.78079) (xy 221.10485 -32.845049) (xy 221.066904 -32.90544) (xy 221.022435 -32.961202)
			(xy 220.972002 -33.011635) (xy 220.91624 -33.056104) (xy 220.855849 -33.09405) (xy 220.79159 -33.124995)
			(xy 220.72427 -33.148552) (xy 220.654735 -33.164422) (xy 220.583861 -33.172408) (xy 220.512539 -33.172408)
			(xy 220.441665 -33.164422) (xy 220.37213 -33.148552) (xy 220.30481 -33.124995) (xy 220.240551 -33.09405)
			(xy 220.18016 -33.056104) (xy 220.124398 -33.011635) (xy 220.073965 -32.961202) (xy 220.029496 -32.90544)
			(xy 219.99155 -32.845049) (xy 219.960605 -32.78079) (xy 219.937048 -32.71347) (xy 219.921178 -32.643935)
			(xy 219.913192 -32.573061) (xy 213.563208 -32.573061) (xy 213.555222 -32.643935) (xy 213.539352 -32.71347)
			(xy 213.515795 -32.78079) (xy 213.48485 -32.845049) (xy 213.446904 -32.90544) (xy 213.402435 -32.961202)
			(xy 213.352002 -33.011635) (xy 213.29624 -33.056104) (xy 213.235849 -33.09405) (xy 213.17159 -33.124995)
			(xy 213.10427 -33.148552) (xy 213.034735 -33.164422) (xy 212.963861 -33.172408) (xy 212.892539 -33.172408)
			(xy 212.821665 -33.164422) (xy 212.75213 -33.148552) (xy 212.68481 -33.124995) (xy 212.620551 -33.09405)
			(xy 212.56016 -33.056104) (xy 212.504398 -33.011635) (xy 212.453965 -32.961202) (xy 212.409496 -32.90544)
			(xy 212.37155 -32.845049) (xy 212.340605 -32.78079) (xy 212.317048 -32.71347) (xy 212.301178 -32.643935)
			(xy 212.293192 -32.573061) (xy 198.17 -32.573061) (xy 198.243532 -32.625538) (xy 198.318869 -32.689071)
			(xy 198.388835 -32.758474) (xy 198.452975 -32.833294) (xy 198.51087 -32.913045) (xy 198.562143 -32.997206)
			(xy 198.60646 -33.085229) (xy 198.643532 -33.17654) (xy 198.673118 -33.270544) (xy 198.695023 -33.366629)
			(xy 198.709107 -33.464167) (xy 198.715276 -33.562523) (xy 198.713491 -33.661057) (xy 198.703764 -33.759125)
			(xy 198.686157 -33.85609) (xy 198.660786 -33.951317) (xy 198.627815 -34.044188) (xy 198.587461 -34.134097)
			(xy 198.539985 -34.220457) (xy 198.485697 -34.302706) (xy 198.424952 -34.380308) (xy 198.358144 -34.452756)
			(xy 198.28571 -34.51958) (xy 198.208122 -34.580342) (xy 198.125884 -34.634648) (xy 198.039534 -34.682142)
			(xy 197.949635 -34.722517) (xy 197.856771 -34.755507) (xy 197.761549 -34.780899) (xy 197.664588 -34.798527)
			(xy 197.566522 -34.808276) (xy 197.467989 -34.810082) (xy 197.369631 -34.803934) (xy 197.27209 -34.789872)
			(xy 197.176001 -34.767987) (xy 197.08199 -34.738422) (xy 196.990671 -34.70137) (xy 196.902638 -34.657072)
			(xy 196.818466 -34.605817) (xy 196.738703 -34.547939) (xy 196.663868 -34.483816) (xy 196.59445 -34.413864)
			(xy 196.530901 -34.338541) (xy 196.473635 -34.258337) (xy 196.423026 -34.173775) (xy 196.379403 -34.085406)
			(xy 196.343051 -33.993806) (xy 196.314207 -33.899572) (xy 196.293058 -33.803318) (xy 196.285866 -33.754568)
			(xy 196.282516 -33.733106) (xy 196.269459 -33.691679) (xy 196.249546 -33.653077) (xy 196.223358 -33.618424)
			(xy 196.191657 -33.58873) (xy 196.155367 -33.564861) (xy 196.115547 -33.547512) (xy 196.073356 -33.537189)
			(xy 196.030024 -33.534193) (xy 195.986813 -33.53861) (xy 195.944984 -33.550312) (xy 195.905754 -33.568959)
			(xy 195.870268 -33.594006) (xy 195.854574 -33.609026) (xy 194.3354 -35.1282) (xy 165.1762 -35.1282)
			(xy 164.172646 -34.124646) (xy 164.172646 -27.901646) (xy 157.9118 -21.6408) (xy 143.713708 -21.6408)
			(xy 143.690256 -21.641338) (xy 143.644148 -21.649943) (xy 143.600401 -21.666861) (xy 143.560502 -21.691519)
			(xy 143.525804 -21.72308) (xy 143.497486 -21.760471) (xy 143.47651 -21.802423) (xy 143.463587 -21.847512)
			(xy 143.459157 -21.894207) (xy 143.463369 -21.940921) (xy 143.476082 -21.98607) (xy 143.496862 -22.028119)
			(xy 143.510508 -22.0472) (xy 143.526468 -22.069288) (xy 143.552589 -22.117114) (xy 143.571637 -22.16817)
			(xy 143.583225 -22.221417) (xy 143.587117 -22.275772) (xy 143.583233 -22.330127) (xy 143.571653 -22.383376)
			(xy 143.552612 -22.434435) (xy 143.526498 -22.482265) (xy 143.493843 -22.525891) (xy 143.455312 -22.564425)
			(xy 143.411688 -22.597083) (xy 143.363861 -22.6232) (xy 143.312803 -22.642245) (xy 143.259555 -22.653829)
			(xy 143.2052 -22.657717) (xy 143.150845 -22.653829) (xy 143.097597 -22.642245) (xy 143.046539 -22.6232)
			(xy 142.998712 -22.597083) (xy 142.955088 -22.564425) (xy 142.916557 -22.525891) (xy 142.883902 -22.482265)
			(xy 142.857788 -22.434435) (xy 142.838747 -22.383376) (xy 142.827167 -22.330127) (xy 142.823283 -22.275772)
			(xy 142.827175 -22.221417) (xy 142.838763 -22.16817) (xy 142.857811 -22.117114) (xy 142.883932 -22.069288)
			(xy 142.899892 -22.0472) (xy 142.913532 -22.028116) (xy 142.934312 -21.986067) (xy 142.947024 -21.94092)
			(xy 142.951237 -21.894207) (xy 142.946807 -21.847513) (xy 142.933884 -21.802426) (xy 142.912908 -21.760474)
			(xy 142.884591 -21.723084) (xy 142.849894 -21.691525) (xy 142.809996 -21.666867) (xy 142.76625 -21.649949)
			(xy 142.720143 -21.641344) (xy 142.696692 -21.6408) (xy 134.493 -21.6408) (xy 133.4262 -22.7076)
			(xy 139.108178 -22.7076) (xy 139.112249 -22.651978) (xy 139.124375 -22.597541) (xy 139.144298 -22.54545)
			(xy 139.171594 -22.496815) (xy 139.20568 -22.452672) (xy 139.245829 -22.413963) (xy 139.291187 -22.381512)
			(xy 139.340787 -22.356011) (xy 139.393571 -22.338004) (xy 139.448414 -22.327874) (xy 139.504148 -22.325837)
			(xy 139.559585 -22.331937) (xy 139.613542 -22.346043) (xy 139.664871 -22.367855) (xy 139.712477 -22.396909)
			(xy 139.755345 -22.432584) (xy 139.792562 -22.474121) (xy 139.823335 -22.520634) (xy 139.847007 -22.571131)
			(xy 139.863075 -22.624538) (xy 139.871195 -22.679714) (xy 139.871704 -22.7076) (xy 139.871195 -22.735486)
			(xy 139.863075 -22.790662) (xy 139.847007 -22.844069) (xy 139.823335 -22.894566) (xy 139.799994 -22.929846)
			(xy 155.727382 -22.929846) (xy 155.727382 -22.86991) (xy 155.735205 -22.810488) (xy 155.750718 -22.752595)
			(xy 155.773654 -22.697222) (xy 155.803621 -22.645316) (xy 155.840108 -22.597766) (xy 155.882488 -22.555386)
			(xy 155.930038 -22.518899) (xy 155.981944 -22.488932) (xy 156.037317 -22.465996) (xy 156.09521 -22.450483)
			(xy 156.154632 -22.44266) (xy 156.214568 -22.44266) (xy 156.27399 -22.450483) (xy 156.331883 -22.465996)
			(xy 156.387256 -22.488932) (xy 156.439162 -22.518899) (xy 156.486712 -22.555386) (xy 156.529092 -22.597766)
			(xy 156.565579 -22.645316) (xy 156.595546 -22.697222) (xy 156.618482 -22.752595) (xy 156.633995 -22.810488)
			(xy 156.641818 -22.86991) (xy 156.642308 -22.899878) (xy 156.641818 -22.929846) (xy 156.633995 -22.989268)
			(xy 156.618482 -23.047161) (xy 156.595546 -23.102534) (xy 156.565579 -23.15444) (xy 156.529092 -23.20199)
			(xy 156.486712 -23.24437) (xy 156.439162 -23.280857) (xy 156.387256 -23.310824) (xy 156.331883 -23.33376)
			(xy 156.27399 -23.349273) (xy 156.214568 -23.357096) (xy 156.154632 -23.357096) (xy 156.09521 -23.349273)
			(xy 156.037317 -23.33376) (xy 155.981944 -23.310824) (xy 155.930038 -23.280857) (xy 155.882488 -23.24437)
			(xy 155.840108 -23.20199) (xy 155.803621 -23.15444) (xy 155.773654 -23.102534) (xy 155.750718 -23.047161)
			(xy 155.735205 -22.989268) (xy 155.727382 -22.929846) (xy 139.799994 -22.929846) (xy 139.792562 -22.941079)
			(xy 139.755345 -22.982616) (xy 139.712477 -23.018291) (xy 139.664871 -23.047345) (xy 139.613542 -23.069157)
			(xy 139.559585 -23.083263) (xy 139.504148 -23.089363) (xy 139.448414 -23.087326) (xy 139.393571 -23.077196)
			(xy 139.340787 -23.059189) (xy 139.291187 -23.033688) (xy 139.245829 -23.001237) (xy 139.20568 -22.962528)
			(xy 139.171594 -22.918385) (xy 139.144298 -22.86975) (xy 139.124375 -22.817659) (xy 139.112249 -22.763222)
			(xy 139.108178 -22.7076) (xy 133.4262 -22.7076) (xy 132.28955 -23.84425) (xy 132.273172 -23.861382)
			(xy 132.24646 -23.900527) (xy 132.227463 -23.943943) (xy 132.216837 -23.990127) (xy 132.21495 -24.03748)
			(xy 132.221868 -24.084363) (xy 132.237351 -24.129153) (xy 132.260864 -24.170299) (xy 132.275834 -24.188674)
			(xy 132.294987 -24.211871) (xy 132.327684 -24.262365) (xy 132.353483 -24.316709) (xy 132.37194 -24.373963)
			(xy 132.373771 -24.384) (xy 153.135582 -24.384) (xy 153.139653 -24.328378) (xy 153.151779 -24.273941)
			(xy 153.171702 -24.22185) (xy 153.198998 -24.173215) (xy 153.233084 -24.129072) (xy 153.273233 -24.090363)
			(xy 153.318591 -24.057912) (xy 153.368191 -24.032411) (xy 153.420975 -24.014404) (xy 153.475818 -24.004274)
			(xy 153.531552 -24.002237) (xy 153.586989 -24.008337) (xy 153.640946 -24.022443) (xy 153.692275 -24.044255)
			(xy 153.739881 -24.073309) (xy 153.782749 -24.108984) (xy 153.819966 -24.150521) (xy 153.849575 -24.195274)
			(xy 155.905182 -24.195274) (xy 155.905182 -24.135338) (xy 155.913005 -24.075916) (xy 155.928518 -24.018023)
			(xy 155.951454 -23.96265) (xy 155.981421 -23.910744) (xy 156.017908 -23.863194) (xy 156.060288 -23.820814)
			(xy 156.107838 -23.784327) (xy 156.159744 -23.75436) (xy 156.215117 -23.731424) (xy 156.27301 -23.715911)
			(xy 156.332432 -23.708088) (xy 156.392368 -23.708088) (xy 156.45179 -23.715911) (xy 156.509683 -23.731424)
			(xy 156.565056 -23.75436) (xy 156.616962 -23.784327) (xy 156.664512 -23.820814) (xy 156.706892 -23.863194)
			(xy 156.743379 -23.910744) (xy 156.773346 -23.96265) (xy 156.796282 -24.018023) (xy 156.811795 -24.075916)
			(xy 156.819618 -24.135338) (xy 156.820108 -24.165306) (xy 156.819618 -24.195274) (xy 156.811795 -24.254696)
			(xy 156.796282 -24.312589) (xy 156.773346 -24.367962) (xy 156.743379 -24.419868) (xy 156.706892 -24.467418)
			(xy 156.664512 -24.509798) (xy 156.616962 -24.546285) (xy 156.565056 -24.576252) (xy 156.509683 -24.599188)
			(xy 156.45179 -24.614701) (xy 156.392368 -24.622524) (xy 156.332432 -24.622524) (xy 156.27301 -24.614701)
			(xy 156.215117 -24.599188) (xy 156.159744 -24.576252) (xy 156.107838 -24.546285) (xy 156.060288 -24.509798)
			(xy 156.017908 -24.467418) (xy 155.981421 -24.419868) (xy 155.951454 -24.367962) (xy 155.928518 -24.312589)
			(xy 155.913005 -24.254696) (xy 155.905182 -24.195274) (xy 153.849575 -24.195274) (xy 153.850739 -24.197034)
			(xy 153.874411 -24.247531) (xy 153.890479 -24.300938) (xy 153.898599 -24.356114) (xy 153.899108 -24.384)
			(xy 153.898599 -24.411886) (xy 153.890479 -24.467062) (xy 153.874411 -24.520469) (xy 153.850739 -24.570966)
			(xy 153.819966 -24.617479) (xy 153.782749 -24.659016) (xy 153.739881 -24.694691) (xy 153.692275 -24.723745)
			(xy 153.640946 -24.745557) (xy 153.586989 -24.759663) (xy 153.531552 -24.765763) (xy 153.475818 -24.763726)
			(xy 153.420975 -24.753596) (xy 153.368191 -24.735589) (xy 153.318591 -24.710088) (xy 153.273233 -24.677637)
			(xy 153.233084 -24.638928) (xy 153.198998 -24.594785) (xy 153.171702 -24.54615) (xy 153.151779 -24.494059)
			(xy 153.139653 -24.439622) (xy 153.135582 -24.384) (xy 132.373771 -24.384) (xy 132.382736 -24.433143)
			(xy 132.385686 -24.493227) (xy 132.380738 -24.55318) (xy 132.367977 -24.611967) (xy 132.347625 -24.668576)
			(xy 132.32003 -24.72203) (xy 132.285671 -24.771408) (xy 132.245137 -24.815859) (xy 132.19913 -24.854615)
			(xy 132.148441 -24.88701) (xy 132.093944 -24.912484) (xy 132.03658 -24.930599) (xy 131.977337 -24.941042)
			(xy 131.917237 -24.943632) (xy 131.857315 -24.938326) (xy 131.798605 -24.925215) (xy 131.742118 -24.904524)
			(xy 131.715256 -24.890984) (xy 131.695784 -24.881289) (xy 131.65438 -24.867963) (xy 131.611312 -24.861883)
			(xy 131.567837 -24.863226) (xy 131.525226 -24.871951) (xy 131.484723 -24.887805) (xy 131.447511 -24.910325)
			(xy 131.414678 -24.938852) (xy 131.387181 -24.972553) (xy 131.365825 -25.010445) (xy 131.351233 -25.051419)
			(xy 131.343831 -25.09428) (xy 131.3434 -25.116028) (xy 131.3434 -25.252168) (xy 133.070582 -25.252168)
			(xy 133.070582 -25.192232) (xy 133.078405 -25.13281) (xy 133.093918 -25.074917) (xy 133.116854 -25.019544)
			(xy 133.146821 -24.967638) (xy 133.183308 -24.920088) (xy 133.225688 -24.877708) (xy 133.273238 -24.841221)
			(xy 133.325144 -24.811254) (xy 133.380517 -24.788318) (xy 133.43841 -24.772805) (xy 133.497832 -24.764982)
			(xy 133.557768 -24.764982) (xy 133.61719 -24.772805) (xy 133.675083 -24.788318) (xy 133.730456 -24.811254)
			(xy 133.782362 -24.841221) (xy 133.829912 -24.877708) (xy 133.872292 -24.920088) (xy 133.908779 -24.967638)
			(xy 133.938746 -25.019544) (xy 133.961682 -25.074917) (xy 133.977195 -25.13281) (xy 133.985018 -25.192232)
			(xy 133.985508 -25.2222) (xy 133.985018 -25.252168) (xy 133.977195 -25.31159) (xy 133.961682 -25.369483)
			(xy 133.938746 -25.424856) (xy 133.912772 -25.469846) (xy 155.879782 -25.469846) (xy 155.879782 -25.40991)
			(xy 155.887605 -25.350488) (xy 155.903118 -25.292595) (xy 155.926054 -25.237222) (xy 155.956021 -25.185316)
			(xy 155.992508 -25.137766) (xy 156.034888 -25.095386) (xy 156.082438 -25.058899) (xy 156.134344 -25.028932)
			(xy 156.189717 -25.005996) (xy 156.24761 -24.990483) (xy 156.307032 -24.98266) (xy 156.366968 -24.98266)
			(xy 156.42639 -24.990483) (xy 156.484283 -25.005996) (xy 156.539656 -25.028932) (xy 156.591562 -25.058899)
			(xy 156.639112 -25.095386) (xy 156.681492 -25.137766) (xy 156.717979 -25.185316) (xy 156.747946 -25.237222)
			(xy 156.770882 -25.292595) (xy 156.786395 -25.350488) (xy 156.794218 -25.40991) (xy 156.794708 -25.439878)
			(xy 156.794218 -25.469846) (xy 156.786395 -25.529268) (xy 156.770882 -25.587161) (xy 156.747946 -25.642534)
			(xy 156.717979 -25.69444) (xy 156.681492 -25.74199) (xy 156.639112 -25.78437) (xy 156.591562 -25.820857)
			(xy 156.539656 -25.850824) (xy 156.484283 -25.87376) (xy 156.42639 -25.889273) (xy 156.366968 -25.897096)
			(xy 156.307032 -25.897096) (xy 156.24761 -25.889273) (xy 156.189717 -25.87376) (xy 156.134344 -25.850824)
			(xy 156.082438 -25.820857) (xy 156.034888 -25.78437) (xy 155.992508 -25.74199) (xy 155.956021 -25.69444)
			(xy 155.926054 -25.642534) (xy 155.903118 -25.587161) (xy 155.887605 -25.529268) (xy 155.879782 -25.469846)
			(xy 133.912772 -25.469846) (xy 133.908779 -25.476762) (xy 133.872292 -25.524312) (xy 133.829912 -25.566692)
			(xy 133.782362 -25.603179) (xy 133.730456 -25.633146) (xy 133.675083 -25.656082) (xy 133.61719 -25.671595)
			(xy 133.557768 -25.679418) (xy 133.497832 -25.679418) (xy 133.43841 -25.671595) (xy 133.380517 -25.656082)
			(xy 133.325144 -25.633146) (xy 133.273238 -25.603179) (xy 133.225688 -25.566692) (xy 133.183308 -25.524312)
			(xy 133.146821 -25.476762) (xy 133.116854 -25.424856) (xy 133.093918 -25.369483) (xy 133.078405 -25.31159)
			(xy 133.070582 -25.252168) (xy 131.3434 -25.252168) (xy 131.3434 -26.739846) (xy 155.879782 -26.739846)
			(xy 155.879782 -26.67991) (xy 155.887605 -26.620488) (xy 155.903118 -26.562595) (xy 155.926054 -26.507222)
			(xy 155.956021 -26.455316) (xy 155.992508 -26.407766) (xy 156.034888 -26.365386) (xy 156.082438 -26.328899)
			(xy 156.134344 -26.298932) (xy 156.189717 -26.275996) (xy 156.24761 -26.260483) (xy 156.307032 -26.25266)
			(xy 156.366968 -26.25266) (xy 156.42639 -26.260483) (xy 156.484283 -26.275996) (xy 156.539656 -26.298932)
			(xy 156.591562 -26.328899) (xy 156.639112 -26.365386) (xy 156.681492 -26.407766) (xy 156.717979 -26.455316)
			(xy 156.747946 -26.507222) (xy 156.770882 -26.562595) (xy 156.786395 -26.620488) (xy 156.794218 -26.67991)
			(xy 156.794708 -26.709878) (xy 156.794218 -26.739846) (xy 156.786395 -26.799268) (xy 156.770882 -26.857161)
			(xy 156.747946 -26.912534) (xy 156.717979 -26.96444) (xy 156.681492 -27.01199) (xy 156.639112 -27.05437)
			(xy 156.591562 -27.090857) (xy 156.539656 -27.120824) (xy 156.484283 -27.14376) (xy 156.42639 -27.159273)
			(xy 156.366968 -27.167096) (xy 156.307032 -27.167096) (xy 156.24761 -27.159273) (xy 156.189717 -27.14376)
			(xy 156.134344 -27.120824) (xy 156.082438 -27.090857) (xy 156.034888 -27.05437) (xy 155.992508 -27.01199)
			(xy 155.956021 -26.96444) (xy 155.926054 -26.912534) (xy 155.903118 -26.857161) (xy 155.887605 -26.799268)
			(xy 155.879782 -26.739846) (xy 131.3434 -26.739846) (xy 131.3434 -27.309568) (xy 153.009582 -27.309568)
			(xy 153.009582 -27.249632) (xy 153.017405 -27.19021) (xy 153.032918 -27.132317) (xy 153.055854 -27.076944)
			(xy 153.085821 -27.025038) (xy 153.122308 -26.977488) (xy 153.164688 -26.935108) (xy 153.212238 -26.898621)
			(xy 153.264144 -26.868654) (xy 153.319517 -26.845718) (xy 153.37741 -26.830205) (xy 153.436832 -26.822382)
			(xy 153.496768 -26.822382) (xy 153.55619 -26.830205) (xy 153.614083 -26.845718) (xy 153.669456 -26.868654)
			(xy 153.721362 -26.898621) (xy 153.768912 -26.935108) (xy 153.811292 -26.977488) (xy 153.847779 -27.025038)
			(xy 153.877746 -27.076944) (xy 153.900682 -27.132317) (xy 153.916195 -27.19021) (xy 153.924018 -27.249632)
			(xy 153.924508 -27.2796) (xy 153.924018 -27.309568) (xy 153.916195 -27.36899) (xy 153.900682 -27.426883)
			(xy 153.877746 -27.482256) (xy 153.847779 -27.534162) (xy 153.811292 -27.581712) (xy 153.768912 -27.624092)
			(xy 153.721362 -27.660579) (xy 153.669456 -27.690546) (xy 153.614083 -27.713482) (xy 153.55619 -27.728995)
			(xy 153.496768 -27.736818) (xy 153.436832 -27.736818) (xy 153.37741 -27.728995) (xy 153.319517 -27.713482)
			(xy 153.264144 -27.690546) (xy 153.212238 -27.660579) (xy 153.164688 -27.624092) (xy 153.122308 -27.581712)
			(xy 153.085821 -27.534162) (xy 153.055854 -27.482256) (xy 153.032918 -27.426883) (xy 153.017405 -27.36899)
			(xy 153.009582 -27.309568) (xy 131.3434 -27.309568) (xy 131.3434 -28.5181) (xy 157.697914 -28.5181)
			(xy 157.697914 -28.458164) (xy 157.705737 -28.398742) (xy 157.72125 -28.340849) (xy 157.744186 -28.285476)
			(xy 157.774153 -28.23357) (xy 157.81064 -28.18602) (xy 157.85302 -28.14364) (xy 157.90057 -28.107153)
			(xy 157.952476 -28.077186) (xy 158.007849 -28.05425) (xy 158.065742 -28.038737) (xy 158.125164 -28.030914)
			(xy 158.1851 -28.030914) (xy 158.244522 -28.038737) (xy 158.302415 -28.05425) (xy 158.357788 -28.077186)
			(xy 158.409694 -28.107153) (xy 158.457244 -28.14364) (xy 158.499624 -28.18602) (xy 158.536111 -28.23357)
			(xy 158.566078 -28.285476) (xy 158.589014 -28.340849) (xy 158.604527 -28.398742) (xy 158.61235 -28.458164)
			(xy 158.61284 -28.488132) (xy 158.61235 -28.5181) (xy 158.604527 -28.577522) (xy 158.589014 -28.635415)
			(xy 158.566078 -28.690788) (xy 158.536111 -28.742694) (xy 158.499624 -28.790244) (xy 158.457244 -28.832624)
			(xy 158.409694 -28.869111) (xy 158.357788 -28.899078) (xy 158.302415 -28.922014) (xy 158.244522 -28.937527)
			(xy 158.1851 -28.94535) (xy 158.125164 -28.94535) (xy 158.065742 -28.937527) (xy 158.007849 -28.922014)
			(xy 157.952476 -28.899078) (xy 157.90057 -28.869111) (xy 157.85302 -28.832624) (xy 157.81064 -28.790244)
			(xy 157.774153 -28.742694) (xy 157.744186 -28.690788) (xy 157.72125 -28.635415) (xy 157.705737 -28.577522)
			(xy 157.697914 -28.5181) (xy 131.3434 -28.5181) (xy 131.3434 -30.5755) (xy 157.581582 -30.5755) (xy 157.581582 -30.515564)
			(xy 157.589405 -30.456142) (xy 157.604918 -30.398249) (xy 157.627854 -30.342876) (xy 157.657821 -30.29097)
			(xy 157.694308 -30.24342) (xy 157.736688 -30.20104) (xy 157.784238 -30.164553) (xy 157.836144 -30.134586)
			(xy 157.891517 -30.11165) (xy 157.94941 -30.096137) (xy 158.008832 -30.088314) (xy 158.068768 -30.088314)
			(xy 158.12819 -30.096137) (xy 158.186083 -30.11165) (xy 158.241456 -30.134586) (xy 158.293362 -30.164553)
			(xy 158.340912 -30.20104) (xy 158.383292 -30.24342) (xy 158.419779 -30.29097) (xy 158.449746 -30.342876)
			(xy 158.472682 -30.398249) (xy 158.488195 -30.456142) (xy 158.496018 -30.515564) (xy 158.496508 -30.545532)
			(xy 158.496018 -30.5755) (xy 158.488195 -30.634922) (xy 158.472682 -30.692815) (xy 158.449746 -30.748188)
			(xy 158.419779 -30.800094) (xy 158.383292 -30.847644) (xy 158.340912 -30.890024) (xy 158.293362 -30.926511)
			(xy 158.241456 -30.956478) (xy 158.186083 -30.979414) (xy 158.12819 -30.994927) (xy 158.068768 -31.00275)
			(xy 158.008832 -31.00275) (xy 157.94941 -30.994927) (xy 157.891517 -30.979414) (xy 157.836144 -30.956478)
			(xy 157.784238 -30.926511) (xy 157.736688 -30.890024) (xy 157.694308 -30.847644) (xy 157.657821 -30.800094)
			(xy 157.627854 -30.748188) (xy 157.604918 -30.692815) (xy 157.589405 -30.634922) (xy 157.581582 -30.5755)
			(xy 131.3434 -30.5755) (xy 131.3434 -33.2232) (xy 128.8288 -35.7378) (xy 128.8288 -36.068) (xy 133.37743 -36.068)
			(xy 133.381501 -36.012378) (xy 133.393627 -35.957941) (xy 133.41355 -35.90585) (xy 133.440846 -35.857215)
			(xy 133.474932 -35.813072) (xy 133.515081 -35.774363) (xy 133.560439 -35.741912) (xy 133.610039 -35.716411)
			(xy 133.662823 -35.698404) (xy 133.717666 -35.688274) (xy 133.7734 -35.686237) (xy 133.828837 -35.692337)
			(xy 133.882794 -35.706443) (xy 133.934123 -35.728255) (xy 133.981729 -35.757309) (xy 134.024597 -35.792984)
			(xy 134.061814 -35.834521) (xy 134.092587 -35.881034) (xy 134.116259 -35.931531) (xy 134.132327 -35.984938)
			(xy 134.140447 -36.040114) (xy 134.140956 -36.068) (xy 134.140447 -36.095886) (xy 134.132327 -36.151062)
			(xy 134.116259 -36.204469) (xy 134.092587 -36.254966) (xy 134.061814 -36.301479) (xy 134.024597 -36.343016)
			(xy 133.981729 -36.378691) (xy 133.934123 -36.407745) (xy 133.882794 -36.429557) (xy 133.828837 -36.443663)
			(xy 133.7734 -36.449763) (xy 133.717666 -36.447726) (xy 133.662823 -36.437596) (xy 133.610039 -36.419589)
			(xy 133.560439 -36.394088) (xy 133.515081 -36.361637) (xy 133.474932 -36.322928) (xy 133.440846 -36.278785)
			(xy 133.41355 -36.23015) (xy 133.393627 -36.178059) (xy 133.381501 -36.123622) (xy 133.37743 -36.068)
			(xy 128.8288 -36.068) (xy 128.8288 -36.834568) (xy 307.187582 -36.834568) (xy 307.187582 -36.774632)
			(xy 307.195405 -36.71521) (xy 307.210918 -36.657317) (xy 307.233854 -36.601944) (xy 307.263821 -36.550038)
			(xy 307.300308 -36.502488) (xy 307.342688 -36.460108) (xy 307.390238 -36.423621) (xy 307.442144 -36.393654)
			(xy 307.497517 -36.370718) (xy 307.55541 -36.355205) (xy 307.614832 -36.347382) (xy 307.674768 -36.347382)
			(xy 307.73419 -36.355205) (xy 307.792083 -36.370718) (xy 307.847456 -36.393654) (xy 307.899362 -36.423621)
			(xy 307.946912 -36.460108) (xy 307.989292 -36.502488) (xy 308.025779 -36.550038) (xy 308.042672 -36.579298)
			(xy 308.763652 -36.579298) (xy 308.763652 -36.519362) (xy 308.771475 -36.45994) (xy 308.786988 -36.402047)
			(xy 308.809924 -36.346674) (xy 308.839891 -36.294768) (xy 308.876378 -36.247218) (xy 308.918758 -36.204838)
			(xy 308.966308 -36.168351) (xy 309.018214 -36.138384) (xy 309.073587 -36.115448) (xy 309.13148 -36.099935)
			(xy 309.190902 -36.092112) (xy 309.250838 -36.092112) (xy 309.31026 -36.099935) (xy 309.368153 -36.115448)
			(xy 309.423526 -36.138384) (xy 309.475432 -36.168351) (xy 309.522982 -36.204838) (xy 309.565362 -36.247218)
			(xy 309.601849 -36.294768) (xy 309.631816 -36.346674) (xy 309.654752 -36.402047) (xy 309.670265 -36.45994)
			(xy 309.678088 -36.519362) (xy 309.678578 -36.54933) (xy 309.678088 -36.579298) (xy 309.670265 -36.63872)
			(xy 309.654752 -36.696613) (xy 309.631816 -36.751986) (xy 309.601849 -36.803892) (xy 309.565362 -36.851442)
			(xy 309.522982 -36.893822) (xy 309.475432 -36.930309) (xy 309.423526 -36.960276) (xy 309.368153 -36.983212)
			(xy 309.31026 -36.998725) (xy 309.250838 -37.006548) (xy 309.190902 -37.006548) (xy 309.13148 -36.998725)
			(xy 309.073587 -36.983212) (xy 309.018214 -36.960276) (xy 308.966308 -36.930309) (xy 308.918758 -36.893822)
			(xy 308.876378 -36.851442) (xy 308.839891 -36.803892) (xy 308.809924 -36.751986) (xy 308.786988 -36.696613)
			(xy 308.771475 -36.63872) (xy 308.763652 -36.579298) (xy 308.042672 -36.579298) (xy 308.055746 -36.601944)
			(xy 308.078682 -36.657317) (xy 308.094195 -36.71521) (xy 308.102018 -36.774632) (xy 308.102508 -36.8046)
			(xy 308.102018 -36.834568) (xy 308.094195 -36.89399) (xy 308.078682 -36.951883) (xy 308.055746 -37.007256)
			(xy 308.025779 -37.059162) (xy 307.989292 -37.106712) (xy 307.946912 -37.149092) (xy 307.899362 -37.185579)
			(xy 307.847456 -37.215546) (xy 307.792083 -37.238482) (xy 307.73419 -37.253995) (xy 307.674768 -37.261818)
			(xy 307.614832 -37.261818) (xy 307.55541 -37.253995) (xy 307.497517 -37.238482) (xy 307.442144 -37.215546)
			(xy 307.390238 -37.185579) (xy 307.342688 -37.149092) (xy 307.300308 -37.106712) (xy 307.263821 -37.059162)
			(xy 307.233854 -37.007256) (xy 307.210918 -36.951883) (xy 307.195405 -36.89399) (xy 307.187582 -36.834568)
			(xy 128.8288 -36.834568) (xy 128.8288 -37.367968) (xy 156.501828 -37.367968) (xy 156.501828 -37.308032)
			(xy 156.509651 -37.24861) (xy 156.525164 -37.190717) (xy 156.5481 -37.135344) (xy 156.578067 -37.083438)
			(xy 156.614554 -37.035888) (xy 156.656934 -36.993508) (xy 156.704484 -36.957021) (xy 156.75639 -36.927054)
			(xy 156.811763 -36.904118) (xy 156.869656 -36.888605) (xy 156.929078 -36.880782) (xy 156.989014 -36.880782)
			(xy 157.048436 -36.888605) (xy 157.106329 -36.904118) (xy 157.161702 -36.927054) (xy 157.213608 -36.957021)
			(xy 157.261158 -36.993508) (xy 157.303538 -37.035888) (xy 157.340025 -37.083438) (xy 157.369992 -37.135344)
			(xy 157.392928 -37.190717) (xy 157.408441 -37.24861) (xy 157.416264 -37.308032) (xy 157.416754 -37.338)
			(xy 157.416264 -37.367968) (xy 157.408441 -37.42739) (xy 157.392928 -37.485283) (xy 157.369992 -37.540656)
			(xy 157.340025 -37.592562) (xy 157.303538 -37.640112) (xy 157.261158 -37.682492) (xy 157.213608 -37.718979)
			(xy 157.205659 -37.723568) (xy 158.590724 -37.723568) (xy 158.590724 -37.663632) (xy 158.598547 -37.60421)
			(xy 158.61406 -37.546317) (xy 158.636996 -37.490944) (xy 158.666963 -37.439038) (xy 158.70345 -37.391488)
			(xy 158.74583 -37.349108) (xy 158.79338 -37.312621) (xy 158.845286 -37.282654) (xy 158.900659 -37.259718)
			(xy 158.958552 -37.244205) (xy 159.017974 -37.236382) (xy 159.07791 -37.236382) (xy 159.137332 -37.244205)
			(xy 159.195225 -37.259718) (xy 159.250598 -37.282654) (xy 159.302504 -37.312621) (xy 159.350054 -37.349108)
			(xy 159.392434 -37.391488) (xy 159.428921 -37.439038) (xy 159.458888 -37.490944) (xy 159.481824 -37.546317)
			(xy 159.497337 -37.60421) (xy 159.50516 -37.663632) (xy 159.50565 -37.6936) (xy 159.50516 -37.723568)
			(xy 159.497337 -37.78299) (xy 159.481824 -37.840883) (xy 159.458888 -37.896256) (xy 159.428921 -37.948162)
			(xy 159.392434 -37.995712) (xy 159.350054 -38.038092) (xy 159.302504 -38.074579) (xy 159.250598 -38.104546)
			(xy 159.195225 -38.127482) (xy 159.137332 -38.142995) (xy 159.07791 -38.150818) (xy 159.017974 -38.150818)
			(xy 158.958552 -38.142995) (xy 158.900659 -38.127482) (xy 158.845286 -38.104546) (xy 158.79338 -38.074579)
			(xy 158.74583 -38.038092) (xy 158.70345 -37.995712) (xy 158.666963 -37.948162) (xy 158.636996 -37.896256)
			(xy 158.61406 -37.840883) (xy 158.598547 -37.78299) (xy 158.590724 -37.723568) (xy 157.205659 -37.723568)
			(xy 157.161702 -37.748946) (xy 157.106329 -37.771882) (xy 157.048436 -37.787395) (xy 156.989014 -37.795218)
			(xy 156.929078 -37.795218) (xy 156.869656 -37.787395) (xy 156.811763 -37.771882) (xy 156.75639 -37.748946)
			(xy 156.704484 -37.718979) (xy 156.656934 -37.682492) (xy 156.614554 -37.640112) (xy 156.578067 -37.592562)
			(xy 156.5481 -37.540656) (xy 156.525164 -37.485283) (xy 156.509651 -37.42739) (xy 156.501828 -37.367968)
			(xy 128.8288 -37.367968) (xy 128.8288 -38.745261) (xy 216.636592 -38.745261) (xy 216.636592 -38.673939)
			(xy 216.644578 -38.603065) (xy 216.660448 -38.53353) (xy 216.684005 -38.46621) (xy 216.71495 -38.401951)
			(xy 216.752896 -38.34156) (xy 216.797365 -38.285798) (xy 216.847798 -38.235365) (xy 216.90356 -38.190896)
			(xy 216.963951 -38.15295) (xy 217.02821 -38.122005) (xy 217.09553 -38.098448) (xy 217.165065 -38.082578)
			(xy 217.235939 -38.074592) (xy 217.307261 -38.074592) (xy 217.378135 -38.082578) (xy 217.44767 -38.098448)
			(xy 217.51499 -38.122005) (xy 217.579249 -38.15295) (xy 217.63964 -38.190896) (xy 217.695402 -38.235365)
			(xy 217.745835 -38.285798) (xy 217.790304 -38.34156) (xy 217.82825 -38.401951) (xy 217.859195 -38.46621)
			(xy 217.882752 -38.53353) (xy 217.898622 -38.603065) (xy 217.906608 -38.673939) (xy 217.907108 -38.7096)
			(xy 217.906608 -38.745261) (xy 224.256592 -38.745261) (xy 224.256592 -38.673939) (xy 224.264578 -38.603065)
			(xy 224.280448 -38.53353) (xy 224.304005 -38.46621) (xy 224.33495 -38.401951) (xy 224.372896 -38.34156)
			(xy 224.417365 -38.285798) (xy 224.467798 -38.235365) (xy 224.52356 -38.190896) (xy 224.583951 -38.15295)
			(xy 224.64821 -38.122005) (xy 224.71553 -38.098448) (xy 224.785065 -38.082578) (xy 224.855939 -38.074592)
			(xy 224.927261 -38.074592) (xy 224.998135 -38.082578) (xy 225.06767 -38.098448) (xy 225.13499 -38.122005)
			(xy 225.199249 -38.15295) (xy 225.25964 -38.190896) (xy 225.315402 -38.235365) (xy 225.365835 -38.285798)
			(xy 225.410304 -38.34156) (xy 225.44825 -38.401951) (xy 225.479195 -38.46621) (xy 225.502752 -38.53353)
			(xy 225.518622 -38.603065) (xy 225.526608 -38.673939) (xy 225.527108 -38.7096) (xy 225.526608 -38.745261)
			(xy 231.876592 -38.745261) (xy 231.876592 -38.673939) (xy 231.884578 -38.603065) (xy 231.900448 -38.53353)
			(xy 231.924005 -38.46621) (xy 231.95495 -38.401951) (xy 231.992896 -38.34156) (xy 232.037365 -38.285798)
			(xy 232.087798 -38.235365) (xy 232.14356 -38.190896) (xy 232.203951 -38.15295) (xy 232.26821 -38.122005)
			(xy 232.33553 -38.098448) (xy 232.405065 -38.082578) (xy 232.475939 -38.074592) (xy 232.547261 -38.074592)
			(xy 232.618135 -38.082578) (xy 232.68767 -38.098448) (xy 232.75499 -38.122005) (xy 232.819249 -38.15295)
			(xy 232.87964 -38.190896) (xy 232.935402 -38.235365) (xy 232.985835 -38.285798) (xy 233.030304 -38.34156)
			(xy 233.06825 -38.401951) (xy 233.099195 -38.46621) (xy 233.122752 -38.53353) (xy 233.138622 -38.603065)
			(xy 233.146608 -38.673939) (xy 233.147108 -38.7096) (xy 233.146608 -38.745261) (xy 239.496592 -38.745261)
			(xy 239.496592 -38.673939) (xy 239.504578 -38.603065) (xy 239.520448 -38.53353) (xy 239.544005 -38.46621)
			(xy 239.57495 -38.401951) (xy 239.612896 -38.34156) (xy 239.657365 -38.285798) (xy 239.707798 -38.235365)
			(xy 239.76356 -38.190896) (xy 239.823951 -38.15295) (xy 239.88821 -38.122005) (xy 239.95553 -38.098448)
			(xy 240.025065 -38.082578) (xy 240.095939 -38.074592) (xy 240.167261 -38.074592) (xy 240.238135 -38.082578)
			(xy 240.30767 -38.098448) (xy 240.37499 -38.122005) (xy 240.439249 -38.15295) (xy 240.49964 -38.190896)
			(xy 240.555402 -38.235365) (xy 240.605835 -38.285798) (xy 240.650304 -38.34156) (xy 240.68825 -38.401951)
			(xy 240.719195 -38.46621) (xy 240.742752 -38.53353) (xy 240.758622 -38.603065) (xy 240.766608 -38.673939)
			(xy 240.767108 -38.7096) (xy 240.766608 -38.745261) (xy 247.116592 -38.745261) (xy 247.116592 -38.673939)
			(xy 247.124578 -38.603065) (xy 247.140448 -38.53353) (xy 247.164005 -38.46621) (xy 247.19495 -38.401951)
			(xy 247.232896 -38.34156) (xy 247.277365 -38.285798) (xy 247.327798 -38.235365) (xy 247.38356 -38.190896)
			(xy 247.443951 -38.15295) (xy 247.50821 -38.122005) (xy 247.57553 -38.098448) (xy 247.645065 -38.082578)
			(xy 247.715939 -38.074592) (xy 247.787261 -38.074592) (xy 247.858135 -38.082578) (xy 247.92767 -38.098448)
			(xy 247.99499 -38.122005) (xy 248.059249 -38.15295) (xy 248.11964 -38.190896) (xy 248.175402 -38.235365)
			(xy 248.225835 -38.285798) (xy 248.270304 -38.34156) (xy 248.30825 -38.401951) (xy 248.339195 -38.46621)
			(xy 248.362752 -38.53353) (xy 248.378622 -38.603065) (xy 248.386608 -38.673939) (xy 248.387108 -38.7096)
			(xy 248.386608 -38.745261) (xy 254.736592 -38.745261) (xy 254.736592 -38.673939) (xy 254.744578 -38.603065)
			(xy 254.760448 -38.53353) (xy 254.784005 -38.46621) (xy 254.81495 -38.401951) (xy 254.852896 -38.34156)
			(xy 254.897365 -38.285798) (xy 254.947798 -38.235365) (xy 255.00356 -38.190896) (xy 255.063951 -38.15295)
			(xy 255.12821 -38.122005) (xy 255.19553 -38.098448) (xy 255.265065 -38.082578) (xy 255.335939 -38.074592)
			(xy 255.407261 -38.074592) (xy 255.478135 -38.082578) (xy 255.54767 -38.098448) (xy 255.61499 -38.122005)
			(xy 255.679249 -38.15295) (xy 255.73964 -38.190896) (xy 255.795402 -38.235365) (xy 255.845835 -38.285798)
			(xy 255.890304 -38.34156) (xy 255.92825 -38.401951) (xy 255.959195 -38.46621) (xy 255.982752 -38.53353)
			(xy 255.998622 -38.603065) (xy 256.006608 -38.673939) (xy 256.007108 -38.7096) (xy 256.006608 -38.745261)
			(xy 262.356592 -38.745261) (xy 262.356592 -38.673939) (xy 262.364578 -38.603065) (xy 262.380448 -38.53353)
			(xy 262.404005 -38.46621) (xy 262.43495 -38.401951) (xy 262.472896 -38.34156) (xy 262.517365 -38.285798)
			(xy 262.567798 -38.235365) (xy 262.62356 -38.190896) (xy 262.683951 -38.15295) (xy 262.74821 -38.122005)
			(xy 262.81553 -38.098448) (xy 262.885065 -38.082578) (xy 262.955939 -38.074592) (xy 263.027261 -38.074592)
			(xy 263.098135 -38.082578) (xy 263.16767 -38.098448) (xy 263.23499 -38.122005) (xy 263.299249 -38.15295)
			(xy 263.35964 -38.190896) (xy 263.415402 -38.235365) (xy 263.465835 -38.285798) (xy 263.510304 -38.34156)
			(xy 263.54825 -38.401951) (xy 263.579195 -38.46621) (xy 263.602752 -38.53353) (xy 263.618622 -38.603065)
			(xy 263.626608 -38.673939) (xy 263.627108 -38.7096) (xy 263.626608 -38.745261) (xy 269.976592 -38.745261)
			(xy 269.976592 -38.673939) (xy 269.984578 -38.603065) (xy 270.000448 -38.53353) (xy 270.024005 -38.46621)
			(xy 270.05495 -38.401951) (xy 270.092896 -38.34156) (xy 270.137365 -38.285798) (xy 270.187798 -38.235365)
			(xy 270.24356 -38.190896) (xy 270.303951 -38.15295) (xy 270.36821 -38.122005) (xy 270.43553 -38.098448)
			(xy 270.505065 -38.082578) (xy 270.575939 -38.074592) (xy 270.647261 -38.074592) (xy 270.718135 -38.082578)
			(xy 270.78767 -38.098448) (xy 270.85499 -38.122005) (xy 270.919249 -38.15295) (xy 270.97964 -38.190896)
			(xy 271.035402 -38.235365) (xy 271.085835 -38.285798) (xy 271.130304 -38.34156) (xy 271.16825 -38.401951)
			(xy 271.199195 -38.46621) (xy 271.222752 -38.53353) (xy 271.238622 -38.603065) (xy 271.246608 -38.673939)
			(xy 271.247108 -38.7096) (xy 271.246608 -38.745261) (xy 277.596592 -38.745261) (xy 277.596592 -38.673939)
			(xy 277.604578 -38.603065) (xy 277.620448 -38.53353) (xy 277.644005 -38.46621) (xy 277.67495 -38.401951)
			(xy 277.712896 -38.34156) (xy 277.757365 -38.285798) (xy 277.807798 -38.235365) (xy 277.86356 -38.190896)
			(xy 277.923951 -38.15295) (xy 277.98821 -38.122005) (xy 278.05553 -38.098448) (xy 278.125065 -38.082578)
			(xy 278.195939 -38.074592) (xy 278.267261 -38.074592) (xy 278.338135 -38.082578) (xy 278.40767 -38.098448)
			(xy 278.47499 -38.122005) (xy 278.539249 -38.15295) (xy 278.59964 -38.190896) (xy 278.655402 -38.235365)
			(xy 278.705835 -38.285798) (xy 278.750304 -38.34156) (xy 278.78825 -38.401951) (xy 278.819195 -38.46621)
			(xy 278.842752 -38.53353) (xy 278.858622 -38.603065) (xy 278.866608 -38.673939) (xy 278.867108 -38.7096)
			(xy 278.866608 -38.745261) (xy 285.216592 -38.745261) (xy 285.216592 -38.673939) (xy 285.224578 -38.603065)
			(xy 285.240448 -38.53353) (xy 285.264005 -38.46621) (xy 285.29495 -38.401951) (xy 285.332896 -38.34156)
			(xy 285.377365 -38.285798) (xy 285.427798 -38.235365) (xy 285.48356 -38.190896) (xy 285.543951 -38.15295)
			(xy 285.60821 -38.122005) (xy 285.67553 -38.098448) (xy 285.745065 -38.082578) (xy 285.815939 -38.074592)
			(xy 285.887261 -38.074592) (xy 285.958135 -38.082578) (xy 286.02767 -38.098448) (xy 286.09499 -38.122005)
			(xy 286.159249 -38.15295) (xy 286.21964 -38.190896) (xy 286.275402 -38.235365) (xy 286.325835 -38.285798)
			(xy 286.370304 -38.34156) (xy 286.40825 -38.401951) (xy 286.439195 -38.46621) (xy 286.462752 -38.53353)
			(xy 286.478622 -38.603065) (xy 286.486608 -38.673939) (xy 286.487108 -38.7096) (xy 286.486608 -38.745261)
			(xy 292.836592 -38.745261) (xy 292.836592 -38.673939) (xy 292.844578 -38.603065) (xy 292.860448 -38.53353)
			(xy 292.884005 -38.46621) (xy 292.91495 -38.401951) (xy 292.952896 -38.34156) (xy 292.997365 -38.285798)
			(xy 293.047798 -38.235365) (xy 293.10356 -38.190896) (xy 293.163951 -38.15295) (xy 293.22821 -38.122005)
			(xy 293.29553 -38.098448) (xy 293.365065 -38.082578) (xy 293.435939 -38.074592) (xy 293.507261 -38.074592)
			(xy 293.578135 -38.082578) (xy 293.64767 -38.098448) (xy 293.71499 -38.122005) (xy 293.779249 -38.15295)
			(xy 293.83964 -38.190896) (xy 293.895402 -38.235365) (xy 293.945835 -38.285798) (xy 293.990304 -38.34156)
			(xy 294.02825 -38.401951) (xy 294.059195 -38.46621) (xy 294.082752 -38.53353) (xy 294.098622 -38.603065)
			(xy 294.106608 -38.673939) (xy 294.107108 -38.7096) (xy 294.106608 -38.745261) (xy 294.098622 -38.816135)
			(xy 294.082752 -38.88567) (xy 294.059195 -38.95299) (xy 294.02825 -39.017249) (xy 293.990304 -39.07764)
			(xy 293.945835 -39.133402) (xy 293.895402 -39.183835) (xy 293.83964 -39.228304) (xy 293.779249 -39.26625)
			(xy 293.71499 -39.297195) (xy 293.64767 -39.320752) (xy 293.578135 -39.336622) (xy 293.507261 -39.344608)
			(xy 293.435939 -39.344608) (xy 293.365065 -39.336622) (xy 293.29553 -39.320752) (xy 293.22821 -39.297195)
			(xy 293.163951 -39.26625) (xy 293.10356 -39.228304) (xy 293.047798 -39.183835) (xy 292.997365 -39.133402)
			(xy 292.952896 -39.07764) (xy 292.91495 -39.017249) (xy 292.884005 -38.95299) (xy 292.860448 -38.88567)
			(xy 292.844578 -38.816135) (xy 292.836592 -38.745261) (xy 286.486608 -38.745261) (xy 286.478622 -38.816135)
			(xy 286.462752 -38.88567) (xy 286.439195 -38.95299) (xy 286.40825 -39.017249) (xy 286.370304 -39.07764)
			(xy 286.325835 -39.133402) (xy 286.275402 -39.183835) (xy 286.21964 -39.228304) (xy 286.159249 -39.26625)
			(xy 286.09499 -39.297195) (xy 286.02767 -39.320752) (xy 285.958135 -39.336622) (xy 285.887261 -39.344608)
			(xy 285.815939 -39.344608) (xy 285.745065 -39.336622) (xy 285.67553 -39.320752) (xy 285.60821 -39.297195)
			(xy 285.543951 -39.26625) (xy 285.48356 -39.228304) (xy 285.427798 -39.183835) (xy 285.377365 -39.133402)
			(xy 285.332896 -39.07764) (xy 285.29495 -39.017249) (xy 285.264005 -38.95299) (xy 285.240448 -38.88567)
			(xy 285.224578 -38.816135) (xy 285.216592 -38.745261) (xy 278.866608 -38.745261) (xy 278.858622 -38.816135)
			(xy 278.842752 -38.88567) (xy 278.819195 -38.95299) (xy 278.78825 -39.017249) (xy 278.750304 -39.07764)
			(xy 278.705835 -39.133402) (xy 278.655402 -39.183835) (xy 278.59964 -39.228304) (xy 278.539249 -39.26625)
			(xy 278.47499 -39.297195) (xy 278.40767 -39.320752) (xy 278.338135 -39.336622) (xy 278.267261 -39.344608)
			(xy 278.195939 -39.344608) (xy 278.125065 -39.336622) (xy 278.05553 -39.320752) (xy 277.98821 -39.297195)
			(xy 277.923951 -39.26625) (xy 277.86356 -39.228304) (xy 277.807798 -39.183835) (xy 277.757365 -39.133402)
			(xy 277.712896 -39.07764) (xy 277.67495 -39.017249) (xy 277.644005 -38.95299) (xy 277.620448 -38.88567)
			(xy 277.604578 -38.816135) (xy 277.596592 -38.745261) (xy 271.246608 -38.745261) (xy 271.238622 -38.816135)
			(xy 271.222752 -38.88567) (xy 271.199195 -38.95299) (xy 271.16825 -39.017249) (xy 271.130304 -39.07764)
			(xy 271.085835 -39.133402) (xy 271.035402 -39.183835) (xy 270.97964 -39.228304) (xy 270.919249 -39.26625)
			(xy 270.85499 -39.297195) (xy 270.78767 -39.320752) (xy 270.718135 -39.336622) (xy 270.647261 -39.344608)
			(xy 270.575939 -39.344608) (xy 270.505065 -39.336622) (xy 270.43553 -39.320752) (xy 270.36821 -39.297195)
			(xy 270.303951 -39.26625) (xy 270.24356 -39.228304) (xy 270.187798 -39.183835) (xy 270.137365 -39.133402)
			(xy 270.092896 -39.07764) (xy 270.05495 -39.017249) (xy 270.024005 -38.95299) (xy 270.000448 -38.88567)
			(xy 269.984578 -38.816135) (xy 269.976592 -38.745261) (xy 263.626608 -38.745261) (xy 263.618622 -38.816135)
			(xy 263.602752 -38.88567) (xy 263.579195 -38.95299) (xy 263.54825 -39.017249) (xy 263.510304 -39.07764)
			(xy 263.465835 -39.133402) (xy 263.415402 -39.183835) (xy 263.35964 -39.228304) (xy 263.299249 -39.26625)
			(xy 263.23499 -39.297195) (xy 263.16767 -39.320752) (xy 263.098135 -39.336622) (xy 263.027261 -39.344608)
			(xy 262.955939 -39.344608) (xy 262.885065 -39.336622) (xy 262.81553 -39.320752) (xy 262.74821 -39.297195)
			(xy 262.683951 -39.26625) (xy 262.62356 -39.228304) (xy 262.567798 -39.183835) (xy 262.517365 -39.133402)
			(xy 262.472896 -39.07764) (xy 262.43495 -39.017249) (xy 262.404005 -38.95299) (xy 262.380448 -38.88567)
			(xy 262.364578 -38.816135) (xy 262.356592 -38.745261) (xy 256.006608 -38.745261) (xy 255.998622 -38.816135)
			(xy 255.982752 -38.88567) (xy 255.959195 -38.95299) (xy 255.92825 -39.017249) (xy 255.890304 -39.07764)
			(xy 255.845835 -39.133402) (xy 255.795402 -39.183835) (xy 255.73964 -39.228304) (xy 255.679249 -39.26625)
			(xy 255.61499 -39.297195) (xy 255.54767 -39.320752) (xy 255.478135 -39.336622) (xy 255.407261 -39.344608)
			(xy 255.335939 -39.344608) (xy 255.265065 -39.336622) (xy 255.19553 -39.320752) (xy 255.12821 -39.297195)
			(xy 255.063951 -39.26625) (xy 255.00356 -39.228304) (xy 254.947798 -39.183835) (xy 254.897365 -39.133402)
			(xy 254.852896 -39.07764) (xy 254.81495 -39.017249) (xy 254.784005 -38.95299) (xy 254.760448 -38.88567)
			(xy 254.744578 -38.816135) (xy 254.736592 -38.745261) (xy 248.386608 -38.745261) (xy 248.378622 -38.816135)
			(xy 248.362752 -38.88567) (xy 248.339195 -38.95299) (xy 248.30825 -39.017249) (xy 248.270304 -39.07764)
			(xy 248.225835 -39.133402) (xy 248.175402 -39.183835) (xy 248.11964 -39.228304) (xy 248.059249 -39.26625)
			(xy 247.99499 -39.297195) (xy 247.92767 -39.320752) (xy 247.858135 -39.336622) (xy 247.787261 -39.344608)
			(xy 247.715939 -39.344608) (xy 247.645065 -39.336622) (xy 247.57553 -39.320752) (xy 247.50821 -39.297195)
			(xy 247.443951 -39.26625) (xy 247.38356 -39.228304) (xy 247.327798 -39.183835) (xy 247.277365 -39.133402)
			(xy 247.232896 -39.07764) (xy 247.19495 -39.017249) (xy 247.164005 -38.95299) (xy 247.140448 -38.88567)
			(xy 247.124578 -38.816135) (xy 247.116592 -38.745261) (xy 240.766608 -38.745261) (xy 240.758622 -38.816135)
			(xy 240.742752 -38.88567) (xy 240.719195 -38.95299) (xy 240.68825 -39.017249) (xy 240.650304 -39.07764)
			(xy 240.605835 -39.133402) (xy 240.555402 -39.183835) (xy 240.49964 -39.228304) (xy 240.439249 -39.26625)
			(xy 240.37499 -39.297195) (xy 240.30767 -39.320752) (xy 240.238135 -39.336622) (xy 240.167261 -39.344608)
			(xy 240.095939 -39.344608) (xy 240.025065 -39.336622) (xy 239.95553 -39.320752) (xy 239.88821 -39.297195)
			(xy 239.823951 -39.26625) (xy 239.76356 -39.228304) (xy 239.707798 -39.183835) (xy 239.657365 -39.133402)
			(xy 239.612896 -39.07764) (xy 239.57495 -39.017249) (xy 239.544005 -38.95299) (xy 239.520448 -38.88567)
			(xy 239.504578 -38.816135) (xy 239.496592 -38.745261) (xy 233.146608 -38.745261) (xy 233.138622 -38.816135)
			(xy 233.122752 -38.88567) (xy 233.099195 -38.95299) (xy 233.06825 -39.017249) (xy 233.030304 -39.07764)
			(xy 232.985835 -39.133402) (xy 232.935402 -39.183835) (xy 232.87964 -39.228304) (xy 232.819249 -39.26625)
			(xy 232.75499 -39.297195) (xy 232.68767 -39.320752) (xy 232.618135 -39.336622) (xy 232.547261 -39.344608)
			(xy 232.475939 -39.344608) (xy 232.405065 -39.336622) (xy 232.33553 -39.320752) (xy 232.26821 -39.297195)
			(xy 232.203951 -39.26625) (xy 232.14356 -39.228304) (xy 232.087798 -39.183835) (xy 232.037365 -39.133402)
			(xy 231.992896 -39.07764) (xy 231.95495 -39.017249) (xy 231.924005 -38.95299) (xy 231.900448 -38.88567)
			(xy 231.884578 -38.816135) (xy 231.876592 -38.745261) (xy 225.526608 -38.745261) (xy 225.518622 -38.816135)
			(xy 225.502752 -38.88567) (xy 225.479195 -38.95299) (xy 225.44825 -39.017249) (xy 225.410304 -39.07764)
			(xy 225.365835 -39.133402) (xy 225.315402 -39.183835) (xy 225.25964 -39.228304) (xy 225.199249 -39.26625)
			(xy 225.13499 -39.297195) (xy 225.06767 -39.320752) (xy 224.998135 -39.336622) (xy 224.927261 -39.344608)
			(xy 224.855939 -39.344608) (xy 224.785065 -39.336622) (xy 224.71553 -39.320752) (xy 224.64821 -39.297195)
			(xy 224.583951 -39.26625) (xy 224.52356 -39.228304) (xy 224.467798 -39.183835) (xy 224.417365 -39.133402)
			(xy 224.372896 -39.07764) (xy 224.33495 -39.017249) (xy 224.304005 -38.95299) (xy 224.280448 -38.88567)
			(xy 224.264578 -38.816135) (xy 224.256592 -38.745261) (xy 217.906608 -38.745261) (xy 217.898622 -38.816135)
			(xy 217.882752 -38.88567) (xy 217.859195 -38.95299) (xy 217.82825 -39.017249) (xy 217.790304 -39.07764)
			(xy 217.745835 -39.133402) (xy 217.695402 -39.183835) (xy 217.63964 -39.228304) (xy 217.579249 -39.26625)
			(xy 217.51499 -39.297195) (xy 217.44767 -39.320752) (xy 217.378135 -39.336622) (xy 217.307261 -39.344608)
			(xy 217.235939 -39.344608) (xy 217.165065 -39.336622) (xy 217.09553 -39.320752) (xy 217.02821 -39.297195)
			(xy 216.963951 -39.26625) (xy 216.90356 -39.228304) (xy 216.847798 -39.183835) (xy 216.797365 -39.133402)
			(xy 216.752896 -39.07764) (xy 216.71495 -39.017249) (xy 216.684005 -38.95299) (xy 216.660448 -38.88567)
			(xy 216.644578 -38.816135) (xy 216.636592 -38.745261) (xy 128.8288 -38.745261) (xy 128.8288 -39.4716)
			(xy 128.0668 -40.2336) (xy 120.0912 -40.2336) (xy 118.237 -38.3794) (xy 118.237 -25.987248) (xy 118.213886 -25.936956)
			(xy 118.19255 -25.918668) (xy 118.171964 -25.900461) (xy 118.135723 -25.859149) (xy 118.105786 -25.813063)
			(xy 118.082773 -25.763157) (xy 118.067162 -25.710465) (xy 118.059275 -25.656078) (xy 118.059275 -25.601122)
			(xy 118.067162 -25.546735) (xy 118.082773 -25.494043) (xy 118.105786 -25.444137) (xy 118.135723 -25.398051)
			(xy 118.171964 -25.356739) (xy 118.19255 -25.338532) (xy 118.213886 -25.320244) (xy 118.237 -25.269952)
			(xy 118.237 -22.64664) (xy 118.236582 -22.6319) (xy 118.229817 -22.603207) (xy 118.21664 -22.576836)
			(xy 118.197756 -22.554199) (xy 118.1862 -22.54504) (xy 118.164683 -22.528324) (xy 118.126157 -22.489795)
			(xy 118.093506 -22.446177) (xy 118.067395 -22.398356) (xy 118.048353 -22.347306) (xy 118.03677 -22.294066)
			(xy 118.032881 -22.239719) (xy 118.036765 -22.185372) (xy 118.048342 -22.132131) (xy 118.067379 -22.081079)
			(xy 118.093486 -22.033256) (xy 118.126132 -21.989634) (xy 118.164654 -21.951101) (xy 118.1862 -21.934424)
			(xy 118.210076 -21.91639) (xy 118.237 -21.862796) (xy 118.237 -21.540216) (xy 118.206774 -21.484082)
			(xy 118.17985 -21.466302) (xy 118.157569 -21.451099) (xy 118.117117 -21.415418) (xy 118.082095 -21.374396)
			(xy 118.0532 -21.328849) (xy 118.031008 -21.279686) (xy 118.015962 -21.227888) (xy 118.008362 -21.174487)
			(xy 118.00836 -21.120548) (xy 118.015955 -21.067146) (xy 118.030996 -21.015347) (xy 118.053183 -20.966182)
			(xy 118.082074 -20.920633) (xy 118.117093 -20.879607) (xy 118.157541 -20.843922) (xy 118.17985 -20.828762)
			(xy 118.206774 -20.810982) (xy 118.237 -20.754848) (xy 118.237 -17.4752) (xy 115.5192 -14.7574) (xy 110.369858 -14.7574)
			(xy 110.355148 -14.757822) (xy 110.326513 -14.764568) (xy 110.300182 -14.777691) (xy 110.277556 -14.796494)
			(xy 110.259836 -14.819978) (xy 110.247963 -14.846896) (xy 110.24489 -14.861286) (xy 110.236705 -14.902822)
			(xy 110.213651 -14.984286) (xy 110.183172 -15.063273) (xy 110.14553 -15.139109) (xy 110.101047 -15.211145)
			(xy 110.050103 -15.278766) (xy 109.993132 -15.341394) (xy 109.930622 -15.398494) (xy 109.863107 -15.449578)
			(xy 109.791163 -15.49421) (xy 109.715405 -15.532008) (xy 109.636481 -15.56265) (xy 109.555065 -15.585873)
			(xy 109.471852 -15.601479) (xy 109.387554 -15.609336) (xy 109.345222 -15.609824) (xy 109.304008 -15.609352)
			(xy 109.221954 -15.601514) (xy 109.141018 -15.585899) (xy 109.061938 -15.562647) (xy 108.985431 -15.531971)
			(xy 108.912193 -15.494148) (xy 108.842889 -15.449524) (xy 108.77815 -15.398502) (xy 108.718563 -15.341548)
			(xy 108.664671 -15.279179) (xy 108.616962 -15.211961) (xy 108.575872 -15.140505) (xy 108.541772 -15.065461)
			(xy 108.514973 -14.987512) (xy 108.495719 -14.907364) (xy 108.489496 -14.86662) (xy 108.486941 -14.851672)
			(xy 108.475733 -14.823505) (xy 108.458191 -14.798779) (xy 108.435309 -14.778893) (xy 108.408379 -14.764971)
			(xy 108.378924 -14.757799) (xy 108.363766 -14.7574) (xy 105.156 -14.7574) (xy 101.219 -10.8204) (xy 101.219 -7.366)
			(xy 100.5332 -6.6802) (xy 100.5332 -4.1402) (xy 97.917 -1.524) (xy 9.9822 -1.524) (xy 9.6774 -1.8288)
			(xy 9.6774 -2.99974) (xy 90.607899 -2.99974) (xy 90.611934 -2.924036) (xy 90.623993 -2.849191) (xy 90.643939 -2.77605)
			(xy 90.671546 -2.705445) (xy 90.706502 -2.638174) (xy 90.74841 -2.574999) (xy 90.796796 -2.516637)
			(xy 90.851112 -2.463749) (xy 90.910741 -2.416934) (xy 90.975009 -2.376722) (xy 91.043186 -2.34357)
			(xy 91.114502 -2.317852) (xy 91.188147 -2.29986) (xy 91.263287 -2.289798) (xy 91.339071 -2.287779)
			(xy 91.414641 -2.293828) (xy 91.489139 -2.307875) (xy 91.561722 -2.329761) (xy 91.631568 -2.359238)
			(xy 91.697885 -2.395973) (xy 91.759921 -2.439548) (xy 91.816974 -2.48947) (xy 91.868398 -2.545174)
			(xy 91.913609 -2.606029) (xy 91.952096 -2.671344) (xy 91.983422 -2.74038) (xy 92.007232 -2.812355)
			(xy 92.023257 -2.886453) (xy 92.031316 -2.961834) (xy 92.03182 -2.99974) (xy 92.607895 -2.99974)
			(xy 92.61193 -2.924036) (xy 92.623989 -2.849191) (xy 92.643935 -2.77605) (xy 92.671542 -2.705445)
			(xy 92.706498 -2.638174) (xy 92.748406 -2.574999) (xy 92.796792 -2.516637) (xy 92.851108 -2.463749)
			(xy 92.910737 -2.416934) (xy 92.975005 -2.376722) (xy 93.043182 -2.34357) (xy 93.114498 -2.317852)
			(xy 93.188143 -2.29986) (xy 93.263283 -2.289798) (xy 93.339067 -2.287779) (xy 93.414637 -2.293828)
			(xy 93.489135 -2.307875) (xy 93.561718 -2.329761) (xy 93.631564 -2.359238) (xy 93.697881 -2.395973)
			(xy 93.759917 -2.439548) (xy 93.81697 -2.48947) (xy 93.868394 -2.545174) (xy 93.913605 -2.606029)
			(xy 93.952092 -2.671344) (xy 93.983418 -2.74038) (xy 94.007228 -2.812355) (xy 94.023253 -2.886453)
			(xy 94.031312 -2.961834) (xy 94.031816 -2.99974) (xy 94.031312 -3.037646) (xy 94.023253 -3.113027)
			(xy 94.007228 -3.187125) (xy 93.983418 -3.2591) (xy 93.952092 -3.328136) (xy 93.913605 -3.393451)
			(xy 93.868394 -3.454306) (xy 93.81697 -3.51001) (xy 93.759917 -3.559932) (xy 93.697881 -3.603507)
			(xy 93.631564 -3.640242) (xy 93.561718 -3.669719) (xy 93.489135 -3.691605) (xy 93.414637 -3.705652)
			(xy 93.339067 -3.711701) (xy 93.263283 -3.709682) (xy 93.188143 -3.69962) (xy 93.114498 -3.681628)
			(xy 93.043182 -3.65591) (xy 92.975005 -3.622758) (xy 92.910737 -3.582546) (xy 92.851108 -3.535731)
			(xy 92.796792 -3.482843) (xy 92.748406 -3.424481) (xy 92.706498 -3.361306) (xy 92.671542 -3.294035)
			(xy 92.643935 -3.22343) (xy 92.623989 -3.150289) (xy 92.61193 -3.075444) (xy 92.607895 -2.99974)
			(xy 92.03182 -2.99974) (xy 92.031316 -3.037646) (xy 92.023257 -3.113027) (xy 92.007232 -3.187125)
			(xy 91.983422 -3.2591) (xy 91.952096 -3.328136) (xy 91.913609 -3.393451) (xy 91.868398 -3.454306)
			(xy 91.816974 -3.51001) (xy 91.759921 -3.559932) (xy 91.697885 -3.603507) (xy 91.631568 -3.640242)
			(xy 91.561722 -3.669719) (xy 91.489139 -3.691605) (xy 91.414641 -3.705652) (xy 91.339071 -3.711701)
			(xy 91.263287 -3.709682) (xy 91.188147 -3.69962) (xy 91.114502 -3.681628) (xy 91.043186 -3.65591)
			(xy 90.975009 -3.622758) (xy 90.910741 -3.582546) (xy 90.851112 -3.535731) (xy 90.796796 -3.482843)
			(xy 90.74841 -3.424481) (xy 90.706502 -3.361306) (xy 90.671546 -3.294035) (xy 90.643939 -3.22343)
			(xy 90.623993 -3.150289) (xy 90.611934 -3.075444) (xy 90.607899 -2.99974) (xy 9.6774 -2.99974) (xy 9.6774 -5.166461)
			(xy 18.897592 -5.166461) (xy 18.897592 -5.095139) (xy 18.905578 -5.024265) (xy 18.921448 -4.95473)
			(xy 18.945005 -4.88741) (xy 18.97595 -4.823151) (xy 19.013896 -4.76276) (xy 19.058365 -4.706998)
			(xy 19.108798 -4.656565) (xy 19.16456 -4.612096) (xy 19.224951 -4.57415) (xy 19.28921 -4.543205)
			(xy 19.35653 -4.519648) (xy 19.426065 -4.503778) (xy 19.496939 -4.495792) (xy 19.568261 -4.495792)
			(xy 19.639135 -4.503778) (xy 19.70867 -4.519648) (xy 19.77599 -4.543205) (xy 19.840249 -4.57415)
			(xy 19.90064 -4.612096) (xy 19.956402 -4.656565) (xy 20.006835 -4.706998) (xy 20.051304 -4.76276)
			(xy 20.08925 -4.823151) (xy 20.120195 -4.88741) (xy 20.137849 -4.937861) (xy 26.593792 -4.937861)
			(xy 26.593792 -4.866539) (xy 26.601778 -4.795665) (xy 26.617648 -4.72613) (xy 26.641205 -4.65881)
			(xy 26.67215 -4.594551) (xy 26.710096 -4.53416) (xy 26.754565 -4.478398) (xy 26.804998 -4.427965)
			(xy 26.86076 -4.383496) (xy 26.921151 -4.34555) (xy 26.98541 -4.314605) (xy 27.05273 -4.291048) (xy 27.122265 -4.275178)
			(xy 27.193139 -4.267192) (xy 27.264461 -4.267192) (xy 27.335335 -4.275178) (xy 27.40487 -4.291048)
			(xy 27.47219 -4.314605) (xy 27.536449 -4.34555) (xy 27.59684 -4.383496) (xy 27.652602 -4.427965)
			(xy 27.703035 -4.478398) (xy 27.747504 -4.53416) (xy 27.78545 -4.594551) (xy 27.816395 -4.65881)
			(xy 27.839952 -4.72613) (xy 27.855822 -4.795665) (xy 27.863808 -4.866539) (xy 27.864308 -4.9022)
			(xy 27.863808 -4.937861) (xy 27.860946 -4.963261) (xy 41.427392 -4.963261) (xy 41.427392 -4.891939)
			(xy 41.435378 -4.821065) (xy 41.451248 -4.75153) (xy 41.474805 -4.68421) (xy 41.50575 -4.619951)
			(xy 41.543696 -4.55956) (xy 41.588165 -4.503798) (xy 41.638598 -4.453365) (xy 41.69436 -4.408896)
			(xy 41.754751 -4.37095) (xy 41.81901 -4.340005) (xy 41.88633 -4.316448) (xy 41.955865 -4.300578)
			(xy 42.026739 -4.292592) (xy 42.098061 -4.292592) (xy 42.168935 -4.300578) (xy 42.23847 -4.316448)
			(xy 42.30579 -4.340005) (xy 42.370049 -4.37095) (xy 42.43044 -4.408896) (xy 42.486202 -4.453365)
			(xy 42.536635 -4.503798) (xy 42.581104 -4.55956) (xy 42.61905 -4.619951) (xy 42.649995 -4.68421)
			(xy 42.673552 -4.75153) (xy 42.689422 -4.821065) (xy 42.697408 -4.891939) (xy 42.697908 -4.9276)
			(xy 42.697408 -4.963261) (xy 42.689422 -5.034135) (xy 42.673552 -5.10367) (xy 42.65158 -5.166461)
			(xy 48.742592 -5.166461) (xy 48.742592 -5.095139) (xy 48.750578 -5.024265) (xy 48.766448 -4.95473)
			(xy 48.790005 -4.88741) (xy 48.82095 -4.823151) (xy 48.858896 -4.76276) (xy 48.903365 -4.706998)
			(xy 48.953798 -4.656565) (xy 49.00956 -4.612096) (xy 49.069951 -4.57415) (xy 49.13421 -4.543205)
			(xy 49.20153 -4.519648) (xy 49.271065 -4.503778) (xy 49.341939 -4.495792) (xy 49.413261 -4.495792)
			(xy 49.484135 -4.503778) (xy 49.55367 -4.519648) (xy 49.62099 -4.543205) (xy 49.685249 -4.57415)
			(xy 49.74564 -4.612096) (xy 49.801402 -4.656565) (xy 49.851835 -4.706998) (xy 49.896304 -4.76276)
			(xy 49.93425 -4.823151) (xy 49.965195 -4.88741) (xy 49.988752 -4.95473) (xy 50.002293 -5.014061)
			(xy 56.718192 -5.014061) (xy 56.718192 -4.942739) (xy 56.726178 -4.871865) (xy 56.742048 -4.80233)
			(xy 56.765605 -4.73501) (xy 56.79655 -4.670751) (xy 56.834496 -4.61036) (xy 56.878965 -4.554598)
			(xy 56.929398 -4.504165) (xy 56.98516 -4.459696) (xy 57.045551 -4.42175) (xy 57.10981 -4.390805)
			(xy 57.17713 -4.367248) (xy 57.246665 -4.351378) (xy 57.317539 -4.343392) (xy 57.388861 -4.343392)
			(xy 57.459735 -4.351378) (xy 57.52927 -4.367248) (xy 57.59659 -4.390805) (xy 57.660849 -4.42175)
			(xy 57.72124 -4.459696) (xy 57.777002 -4.504165) (xy 57.827435 -4.554598) (xy 57.871904 -4.61036)
			(xy 57.90985 -4.670751) (xy 57.940795 -4.73501) (xy 57.964352 -4.80233) (xy 57.980222 -4.871865)
			(xy 57.984796 -4.912461) (xy 63.982592 -4.912461) (xy 63.982592 -4.841139) (xy 63.990578 -4.770265)
			(xy 64.006448 -4.70073) (xy 64.030005 -4.63341) (xy 64.06095 -4.569151) (xy 64.098896 -4.50876) (xy 64.143365 -4.452998)
			(xy 64.193798 -4.402565) (xy 64.24956 -4.358096) (xy 64.309951 -4.32015) (xy 64.37421 -4.289205)
			(xy 64.44153 -4.265648) (xy 64.511065 -4.249778) (xy 64.581939 -4.241792) (xy 64.653261 -4.241792)
			(xy 64.724135 -4.249778) (xy 64.79367 -4.265648) (xy 64.86099 -4.289205) (xy 64.925249 -4.32015)
			(xy 64.98564 -4.358096) (xy 65.041402 -4.402565) (xy 65.091835 -4.452998) (xy 65.136304 -4.50876)
			(xy 65.17425 -4.569151) (xy 65.205195 -4.63341) (xy 65.228752 -4.70073) (xy 65.244622 -4.770265)
			(xy 65.252608 -4.841139) (xy 65.253108 -4.8768) (xy 65.252608 -4.912461) (xy 65.244622 -4.983335)
			(xy 65.240879 -4.999736) (xy 90.607899 -4.999736) (xy 90.611934 -4.924032) (xy 90.623993 -4.849187)
			(xy 90.643939 -4.776046) (xy 90.671546 -4.705441) (xy 90.706502 -4.63817) (xy 90.74841 -4.574995)
			(xy 90.796796 -4.516633) (xy 90.851112 -4.463745) (xy 90.910741 -4.41693) (xy 90.975009 -4.376718)
			(xy 91.043186 -4.343566) (xy 91.114502 -4.317848) (xy 91.188147 -4.299856) (xy 91.263287 -4.289794)
			(xy 91.339071 -4.287775) (xy 91.414641 -4.293824) (xy 91.489139 -4.307871) (xy 91.561722 -4.329757)
			(xy 91.631568 -4.359234) (xy 91.697885 -4.395969) (xy 91.759921 -4.439544) (xy 91.816974 -4.489466)
			(xy 91.868398 -4.54517) (xy 91.913609 -4.606025) (xy 91.952096 -4.67134) (xy 91.983422 -4.740376)
			(xy 92.007232 -4.812351) (xy 92.023257 -4.886449) (xy 92.031316 -4.96183) (xy 92.03182 -4.999736)
			(xy 92.607895 -4.999736) (xy 92.61193 -4.924032) (xy 92.623989 -4.849187) (xy 92.643935 -4.776046)
			(xy 92.671542 -4.705441) (xy 92.706498 -4.63817) (xy 92.748406 -4.574995) (xy 92.796792 -4.516633)
			(xy 92.851108 -4.463745) (xy 92.910737 -4.41693) (xy 92.975005 -4.376718) (xy 93.043182 -4.343566)
			(xy 93.114498 -4.317848) (xy 93.188143 -4.299856) (xy 93.263283 -4.289794) (xy 93.339067 -4.287775)
			(xy 93.414637 -4.293824) (xy 93.489135 -4.307871) (xy 93.561718 -4.329757) (xy 93.631564 -4.359234)
			(xy 93.697881 -4.395969) (xy 93.759917 -4.439544) (xy 93.81697 -4.489466) (xy 93.868394 -4.54517)
			(xy 93.913605 -4.606025) (xy 93.952092 -4.67134) (xy 93.983418 -4.740376) (xy 94.007228 -4.812351)
			(xy 94.023253 -4.886449) (xy 94.031312 -4.96183) (xy 94.031816 -4.999736) (xy 94.031312 -5.037642)
			(xy 94.023253 -5.113023) (xy 94.007228 -5.187121) (xy 93.983418 -5.259096) (xy 93.952092 -5.328132)
			(xy 93.913605 -5.393447) (xy 93.868394 -5.454302) (xy 93.81697 -5.510006) (xy 93.759917 -5.559928)
			(xy 93.697881 -5.603503) (xy 93.631564 -5.640238) (xy 93.561718 -5.669715) (xy 93.489135 -5.691601)
			(xy 93.414637 -5.705648) (xy 93.339067 -5.711697) (xy 93.263283 -5.709678) (xy 93.188143 -5.699616)
			(xy 93.114498 -5.681624) (xy 93.043182 -5.655906) (xy 92.975005 -5.622754) (xy 92.910737 -5.582542)
			(xy 92.851108 -5.535727) (xy 92.796792 -5.482839) (xy 92.748406 -5.424477) (xy 92.706498 -5.361302)
			(xy 92.671542 -5.294031) (xy 92.643935 -5.223426) (xy 92.623989 -5.150285) (xy 92.61193 -5.07544)
			(xy 92.607895 -4.999736) (xy 92.03182 -4.999736) (xy 92.031316 -5.037642) (xy 92.023257 -5.113023)
			(xy 92.007232 -5.187121) (xy 91.983422 -5.259096) (xy 91.952096 -5.328132) (xy 91.913609 -5.393447)
			(xy 91.868398 -5.454302) (xy 91.816974 -5.510006) (xy 91.759921 -5.559928) (xy 91.697885 -5.603503)
			(xy 91.631568 -5.640238) (xy 91.561722 -5.669715) (xy 91.489139 -5.691601) (xy 91.414641 -5.705648)
			(xy 91.339071 -5.711697) (xy 91.263287 -5.709678) (xy 91.188147 -5.699616) (xy 91.114502 -5.681624)
			(xy 91.043186 -5.655906) (xy 90.975009 -5.622754) (xy 90.910741 -5.582542) (xy 90.851112 -5.535727)
			(xy 90.796796 -5.482839) (xy 90.74841 -5.424477) (xy 90.706502 -5.361302) (xy 90.671546 -5.294031)
			(xy 90.643939 -5.223426) (xy 90.623993 -5.150285) (xy 90.611934 -5.07544) (xy 90.607899 -4.999736)
			(xy 65.240879 -4.999736) (xy 65.228752 -5.05287) (xy 65.205195 -5.12019) (xy 65.17425 -5.184449)
			(xy 65.136304 -5.24484) (xy 65.091835 -5.300602) (xy 65.041402 -5.351035) (xy 64.98564 -5.395504)
			(xy 64.925249 -5.43345) (xy 64.86099 -5.464395) (xy 64.79367 -5.487952) (xy 64.724135 -5.503822)
			(xy 64.653261 -5.511808) (xy 64.581939 -5.511808) (xy 64.511065 -5.503822) (xy 64.44153 -5.487952)
			(xy 64.37421 -5.464395) (xy 64.309951 -5.43345) (xy 64.24956 -5.395504) (xy 64.193798 -5.351035)
			(xy 64.143365 -5.300602) (xy 64.098896 -5.24484) (xy 64.06095 -5.184449) (xy 64.030005 -5.12019)
			(xy 64.006448 -5.05287) (xy 63.990578 -4.983335) (xy 63.982592 -4.912461) (xy 57.984796 -4.912461)
			(xy 57.988208 -4.942739) (xy 57.988708 -4.9784) (xy 57.988208 -5.014061) (xy 57.980222 -5.084935)
			(xy 57.964352 -5.15447) (xy 57.940795 -5.22179) (xy 57.90985 -5.286049) (xy 57.871904 -5.34644) (xy 57.827435 -5.402202)
			(xy 57.777002 -5.452635) (xy 57.72124 -5.497104) (xy 57.660849 -5.53505) (xy 57.59659 -5.565995)
			(xy 57.52927 -5.589552) (xy 57.459735 -5.605422) (xy 57.388861 -5.613408) (xy 57.317539 -5.613408)
			(xy 57.246665 -5.605422) (xy 57.17713 -5.589552) (xy 57.10981 -5.565995) (xy 57.045551 -5.53505)
			(xy 56.98516 -5.497104) (xy 56.929398 -5.452635) (xy 56.878965 -5.402202) (xy 56.834496 -5.34644)
			(xy 56.79655 -5.286049) (xy 56.765605 -5.22179) (xy 56.742048 -5.15447) (xy 56.726178 -5.084935)
			(xy 56.718192 -5.014061) (xy 50.002293 -5.014061) (xy 50.004622 -5.024265) (xy 50.012608 -5.095139)
			(xy 50.013108 -5.1308) (xy 50.012608 -5.166461) (xy 50.004622 -5.237335) (xy 49.988752 -5.30687)
			(xy 49.965195 -5.37419) (xy 49.93425 -5.438449) (xy 49.896304 -5.49884) (xy 49.851835 -5.554602)
			(xy 49.801402 -5.605035) (xy 49.74564 -5.649504) (xy 49.685249 -5.68745) (xy 49.62099 -5.718395)
			(xy 49.55367 -5.741952) (xy 49.484135 -5.757822) (xy 49.413261 -5.765808) (xy 49.341939 -5.765808)
			(xy 49.271065 -5.757822) (xy 49.20153 -5.741952) (xy 49.13421 -5.718395) (xy 49.069951 -5.68745)
			(xy 49.00956 -5.649504) (xy 48.953798 -5.605035) (xy 48.903365 -5.554602) (xy 48.858896 -5.49884)
			(xy 48.82095 -5.438449) (xy 48.790005 -5.37419) (xy 48.766448 -5.30687) (xy 48.750578 -5.237335)
			(xy 48.742592 -5.166461) (xy 42.65158 -5.166461) (xy 42.649995 -5.17099) (xy 42.61905 -5.235249)
			(xy 42.581104 -5.29564) (xy 42.536635 -5.351402) (xy 42.486202 -5.401835) (xy 42.43044 -5.446304)
			(xy 42.370049 -5.48425) (xy 42.30579 -5.515195) (xy 42.23847 -5.538752) (xy 42.168935 -5.554622)
			(xy 42.098061 -5.562608) (xy 42.026739 -5.562608) (xy 41.955865 -5.554622) (xy 41.88633 -5.538752)
			(xy 41.81901 -5.515195) (xy 41.754751 -5.48425) (xy 41.69436 -5.446304) (xy 41.638598 -5.401835)
			(xy 41.588165 -5.351402) (xy 41.543696 -5.29564) (xy 41.50575 -5.235249) (xy 41.474805 -5.17099)
			(xy 41.451248 -5.10367) (xy 41.435378 -5.034135) (xy 41.427392 -4.963261) (xy 27.860946 -4.963261)
			(xy 27.855822 -5.008735) (xy 27.839952 -5.07827) (xy 27.816395 -5.14559) (xy 27.78545 -5.209849)
			(xy 27.747504 -5.27024) (xy 27.703035 -5.326002) (xy 27.652602 -5.376435) (xy 27.59684 -5.420904)
			(xy 27.536449 -5.45885) (xy 27.47219 -5.489795) (xy 27.40487 -5.513352) (xy 27.335335 -5.529222)
			(xy 27.264461 -5.537208) (xy 27.193139 -5.537208) (xy 27.122265 -5.529222) (xy 27.05273 -5.513352)
			(xy 26.98541 -5.489795) (xy 26.921151 -5.45885) (xy 26.86076 -5.420904) (xy 26.804998 -5.376435)
			(xy 26.754565 -5.326002) (xy 26.710096 -5.27024) (xy 26.67215 -5.209849) (xy 26.641205 -5.14559)
			(xy 26.617648 -5.07827) (xy 26.601778 -5.008735) (xy 26.593792 -4.937861) (xy 20.137849 -4.937861)
			(xy 20.143752 -4.95473) (xy 20.159622 -5.024265) (xy 20.167608 -5.095139) (xy 20.168108 -5.1308)
			(xy 20.167608 -5.166461) (xy 20.159622 -5.237335) (xy 20.143752 -5.30687) (xy 20.120195 -5.37419)
			(xy 20.08925 -5.438449) (xy 20.051304 -5.49884) (xy 20.006835 -5.554602) (xy 19.956402 -5.605035)
			(xy 19.90064 -5.649504) (xy 19.840249 -5.68745) (xy 19.77599 -5.718395) (xy 19.756369 -5.725261)
			(xy 22.275792 -5.725261) (xy 22.275792 -5.653939) (xy 22.283778 -5.583065) (xy 22.299648 -5.51353)
			(xy 22.323205 -5.44621) (xy 22.35415 -5.381951) (xy 22.392096 -5.32156) (xy 22.436565 -5.265798)
			(xy 22.486998 -5.215365) (xy 22.54276 -5.170896) (xy 22.603151 -5.13295) (xy 22.66741 -5.102005)
			(xy 22.73473 -5.078448) (xy 22.804265 -5.062578) (xy 22.875139 -5.054592) (xy 22.946461 -5.054592)
			(xy 23.017335 -5.062578) (xy 23.08687 -5.078448) (xy 23.15419 -5.102005) (xy 23.218449 -5.13295)
			(xy 23.27884 -5.170896) (xy 23.334602 -5.215365) (xy 23.385035 -5.265798) (xy 23.429504 -5.32156)
			(xy 23.46745 -5.381951) (xy 23.498395 -5.44621) (xy 23.521952 -5.51353) (xy 23.537822 -5.583065)
			(xy 23.545808 -5.653939) (xy 23.546308 -5.6896) (xy 23.545808 -5.725261) (xy 23.537822 -5.796135)
			(xy 23.521952 -5.86567) (xy 23.498395 -5.93299) (xy 23.46745 -5.997249) (xy 23.429504 -6.05764) (xy 23.385035 -6.113402)
			(xy 23.334602 -6.163835) (xy 23.27884 -6.208304) (xy 23.218449 -6.24625) (xy 23.15419 -6.277195)
			(xy 23.08687 -6.300752) (xy 23.017335 -6.316622) (xy 22.946461 -6.324608) (xy 22.875139 -6.324608)
			(xy 22.804265 -6.316622) (xy 22.73473 -6.300752) (xy 22.66741 -6.277195) (xy 22.603151 -6.24625)
			(xy 22.54276 -6.208304) (xy 22.486998 -6.163835) (xy 22.436565 -6.113402) (xy 22.392096 -6.05764)
			(xy 22.35415 -5.997249) (xy 22.323205 -5.93299) (xy 22.299648 -5.86567) (xy 22.283778 -5.796135)
			(xy 22.275792 -5.725261) (xy 19.756369 -5.725261) (xy 19.70867 -5.741952) (xy 19.639135 -5.757822)
			(xy 19.568261 -5.765808) (xy 19.496939 -5.765808) (xy 19.426065 -5.757822) (xy 19.35653 -5.741952)
			(xy 19.28921 -5.718395) (xy 19.224951 -5.68745) (xy 19.16456 -5.649504) (xy 19.108798 -5.605035)
			(xy 19.058365 -5.554602) (xy 19.013896 -5.49884) (xy 18.97595 -5.438449) (xy 18.945005 -5.37419)
			(xy 18.921448 -5.30687) (xy 18.905578 -5.237335) (xy 18.897592 -5.166461) (xy 9.6774 -5.166461) (xy 9.6774 -6.361938)
			(xy 9.677878 -6.384339) (xy 9.68574 -6.428446) (xy 9.701215 -6.470491) (xy 9.723822 -6.50917) (xy 9.752862 -6.543287)
			(xy 9.787434 -6.571783) (xy 9.826467 -6.593775) (xy 9.868751 -6.608582) (xy 9.912977 -6.615746) (xy 9.957773 -6.615043)
			(xy 10.001753 -6.606497) (xy 10.02284 -6.59892) (xy 10.063648 -6.583712) (xy 10.147408 -6.559844)
			(xy 10.232978 -6.543616) (xy 10.31966 -6.535158) (xy 10.406753 -6.534539) (xy 10.493547 -6.541766)
			(xy 10.579338 -6.556778) (xy 10.663428 -6.579454) (xy 10.745136 -6.609609) (xy 10.823796 -6.647)
			(xy 10.898769 -6.691321) (xy 10.969448 -6.742213) (xy 11.035257 -6.799263) (xy 11.095661 -6.862006)
			(xy 11.150171 -6.929934) (xy 11.198342 -7.002494) (xy 11.239785 -7.079097) (xy 11.274161 -7.15912)
			(xy 11.301192 -7.241913) (xy 11.320659 -7.326804) (xy 11.332402 -7.413103) (xy 11.336328 -7.500109)
			(xy 11.336186 -7.503261) (xy 25.399992 -7.503261) (xy 25.399992 -7.431939) (xy 25.407978 -7.361065)
			(xy 25.423848 -7.29153) (xy 25.447405 -7.22421) (xy 25.47835 -7.159951) (xy 25.516296 -7.09956) (xy 25.560765 -7.043798)
			(xy 25.611198 -6.993365) (xy 25.66696 -6.948896) (xy 25.727351 -6.91095) (xy 25.79161 -6.880005)
			(xy 25.85893 -6.856448) (xy 25.928465 -6.840578) (xy 25.999339 -6.832592) (xy 26.070661 -6.832592)
			(xy 26.141535 -6.840578) (xy 26.21107 -6.856448) (xy 26.27839 -6.880005) (xy 26.342649 -6.91095)
			(xy 26.40304 -6.948896) (xy 26.458802 -6.993365) (xy 26.465169 -6.999732) (xy 90.607899 -6.999732)
			(xy 90.611934 -6.924028) (xy 90.623993 -6.849183) (xy 90.643939 -6.776042) (xy 90.671546 -6.705437)
			(xy 90.706502 -6.638166) (xy 90.74841 -6.574991) (xy 90.796796 -6.516629) (xy 90.851112 -6.463741)
			(xy 90.910741 -6.416926) (xy 90.975009 -6.376714) (xy 91.043186 -6.343562) (xy 91.114502 -6.317844)
			(xy 91.188147 -6.299852) (xy 91.263287 -6.28979) (xy 91.339071 -6.287771) (xy 91.414641 -6.29382)
			(xy 91.489139 -6.307867) (xy 91.561722 -6.329753) (xy 91.631568 -6.35923) (xy 91.697885 -6.395965)
			(xy 91.759921 -6.43954) (xy 91.816974 -6.489462) (xy 91.868398 -6.545166) (xy 91.913609 -6.606021)
			(xy 91.952096 -6.671336) (xy 91.983422 -6.740372) (xy 92.007232 -6.812347) (xy 92.023257 -6.886445)
			(xy 92.031316 -6.961826) (xy 92.03182 -6.999732) (xy 92.607895 -6.999732) (xy 92.61193 -6.924028)
			(xy 92.623989 -6.849183) (xy 92.643935 -6.776042) (xy 92.671542 -6.705437) (xy 92.706498 -6.638166)
			(xy 92.748406 -6.574991) (xy 92.796792 -6.516629) (xy 92.851108 -6.463741) (xy 92.910737 -6.416926)
			(xy 92.975005 -6.376714) (xy 93.043182 -6.343562) (xy 93.114498 -6.317844) (xy 93.188143 -6.299852)
			(xy 93.263283 -6.28979) (xy 93.339067 -6.287771) (xy 93.414637 -6.29382) (xy 93.489135 -6.307867)
			(xy 93.561718 -6.329753) (xy 93.631564 -6.35923) (xy 93.697881 -6.395965) (xy 93.759917 -6.43954)
			(xy 93.81697 -6.489462) (xy 93.868394 -6.545166) (xy 93.913605 -6.606021) (xy 93.952092 -6.671336)
			(xy 93.983418 -6.740372) (xy 94.007228 -6.812347) (xy 94.023253 -6.886445) (xy 94.031312 -6.961826)
			(xy 94.031816 -6.999732) (xy 94.031312 -7.037638) (xy 94.023253 -7.113019) (xy 94.007228 -7.187117)
			(xy 93.983418 -7.259092) (xy 93.952092 -7.328128) (xy 93.913605 -7.393443) (xy 93.868394 -7.454298)
			(xy 93.81697 -7.510002) (xy 93.759917 -7.559924) (xy 93.697881 -7.603499) (xy 93.631564 -7.640234)
			(xy 93.561718 -7.669711) (xy 93.489135 -7.691597) (xy 93.414637 -7.705644) (xy 93.339067 -7.711693)
			(xy 93.263283 -7.709674) (xy 93.188143 -7.699612) (xy 93.114498 -7.68162) (xy 93.043182 -7.655902)
			(xy 92.975005 -7.62275) (xy 92.910737 -7.582538) (xy 92.851108 -7.535723) (xy 92.796792 -7.482835)
			(xy 92.748406 -7.424473) (xy 92.706498 -7.361298) (xy 92.671542 -7.294027) (xy 92.643935 -7.223422)
			(xy 92.623989 -7.150281) (xy 92.61193 -7.075436) (xy 92.607895 -6.999732) (xy 92.03182 -6.999732)
			(xy 92.031316 -7.037638) (xy 92.023257 -7.113019) (xy 92.007232 -7.187117) (xy 91.983422 -7.259092)
			(xy 91.952096 -7.328128) (xy 91.913609 -7.393443) (xy 91.868398 -7.454298) (xy 91.816974 -7.510002)
			(xy 91.759921 -7.559924) (xy 91.697885 -7.603499) (xy 91.631568 -7.640234) (xy 91.561722 -7.669711)
			(xy 91.489139 -7.691597) (xy 91.414641 -7.705644) (xy 91.339071 -7.711693) (xy 91.263287 -7.709674)
			(xy 91.188147 -7.699612) (xy 91.114502 -7.68162) (xy 91.043186 -7.655902) (xy 90.975009 -7.62275)
			(xy 90.910741 -7.582538) (xy 90.851112 -7.535723) (xy 90.796796 -7.482835) (xy 90.74841 -7.424473)
			(xy 90.706502 -7.361298) (xy 90.671546 -7.294027) (xy 90.643939 -7.223422) (xy 90.623993 -7.150281)
			(xy 90.611934 -7.075436) (xy 90.607899 -6.999732) (xy 26.465169 -6.999732) (xy 26.509235 -7.043798)
			(xy 26.553704 -7.09956) (xy 26.59165 -7.159951) (xy 26.622595 -7.22421) (xy 26.646152 -7.29153) (xy 26.662022 -7.361065)
			(xy 26.670008 -7.431939) (xy 26.670508 -7.4676) (xy 26.670008 -7.503261) (xy 26.662022 -7.574135)
			(xy 26.646152 -7.64367) (xy 26.622595 -7.71099) (xy 26.59165 -7.775249) (xy 26.553704 -7.83564) (xy 26.51493 -7.884261)
			(xy 49.606192 -7.884261) (xy 49.606192 -7.812939) (xy 49.614178 -7.742065) (xy 49.630048 -7.67253)
			(xy 49.653605 -7.60521) (xy 49.68455 -7.540951) (xy 49.722496 -7.48056) (xy 49.766965 -7.424798)
			(xy 49.817398 -7.374365) (xy 49.87316 -7.329896) (xy 49.933551 -7.29195) (xy 49.99781 -7.261005)
			(xy 50.06513 -7.237448) (xy 50.134665 -7.221578) (xy 50.205539 -7.213592) (xy 50.276861 -7.213592)
			(xy 50.347735 -7.221578) (xy 50.41727 -7.237448) (xy 50.48459 -7.261005) (xy 50.548849 -7.29195)
			(xy 50.60924 -7.329896) (xy 50.665002 -7.374365) (xy 50.715435 -7.424798) (xy 50.759904 -7.48056)
			(xy 50.79785 -7.540951) (xy 50.828795 -7.60521) (xy 50.852352 -7.67253) (xy 50.868222 -7.742065)
			(xy 50.876208 -7.812939) (xy 50.876708 -7.8486) (xy 50.876208 -7.884261) (xy 57.581792 -7.884261)
			(xy 57.581792 -7.812939) (xy 57.589778 -7.742065) (xy 57.605648 -7.67253) (xy 57.629205 -7.60521)
			(xy 57.66015 -7.540951) (xy 57.698096 -7.48056) (xy 57.742565 -7.424798) (xy 57.792998 -7.374365)
			(xy 57.84876 -7.329896) (xy 57.909151 -7.29195) (xy 57.97341 -7.261005) (xy 58.04073 -7.237448) (xy 58.110265 -7.221578)
			(xy 58.181139 -7.213592) (xy 58.252461 -7.213592) (xy 58.323335 -7.221578) (xy 58.39287 -7.237448)
			(xy 58.46019 -7.261005) (xy 58.524449 -7.29195) (xy 58.58484 -7.329896) (xy 58.640602 -7.374365)
			(xy 58.691035 -7.424798) (xy 58.735504 -7.48056) (xy 58.77345 -7.540951) (xy 58.804395 -7.60521)
			(xy 58.827952 -7.67253) (xy 58.843822 -7.742065) (xy 58.851808 -7.812939) (xy 58.852308 -7.8486)
			(xy 58.851808 -7.884261) (xy 58.843822 -7.955135) (xy 58.827952 -8.02467) (xy 58.804395 -8.09199)
			(xy 58.77345 -8.156249) (xy 58.735504 -8.21664) (xy 58.691035 -8.272402) (xy 58.640602 -8.322835)
			(xy 58.58484 -8.367304) (xy 58.524449 -8.40525) (xy 58.46019 -8.436195) (xy 58.39287 -8.459752) (xy 58.323335 -8.475622)
			(xy 58.252461 -8.483608) (xy 58.181139 -8.483608) (xy 58.110265 -8.475622) (xy 58.04073 -8.459752)
			(xy 57.97341 -8.436195) (xy 57.909151 -8.40525) (xy 57.84876 -8.367304) (xy 57.792998 -8.322835)
			(xy 57.742565 -8.272402) (xy 57.698096 -8.21664) (xy 57.66015 -8.156249) (xy 57.629205 -8.09199)
			(xy 57.605648 -8.02467) (xy 57.589778 -7.955135) (xy 57.581792 -7.884261) (xy 50.876208 -7.884261)
			(xy 50.868222 -7.955135) (xy 50.852352 -8.02467) (xy 50.828795 -8.09199) (xy 50.79785 -8.156249)
			(xy 50.759904 -8.21664) (xy 50.715435 -8.272402) (xy 50.665002 -8.322835) (xy 50.60924 -8.367304)
			(xy 50.548849 -8.40525) (xy 50.48459 -8.436195) (xy 50.41727 -8.459752) (xy 50.347735 -8.475622)
			(xy 50.276861 -8.483608) (xy 50.205539 -8.483608) (xy 50.134665 -8.475622) (xy 50.06513 -8.459752)
			(xy 49.99781 -8.436195) (xy 49.933551 -8.40525) (xy 49.87316 -8.367304) (xy 49.817398 -8.322835)
			(xy 49.766965 -8.272402) (xy 49.722496 -8.21664) (xy 49.68455 -8.156249) (xy 49.653605 -8.09199)
			(xy 49.630048 -8.02467) (xy 49.614178 -7.955135) (xy 49.606192 -7.884261) (xy 26.51493 -7.884261)
			(xy 26.509235 -7.891402) (xy 26.458802 -7.941835) (xy 26.40304 -7.986304) (xy 26.342649 -8.02425)
			(xy 26.27839 -8.055195) (xy 26.21107 -8.078752) (xy 26.141535 -8.094622) (xy 26.070661 -8.102608)
			(xy 25.999339 -8.102608) (xy 25.928465 -8.094622) (xy 25.85893 -8.078752) (xy 25.79161 -8.055195)
			(xy 25.727351 -8.02425) (xy 25.66696 -7.986304) (xy 25.611198 -7.941835) (xy 25.560765 -7.891402)
			(xy 25.516296 -7.83564) (xy 25.47835 -7.775249) (xy 25.447405 -7.71099) (xy 25.423848 -7.64367) (xy 25.407978 -7.574135)
			(xy 25.399992 -7.503261) (xy 11.336186 -7.503261) (xy 11.332403 -7.587115) (xy 11.320659 -7.673414)
			(xy 11.301193 -7.758305) (xy 11.274162 -7.841099) (xy 11.239785 -7.921122) (xy 11.198343 -7.997725)
			(xy 11.150171 -8.070285) (xy 11.095662 -8.138213) (xy 11.035258 -8.200956) (xy 10.969449 -8.258006)
			(xy 10.898771 -8.308898) (xy 10.823797 -8.35322) (xy 10.745137 -8.39061) (xy 10.66343 -8.420766)
			(xy 10.579339 -8.443442) (xy 10.493548 -8.458454) (xy 10.406754 -8.465681) (xy 10.319662 -8.465062)
			(xy 10.232979 -8.456605) (xy 10.14741 -8.440376) (xy 10.06365 -8.416508) (xy 10.02284 -8.401304)
			(xy 10.001766 -8.393682) (xy 9.95778 -8.385133) (xy 9.912976 -8.38443) (xy 9.868743 -8.391594) (xy 9.826452 -8.406405)
			(xy 9.787414 -8.428401) (xy 9.752837 -8.456903) (xy 9.723794 -8.491027) (xy 9.701186 -8.529714) (xy 9.685711 -8.571767)
			(xy 9.677851 -8.615881) (xy 9.6774 -8.638286) (xy 9.6774 -8.646261) (xy 30.149792 -8.646261) (xy 30.149792 -8.574939)
			(xy 30.157778 -8.504065) (xy 30.173648 -8.43453) (xy 30.197205 -8.36721) (xy 30.22815 -8.302951)
			(xy 30.266096 -8.24256) (xy 30.310565 -8.186798) (xy 30.360998 -8.136365) (xy 30.41676 -8.091896)
			(xy 30.477151 -8.05395) (xy 30.54141 -8.023005) (xy 30.60873 -7.999448) (xy 30.678265 -7.983578)
			(xy 30.749139 -7.975592) (xy 30.820461 -7.975592) (xy 30.891335 -7.983578) (xy 30.96087 -7.999448)
			(xy 31.02819 -8.023005) (xy 31.092449 -8.05395) (xy 31.15284 -8.091896) (xy 31.208602 -8.136365)
			(xy 31.259035 -8.186798) (xy 31.303504 -8.24256) (xy 31.34145 -8.302951) (xy 31.372395 -8.36721)
			(xy 31.395952 -8.43453) (xy 31.411822 -8.504065) (xy 31.419808 -8.574939) (xy 31.420308 -8.6106)
			(xy 31.419808 -8.646261) (xy 31.411822 -8.717135) (xy 31.395952 -8.78667) (xy 31.372395 -8.85399)
			(xy 31.34145 -8.918249) (xy 31.303504 -8.97864) (xy 31.259035 -9.034402) (xy 31.208602 -9.084835)
			(xy 31.153396 -9.128861) (xy 37.845992 -9.128861) (xy 37.845992 -9.057539) (xy 37.853978 -8.986665)
			(xy 37.869848 -8.91713) (xy 37.893405 -8.84981) (xy 37.92435 -8.785551) (xy 37.962296 -8.72516) (xy 38.006765 -8.669398)
			(xy 38.057198 -8.618965) (xy 38.11296 -8.574496) (xy 38.173351 -8.53655) (xy 38.23761 -8.505605)
			(xy 38.30493 -8.482048) (xy 38.374465 -8.466178) (xy 38.445339 -8.458192) (xy 38.516661 -8.458192)
			(xy 38.587535 -8.466178) (xy 38.65707 -8.482048) (xy 38.72439 -8.505605) (xy 38.788649 -8.53655)
			(xy 38.84904 -8.574496) (xy 38.904802 -8.618965) (xy 38.955235 -8.669398) (xy 38.999704 -8.72516)
			(xy 39.03765 -8.785551) (xy 39.068595 -8.84981) (xy 39.092152 -8.91713) (xy 39.108022 -8.986665)
			(xy 39.116008 -9.057539) (xy 39.116508 -9.0932) (xy 39.116008 -9.128861) (xy 39.108022 -9.199735)
			(xy 39.092152 -9.26927) (xy 39.07018 -9.332061) (xy 46.126392 -9.332061) (xy 46.126392 -9.260739)
			(xy 46.134378 -9.189865) (xy 46.150248 -9.12033) (xy 46.173805 -9.05301) (xy 46.20475 -8.988751)
			(xy 46.242696 -8.92836) (xy 46.287165 -8.872598) (xy 46.337598 -8.822165) (xy 46.39336 -8.777696)
			(xy 46.453751 -8.73975) (xy 46.51801 -8.708805) (xy 46.58533 -8.685248) (xy 46.654865 -8.669378)
			(xy 46.725739 -8.661392) (xy 46.797061 -8.661392) (xy 46.867935 -8.669378) (xy 46.93747 -8.685248)
			(xy 47.00479 -8.708805) (xy 47.069049 -8.73975) (xy 47.12944 -8.777696) (xy 47.185202 -8.822165)
			(xy 47.235635 -8.872598) (xy 47.280104 -8.92836) (xy 47.31805 -8.988751) (xy 47.348995 -9.05301)
			(xy 47.372552 -9.12033) (xy 47.374499 -9.128861) (xy 53.898792 -9.128861) (xy 53.898792 -9.057539)
			(xy 53.906778 -8.986665) (xy 53.922648 -8.91713) (xy 53.946205 -8.84981) (xy 53.97715 -8.785551)
			(xy 54.015096 -8.72516) (xy 54.059565 -8.669398) (xy 54.109998 -8.618965) (xy 54.16576 -8.574496)
			(xy 54.226151 -8.53655) (xy 54.29041 -8.505605) (xy 54.35773 -8.482048) (xy 54.427265 -8.466178)
			(xy 54.498139 -8.458192) (xy 54.569461 -8.458192) (xy 54.640335 -8.466178) (xy 54.70987 -8.482048)
			(xy 54.77719 -8.505605) (xy 54.841449 -8.53655) (xy 54.90184 -8.574496) (xy 54.957602 -8.618965)
			(xy 55.008035 -8.669398) (xy 55.052504 -8.72516) (xy 55.09045 -8.785551) (xy 55.121395 -8.84981)
			(xy 55.144952 -8.91713) (xy 55.160822 -8.986665) (xy 55.168808 -9.057539) (xy 55.169308 -9.0932)
			(xy 55.168808 -9.128861) (xy 55.160822 -9.199735) (xy 55.144952 -9.26927) (xy 55.12298 -9.332061)
			(xy 61.569592 -9.332061) (xy 61.569592 -9.260739) (xy 61.577578 -9.189865) (xy 61.593448 -9.12033)
			(xy 61.617005 -9.05301) (xy 61.64795 -8.988751) (xy 61.685896 -8.92836) (xy 61.730365 -8.872598)
			(xy 61.780798 -8.822165) (xy 61.83656 -8.777696) (xy 61.896951 -8.73975) (xy 61.96121 -8.708805)
			(xy 62.02853 -8.685248) (xy 62.098065 -8.669378) (xy 62.168939 -8.661392) (xy 62.240261 -8.661392)
			(xy 62.311135 -8.669378) (xy 62.38067 -8.685248) (xy 62.44799 -8.708805) (xy 62.512249 -8.73975)
			(xy 62.57264 -8.777696) (xy 62.628402 -8.822165) (xy 62.678835 -8.872598) (xy 62.723304 -8.92836)
			(xy 62.76125 -8.988751) (xy 62.792195 -9.05301) (xy 62.815752 -9.12033) (xy 62.831622 -9.189865)
			(xy 62.836196 -9.230461) (xy 67.513192 -9.230461) (xy 67.513192 -9.159139) (xy 67.521178 -9.088265)
			(xy 67.537048 -9.01873) (xy 67.560605 -8.95141) (xy 67.59155 -8.887151) (xy 67.629496 -8.82676) (xy 67.673965 -8.770998)
			(xy 67.724398 -8.720565) (xy 67.78016 -8.676096) (xy 67.840551 -8.63815) (xy 67.90481 -8.607205)
			(xy 67.97213 -8.583648) (xy 68.041665 -8.567778) (xy 68.112539 -8.559792) (xy 68.183861 -8.559792)
			(xy 68.254735 -8.567778) (xy 68.32427 -8.583648) (xy 68.39159 -8.607205) (xy 68.455849 -8.63815)
			(xy 68.51624 -8.676096) (xy 68.572002 -8.720565) (xy 68.622435 -8.770998) (xy 68.666904 -8.82676)
			(xy 68.70485 -8.887151) (xy 68.735795 -8.95141) (xy 68.759352 -9.01873) (xy 68.775222 -9.088265)
			(xy 68.783208 -9.159139) (xy 68.783708 -9.1948) (xy 68.783208 -9.230461) (xy 68.775222 -9.301335)
			(xy 68.759352 -9.37087) (xy 68.735795 -9.43819) (xy 68.70485 -9.502449) (xy 68.672353 -9.554168)
			(xy 87.83395 -9.554168) (xy 87.83395 -9.44554) (xy 87.841879 -9.337202) (xy 87.857696 -9.229731)
			(xy 87.881315 -9.123702) (xy 87.912611 -9.01968) (xy 87.951416 -8.918219) (xy 87.997524 -8.819862)
			(xy 88.050688 -8.725133) (xy 88.110626 -8.634538) (xy 88.177016 -8.548559) (xy 88.249506 -8.467656)
			(xy 88.327707 -8.39226) (xy 88.411204 -8.322774) (xy 88.49955 -8.259567) (xy 88.592274 -8.202979)
			(xy 88.688882 -8.153309) (xy 88.788857 -8.110824) (xy 88.891667 -8.075751) (xy 88.996763 -8.048275)
			(xy 89.103584 -8.028544) (xy 89.21156 -8.016663) (xy 89.320116 -8.012696) (xy 89.428672 -8.016663)
			(xy 89.536648 -8.028544) (xy 89.643469 -8.048275) (xy 89.748565 -8.075751) (xy 89.851375 -8.110824)
			(xy 89.95135 -8.153309) (xy 90.047958 -8.202979) (xy 90.140682 -8.259567) (xy 90.229028 -8.322774)
			(xy 90.312525 -8.39226) (xy 90.390726 -8.467656) (xy 90.463216 -8.548559) (xy 90.529606 -8.634538)
			(xy 90.589544 -8.725133) (xy 90.642708 -8.819862) (xy 90.688816 -8.918219) (xy 90.727621 -9.01968)
			(xy 90.758917 -9.123702) (xy 90.782536 -9.229731) (xy 90.798353 -9.337202) (xy 90.806282 -9.44554)
			(xy 90.806778 -9.499854) (xy 90.806282 -9.554168) (xy 90.798353 -9.662506) (xy 90.782536 -9.769977)
			(xy 90.758917 -9.876006) (xy 90.727621 -9.980028) (xy 90.688816 -10.081489) (xy 90.642708 -10.179846)
			(xy 90.589544 -10.274575) (xy 90.529606 -10.36517) (xy 90.463216 -10.451149) (xy 90.390726 -10.532052)
			(xy 90.312525 -10.607448) (xy 90.229028 -10.676934) (xy 90.140682 -10.740141) (xy 90.047958 -10.796729)
			(xy 89.95135 -10.846399) (xy 89.851375 -10.888884) (xy 89.748565 -10.923957) (xy 89.643469 -10.951433)
			(xy 89.536648 -10.971164) (xy 89.428672 -10.983045) (xy 89.320116 -10.987012) (xy 89.21156 -10.983045)
			(xy 89.103584 -10.971164) (xy 88.996763 -10.951433) (xy 88.891667 -10.923957) (xy 88.788857 -10.888884)
			(xy 88.688882 -10.846399) (xy 88.592274 -10.796729) (xy 88.49955 -10.740141) (xy 88.411204 -10.676934)
			(xy 88.327707 -10.607448) (xy 88.249506 -10.532052) (xy 88.177016 -10.451149) (xy 88.110626 -10.36517)
			(xy 88.050688 -10.274575) (xy 87.997524 -10.179846) (xy 87.951416 -10.081489) (xy 87.912611 -9.980028)
			(xy 87.881315 -9.876006) (xy 87.857696 -9.769977) (xy 87.841879 -9.662506) (xy 87.83395 -9.554168)
			(xy 68.672353 -9.554168) (xy 68.666904 -9.56284) (xy 68.622435 -9.618602) (xy 68.572002 -9.669035)
			(xy 68.51624 -9.713504) (xy 68.455849 -9.75145) (xy 68.39159 -9.782395) (xy 68.32427 -9.805952) (xy 68.254735 -9.821822)
			(xy 68.183861 -9.829808) (xy 68.112539 -9.829808) (xy 68.041665 -9.821822) (xy 67.97213 -9.805952)
			(xy 67.90481 -9.782395) (xy 67.840551 -9.75145) (xy 67.78016 -9.713504) (xy 67.724398 -9.669035)
			(xy 67.673965 -9.618602) (xy 67.629496 -9.56284) (xy 67.59155 -9.502449) (xy 67.560605 -9.43819)
			(xy 67.537048 -9.37087) (xy 67.521178 -9.301335) (xy 67.513192 -9.230461) (xy 62.836196 -9.230461)
			(xy 62.839608 -9.260739) (xy 62.840108 -9.2964) (xy 62.839608 -9.332061) (xy 62.831622 -9.402935)
			(xy 62.815752 -9.47247) (xy 62.792195 -9.53979) (xy 62.76125 -9.604049) (xy 62.723304 -9.66444) (xy 62.678835 -9.720202)
			(xy 62.628402 -9.770635) (xy 62.57264 -9.815104) (xy 62.512249 -9.85305) (xy 62.44799 -9.883995)
			(xy 62.38067 -9.907552) (xy 62.311135 -9.923422) (xy 62.240261 -9.931408) (xy 62.168939 -9.931408)
			(xy 62.098065 -9.923422) (xy 62.02853 -9.907552) (xy 61.96121 -9.883995) (xy 61.896951 -9.85305)
			(xy 61.83656 -9.815104) (xy 61.780798 -9.770635) (xy 61.730365 -9.720202) (xy 61.685896 -9.66444)
			(xy 61.64795 -9.604049) (xy 61.617005 -9.53979) (xy 61.593448 -9.47247) (xy 61.577578 -9.402935)
			(xy 61.569592 -9.332061) (xy 55.12298 -9.332061) (xy 55.121395 -9.33659) (xy 55.09045 -9.400849)
			(xy 55.052504 -9.46124) (xy 55.008035 -9.517002) (xy 54.957602 -9.567435) (xy 54.90184 -9.611904)
			(xy 54.841449 -9.64985) (xy 54.77719 -9.680795) (xy 54.70987 -9.704352) (xy 54.640335 -9.720222)
			(xy 54.569461 -9.728208) (xy 54.498139 -9.728208) (xy 54.427265 -9.720222) (xy 54.35773 -9.704352)
			(xy 54.29041 -9.680795) (xy 54.226151 -9.64985) (xy 54.16576 -9.611904) (xy 54.109998 -9.567435)
			(xy 54.059565 -9.517002) (xy 54.015096 -9.46124) (xy 53.97715 -9.400849) (xy 53.946205 -9.33659)
			(xy 53.922648 -9.26927) (xy 53.906778 -9.199735) (xy 53.898792 -9.128861) (xy 47.374499 -9.128861)
			(xy 47.388422 -9.189865) (xy 47.396408 -9.260739) (xy 47.396908 -9.2964) (xy 47.396408 -9.332061)
			(xy 47.388422 -9.402935) (xy 47.372552 -9.47247) (xy 47.348995 -9.53979) (xy 47.31805 -9.604049)
			(xy 47.280104 -9.66444) (xy 47.235635 -9.720202) (xy 47.185202 -9.770635) (xy 47.12944 -9.815104)
			(xy 47.069049 -9.85305) (xy 47.00479 -9.883995) (xy 46.93747 -9.907552) (xy 46.867935 -9.923422)
			(xy 46.797061 -9.931408) (xy 46.725739 -9.931408) (xy 46.654865 -9.923422) (xy 46.58533 -9.907552)
			(xy 46.51801 -9.883995) (xy 46.453751 -9.85305) (xy 46.39336 -9.815104) (xy 46.337598 -9.770635)
			(xy 46.287165 -9.720202) (xy 46.242696 -9.66444) (xy 46.20475 -9.604049) (xy 46.173805 -9.53979)
			(xy 46.150248 -9.47247) (xy 46.134378 -9.402935) (xy 46.126392 -9.332061) (xy 39.07018 -9.332061)
			(xy 39.068595 -9.33659) (xy 39.03765 -9.400849) (xy 38.999704 -9.46124) (xy 38.955235 -9.517002)
			(xy 38.904802 -9.567435) (xy 38.84904 -9.611904) (xy 38.788649 -9.64985) (xy 38.72439 -9.680795)
			(xy 38.65707 -9.704352) (xy 38.587535 -9.720222) (xy 38.516661 -9.728208) (xy 38.445339 -9.728208)
			(xy 38.374465 -9.720222) (xy 38.30493 -9.704352) (xy 38.23761 -9.680795) (xy 38.173351 -9.64985)
			(xy 38.11296 -9.611904) (xy 38.057198 -9.567435) (xy 38.006765 -9.517002) (xy 37.962296 -9.46124)
			(xy 37.92435 -9.400849) (xy 37.893405 -9.33659) (xy 37.869848 -9.26927) (xy 37.853978 -9.199735)
			(xy 37.845992 -9.128861) (xy 31.153396 -9.128861) (xy 31.15284 -9.129304) (xy 31.092449 -9.16725)
			(xy 31.02819 -9.198195) (xy 30.96087 -9.221752) (xy 30.891335 -9.237622) (xy 30.820461 -9.245608)
			(xy 30.749139 -9.245608) (xy 30.678265 -9.237622) (xy 30.60873 -9.221752) (xy 30.54141 -9.198195)
			(xy 30.477151 -9.16725) (xy 30.41676 -9.129304) (xy 30.360998 -9.084835) (xy 30.310565 -9.034402)
			(xy 30.266096 -8.97864) (xy 30.22815 -8.918249) (xy 30.197205 -8.85399) (xy 30.173648 -8.78667) (xy 30.157778 -8.717135)
			(xy 30.149792 -8.646261) (xy 9.6774 -8.646261) (xy 9.6774 -10.542969) (xy 10.382999 -10.542969) (xy 10.382999 -10.457243)
			(xy 10.390909 -10.371883) (xy 10.406661 -10.287616) (xy 10.430121 -10.205163) (xy 10.461089 -10.125226)
			(xy 10.4993 -10.048487) (xy 10.544429 -9.975601) (xy 10.59609 -9.90719) (xy 10.653844 -9.843838)
			(xy 10.717196 -9.786084) (xy 10.785607 -9.734423) (xy 10.858493 -9.689294) (xy 10.935232 -9.651083)
			(xy 11.015169 -9.620115) (xy 11.097622 -9.596655) (xy 11.181889 -9.580903) (xy 11.267249 -9.572993)
			(xy 11.352975 -9.572993) (xy 11.438335 -9.580903) (xy 11.522602 -9.596655) (xy 11.605055 -9.620115)
			(xy 11.684992 -9.651083) (xy 11.761731 -9.689294) (xy 11.834617 -9.734423) (xy 11.903028 -9.786084)
			(xy 11.96638 -9.843838) (xy 12.024134 -9.90719) (xy 12.075795 -9.975601) (xy 12.120924 -10.048487)
			(xy 12.159135 -10.125226) (xy 12.190103 -10.205163) (xy 12.213563 -10.287616) (xy 12.229315 -10.371883)
			(xy 12.237225 -10.457243) (xy 12.237392 -10.471663) (xy 26.161741 -10.471663) (xy 26.161741 -10.356337)
			(xy 26.169786 -10.241291) (xy 26.185836 -10.127087) (xy 26.209814 -10.014281) (xy 26.241602 -9.903422)
			(xy 26.281046 -9.79505) (xy 26.327954 -9.689694) (xy 26.382096 -9.587867) (xy 26.44321 -9.490065)
			(xy 26.510997 -9.396764) (xy 26.585127 -9.308419) (xy 26.66524 -9.22546) (xy 26.750944 -9.148291)
			(xy 26.841823 -9.077289) (xy 26.937433 -9.012799) (xy 27.037308 -8.955136) (xy 27.140963 -8.90458)
			(xy 27.247892 -8.861378) (xy 27.357574 -8.82574) (xy 27.469475 -8.79784) (xy 27.583049 -8.777814)
			(xy 27.697744 -8.765759) (xy 27.813 -8.761735) (xy 27.928256 -8.765759) (xy 28.042951 -8.777814)
			(xy 28.156525 -8.79784) (xy 28.268426 -8.82574) (xy 28.378108 -8.861378) (xy 28.485037 -8.90458)
			(xy 28.588692 -8.955136) (xy 28.688567 -9.012799) (xy 28.784177 -9.077289) (xy 28.875056 -9.148291)
			(xy 28.96076 -9.22546) (xy 29.040873 -9.308419) (xy 29.115003 -9.396764) (xy 29.18279 -9.490065)
			(xy 29.243904 -9.587867) (xy 29.298046 -9.689694) (xy 29.344954 -9.79505) (xy 29.384398 -9.903422)
			(xy 29.416186 -10.014281) (xy 29.440164 -10.127087) (xy 29.456214 -10.241291) (xy 29.464259 -10.356337)
			(xy 29.464762 -10.414) (xy 29.464451 -10.449661) (xy 30.835592 -10.449661) (xy 30.835592 -10.378339)
			(xy 30.843578 -10.307465) (xy 30.859448 -10.23793) (xy 30.883005 -10.17061) (xy 30.91395 -10.106351)
			(xy 30.951896 -10.04596) (xy 30.996365 -9.990198) (xy 31.046798 -9.939765) (xy 31.10256 -9.895296)
			(xy 31.162951 -9.85735) (xy 31.22721 -9.826405) (xy 31.29453 -9.802848) (xy 31.364065 -9.786978)
			(xy 31.434939 -9.778992) (xy 31.506261 -9.778992) (xy 31.577135 -9.786978) (xy 31.64667 -9.802848)
			(xy 31.71399 -9.826405) (xy 31.778249 -9.85735) (xy 31.83864 -9.895296) (xy 31.894402 -9.939765)
			(xy 31.944835 -9.990198) (xy 31.989304 -10.04596) (xy 32.02725 -10.106351) (xy 32.058195 -10.17061)
			(xy 32.081752 -10.23793) (xy 32.097622 -10.307465) (xy 32.105608 -10.378339) (xy 32.106108 -10.414)
			(xy 32.105608 -10.449661) (xy 32.097622 -10.520535) (xy 32.081752 -10.59007) (xy 32.058195 -10.65739)
			(xy 32.02725 -10.721649) (xy 31.989304 -10.78204) (xy 31.944835 -10.837802) (xy 31.894402 -10.888235)
			(xy 31.83864 -10.932704) (xy 31.778249 -10.97065) (xy 31.717875 -10.999724) (xy 90.607899 -10.999724)
			(xy 90.611934 -10.92402) (xy 90.623993 -10.849175) (xy 90.643939 -10.776034) (xy 90.671546 -10.705429)
			(xy 90.706502 -10.638158) (xy 90.74841 -10.574983) (xy 90.796796 -10.516621) (xy 90.851112 -10.463733)
			(xy 90.910741 -10.416918) (xy 90.975009 -10.376706) (xy 91.043186 -10.343554) (xy 91.114502 -10.317836)
			(xy 91.188147 -10.299844) (xy 91.263287 -10.289782) (xy 91.339071 -10.287763) (xy 91.414641 -10.293812)
			(xy 91.489139 -10.307859) (xy 91.561722 -10.329745) (xy 91.631568 -10.359222) (xy 91.697885 -10.395957)
			(xy 91.759921 -10.439532) (xy 91.816974 -10.489454) (xy 91.868398 -10.545158) (xy 91.913609 -10.606013)
			(xy 91.952096 -10.671328) (xy 91.983422 -10.740364) (xy 92.007232 -10.812339) (xy 92.023257 -10.886437)
			(xy 92.031316 -10.961818) (xy 92.03182 -10.999724) (xy 92.607895 -10.999724) (xy 92.61193 -10.92402)
			(xy 92.623989 -10.849175) (xy 92.643935 -10.776034) (xy 92.671542 -10.705429) (xy 92.706498 -10.638158)
			(xy 92.748406 -10.574983) (xy 92.796792 -10.516621) (xy 92.851108 -10.463733) (xy 92.910737 -10.416918)
			(xy 92.975005 -10.376706) (xy 93.043182 -10.343554) (xy 93.114498 -10.317836) (xy 93.188143 -10.299844)
			(xy 93.263283 -10.289782) (xy 93.339067 -10.287763) (xy 93.414637 -10.293812) (xy 93.489135 -10.307859)
			(xy 93.561718 -10.329745) (xy 93.631564 -10.359222) (xy 93.697881 -10.395957) (xy 93.759917 -10.439532)
			(xy 93.81697 -10.489454) (xy 93.868394 -10.545158) (xy 93.913605 -10.606013) (xy 93.952092 -10.671328)
			(xy 93.983418 -10.740364) (xy 94.007228 -10.812339) (xy 94.023253 -10.886437) (xy 94.031312 -10.961818)
			(xy 94.031816 -10.999724) (xy 94.031312 -11.03763) (xy 94.023253 -11.113011) (xy 94.007228 -11.187109)
			(xy 93.983418 -11.259084) (xy 93.952092 -11.32812) (xy 93.913605 -11.393435) (xy 93.868394 -11.45429)
			(xy 93.81697 -11.509994) (xy 93.759917 -11.559916) (xy 93.697881 -11.603491) (xy 93.631564 -11.640226)
			(xy 93.561718 -11.669703) (xy 93.489135 -11.691589) (xy 93.414637 -11.705636) (xy 93.339067 -11.711685)
			(xy 93.263283 -11.709666) (xy 93.188143 -11.699604) (xy 93.114498 -11.681612) (xy 93.043182 -11.655894)
			(xy 92.975005 -11.622742) (xy 92.910737 -11.58253) (xy 92.851108 -11.535715) (xy 92.796792 -11.482827)
			(xy 92.748406 -11.424465) (xy 92.706498 -11.36129) (xy 92.671542 -11.294019) (xy 92.643935 -11.223414)
			(xy 92.623989 -11.150273) (xy 92.61193 -11.075428) (xy 92.607895 -10.999724) (xy 92.03182 -10.999724)
			(xy 92.031316 -11.03763) (xy 92.023257 -11.113011) (xy 92.007232 -11.187109) (xy 91.983422 -11.259084)
			(xy 91.952096 -11.32812) (xy 91.913609 -11.393435) (xy 91.868398 -11.45429) (xy 91.816974 -11.509994)
			(xy 91.759921 -11.559916) (xy 91.697885 -11.603491) (xy 91.631568 -11.640226) (xy 91.561722 -11.669703)
			(xy 91.489139 -11.691589) (xy 91.414641 -11.705636) (xy 91.339071 -11.711685) (xy 91.263287 -11.709666)
			(xy 91.188147 -11.699604) (xy 91.114502 -11.681612) (xy 91.043186 -11.655894) (xy 90.975009 -11.622742)
			(xy 90.910741 -11.58253) (xy 90.851112 -11.535715) (xy 90.796796 -11.482827) (xy 90.74841 -11.424465)
			(xy 90.706502 -11.36129) (xy 90.671546 -11.294019) (xy 90.643939 -11.223414) (xy 90.623993 -11.150273)
			(xy 90.611934 -11.075428) (xy 90.607899 -10.999724) (xy 31.717875 -10.999724) (xy 31.71399 -11.001595)
			(xy 31.64667 -11.025152) (xy 31.577135 -11.041022) (xy 31.506261 -11.049008) (xy 31.434939 -11.049008)
			(xy 31.364065 -11.041022) (xy 31.29453 -11.025152) (xy 31.22721 -11.001595) (xy 31.162951 -10.97065)
			(xy 31.10256 -10.932704) (xy 31.046798 -10.888235) (xy 30.996365 -10.837802) (xy 30.951896 -10.78204)
			(xy 30.91395 -10.721649) (xy 30.883005 -10.65739) (xy 30.859448 -10.59007) (xy 30.843578 -10.520535)
			(xy 30.835592 -10.449661) (xy 29.464451 -10.449661) (xy 29.464259 -10.471663) (xy 29.456214 -10.586709)
			(xy 29.440164 -10.700913) (xy 29.416186 -10.813719) (xy 29.384398 -10.924578) (xy 29.344954 -11.03295)
			(xy 29.298046 -11.138306) (xy 29.243904 -11.240133) (xy 29.18279 -11.337935) (xy 29.115003 -11.431236)
			(xy 29.040873 -11.519581) (xy 28.96076 -11.60254) (xy 28.875056 -11.679709) (xy 28.784177 -11.750711)
			(xy 28.688567 -11.815201) (xy 28.588692 -11.872864) (xy 28.485037 -11.92342) (xy 28.378108 -11.966622)
			(xy 28.268426 -12.00226) (xy 28.156525 -12.03016) (xy 28.042951 -12.050186) (xy 27.928256 -12.062241)
			(xy 27.813 -12.066266) (xy 27.697744 -12.062241) (xy 27.583049 -12.050186) (xy 27.469475 -12.03016)
			(xy 27.357574 -12.00226) (xy 27.247892 -11.966622) (xy 27.140963 -11.92342) (xy 27.037308 -11.872864)
			(xy 26.937433 -11.815201) (xy 26.841823 -11.750711) (xy 26.750944 -11.679709) (xy 26.66524 -11.60254)
			(xy 26.585127 -11.519581) (xy 26.510997 -11.431236) (xy 26.44321 -11.337935) (xy 26.382096 -11.240133)
			(xy 26.327954 -11.138306) (xy 26.281046 -11.03295) (xy 26.241602 -10.924578) (xy 26.209814 -10.813719)
			(xy 26.185836 -10.700913) (xy 26.169786 -10.586709) (xy 26.161741 -10.471663) (xy 12.237392 -10.471663)
			(xy 12.23772 -10.500106) (xy 12.237225 -10.542969) (xy 12.229315 -10.628329) (xy 12.213563 -10.712596)
			(xy 12.190103 -10.795049) (xy 12.159135 -10.874986) (xy 12.120924 -10.951725) (xy 12.075795 -11.024611)
			(xy 12.024134 -11.093022) (xy 11.96638 -11.156374) (xy 11.903028 -11.214128) (xy 11.834617 -11.265789)
			(xy 11.761731 -11.310918) (xy 11.684992 -11.349129) (xy 11.605055 -11.380097) (xy 11.522602 -11.403557)
			(xy 11.438335 -11.419309) (xy 11.352975 -11.427219) (xy 11.267249 -11.427219) (xy 11.181889 -11.419309)
			(xy 11.097622 -11.403557) (xy 11.015169 -11.380097) (xy 10.935232 -11.349129) (xy 10.858493 -11.310918)
			(xy 10.785607 -11.265789) (xy 10.717196 -11.214128) (xy 10.653844 -11.156374) (xy 10.59609 -11.093022)
			(xy 10.544429 -11.024611) (xy 10.4993 -10.951725) (xy 10.461089 -10.874986) (xy 10.430121 -10.795049)
			(xy 10.406661 -10.712596) (xy 10.390909 -10.628329) (xy 10.382999 -10.542969) (xy 9.6774 -10.542969)
			(xy 9.6774 -12.329261) (xy 42.062392 -12.329261) (xy 42.062392 -12.257939) (xy 42.070378 -12.187065)
			(xy 42.086248 -12.11753) (xy 42.109805 -12.05021) (xy 42.14075 -11.985951) (xy 42.178696 -11.92556)
			(xy 42.223165 -11.869798) (xy 42.273598 -11.819365) (xy 42.32936 -11.774896) (xy 42.389751 -11.73695)
			(xy 42.45401 -11.706005) (xy 42.52133 -11.682448) (xy 42.590865 -11.666578) (xy 42.661739 -11.658592)
			(xy 42.733061 -11.658592) (xy 42.803935 -11.666578) (xy 42.87347 -11.682448) (xy 42.94079 -11.706005)
			(xy 43.005049 -11.73695) (xy 43.06544 -11.774896) (xy 43.121202 -11.819365) (xy 43.171635 -11.869798)
			(xy 43.216104 -11.92556) (xy 43.25405 -11.985951) (xy 43.284995 -12.05021) (xy 43.308552 -12.11753)
			(xy 43.324422 -12.187065) (xy 43.328996 -12.227661) (xy 49.606192 -12.227661) (xy 49.606192 -12.156339)
			(xy 49.614178 -12.085465) (xy 49.630048 -12.01593) (xy 49.653605 -11.94861) (xy 49.68455 -11.884351)
			(xy 49.722496 -11.82396) (xy 49.766965 -11.768198) (xy 49.817398 -11.717765) (xy 49.87316 -11.673296)
			(xy 49.933551 -11.63535) (xy 49.99781 -11.604405) (xy 50.06513 -11.580848) (xy 50.134665 -11.564978)
			(xy 50.205539 -11.556992) (xy 50.276861 -11.556992) (xy 50.347735 -11.564978) (xy 50.41727 -11.580848)
			(xy 50.48459 -11.604405) (xy 50.548849 -11.63535) (xy 50.60924 -11.673296) (xy 50.665002 -11.717765)
			(xy 50.715435 -11.768198) (xy 50.759904 -11.82396) (xy 50.79785 -11.884351) (xy 50.828795 -11.94861)
			(xy 50.852352 -12.01593) (xy 50.868222 -12.085465) (xy 50.876208 -12.156339) (xy 50.876708 -12.192)
			(xy 50.876208 -12.227661) (xy 50.868222 -12.298535) (xy 50.852352 -12.36807) (xy 50.828795 -12.43539)
			(xy 50.79785 -12.499649) (xy 50.759904 -12.56004) (xy 50.715435 -12.615802) (xy 50.665002 -12.666235)
			(xy 50.60924 -12.710704) (xy 50.548849 -12.74865) (xy 50.48459 -12.779595) (xy 50.41727 -12.803152)
			(xy 50.347735 -12.819022) (xy 50.276861 -12.827008) (xy 50.205539 -12.827008) (xy 50.134665 -12.819022)
			(xy 50.06513 -12.803152) (xy 49.99781 -12.779595) (xy 49.933551 -12.74865) (xy 49.87316 -12.710704)
			(xy 49.817398 -12.666235) (xy 49.766965 -12.615802) (xy 49.722496 -12.56004) (xy 49.68455 -12.499649)
			(xy 49.653605 -12.43539) (xy 49.630048 -12.36807) (xy 49.614178 -12.298535) (xy 49.606192 -12.227661)
			(xy 43.328996 -12.227661) (xy 43.332408 -12.257939) (xy 43.332908 -12.2936) (xy 43.332408 -12.329261)
			(xy 43.324422 -12.400135) (xy 43.308552 -12.46967) (xy 43.284995 -12.53699) (xy 43.25405 -12.601249)
			(xy 43.216104 -12.66164) (xy 43.171635 -12.717402) (xy 43.121202 -12.767835) (xy 43.06544 -12.812304)
			(xy 43.005049 -12.85025) (xy 42.94079 -12.881195) (xy 42.87347 -12.904752) (xy 42.803935 -12.920622)
			(xy 42.733061 -12.928608) (xy 42.661739 -12.928608) (xy 42.590865 -12.920622) (xy 42.52133 -12.904752)
			(xy 42.45401 -12.881195) (xy 42.389751 -12.85025) (xy 42.32936 -12.812304) (xy 42.273598 -12.767835)
			(xy 42.223165 -12.717402) (xy 42.178696 -12.66164) (xy 42.14075 -12.601249) (xy 42.109805 -12.53699)
			(xy 42.086248 -12.46967) (xy 42.070378 -12.400135) (xy 42.062392 -12.329261) (xy 9.6774 -12.329261)
			(xy 9.6774 -12.7) (xy 8.834437 -13.542963) (xy 10.382999 -13.542963) (xy 10.382999 -13.457237) (xy 10.390909 -13.371877)
			(xy 10.406661 -13.28761) (xy 10.430121 -13.205157) (xy 10.461089 -13.12522) (xy 10.4993 -13.048481)
			(xy 10.544429 -12.975595) (xy 10.59609 -12.907184) (xy 10.653844 -12.843832) (xy 10.717196 -12.786078)
			(xy 10.785607 -12.734417) (xy 10.858493 -12.689288) (xy 10.935232 -12.651077) (xy 11.015169 -12.620109)
			(xy 11.097622 -12.596649) (xy 11.181889 -12.580897) (xy 11.267249 -12.572987) (xy 11.352975 -12.572987)
			(xy 11.438335 -12.580897) (xy 11.522602 -12.596649) (xy 11.605055 -12.620109) (xy 11.684992 -12.651077)
			(xy 11.761731 -12.689288) (xy 11.834617 -12.734417) (xy 11.903028 -12.786078) (xy 11.96638 -12.843832)
			(xy 12.024134 -12.907184) (xy 12.075795 -12.975595) (xy 12.115958 -13.040461) (xy 64.846192 -13.040461)
			(xy 64.846192 -12.969139) (xy 64.854178 -12.898265) (xy 64.870048 -12.82873) (xy 64.893605 -12.76141)
			(xy 64.92455 -12.697151) (xy 64.962496 -12.63676) (xy 65.006965 -12.580998) (xy 65.057398 -12.530565)
			(xy 65.11316 -12.486096) (xy 65.173551 -12.44815) (xy 65.23781 -12.417205) (xy 65.30513 -12.393648)
			(xy 65.374665 -12.377778) (xy 65.445539 -12.369792) (xy 65.516861 -12.369792) (xy 65.587735 -12.377778)
			(xy 65.65727 -12.393648) (xy 65.72459 -12.417205) (xy 65.788849 -12.44815) (xy 65.84924 -12.486096)
			(xy 65.905002 -12.530565) (xy 65.955435 -12.580998) (xy 65.999904 -12.63676) (xy 66.03785 -12.697151)
			(xy 66.068795 -12.76141) (xy 66.092352 -12.82873) (xy 66.108222 -12.898265) (xy 66.116208 -12.969139)
			(xy 66.116637 -12.99972) (xy 90.607899 -12.99972) (xy 90.611934 -12.924016) (xy 90.623993 -12.849171)
			(xy 90.643939 -12.77603) (xy 90.671546 -12.705425) (xy 90.706502 -12.638154) (xy 90.74841 -12.574979)
			(xy 90.796796 -12.516617) (xy 90.851112 -12.463729) (xy 90.910741 -12.416914) (xy 90.975009 -12.376702)
			(xy 91.043186 -12.34355) (xy 91.114502 -12.317832) (xy 91.188147 -12.29984) (xy 91.263287 -12.289778)
			(xy 91.339071 -12.287759) (xy 91.414641 -12.293808) (xy 91.489139 -12.307855) (xy 91.561722 -12.329741)
			(xy 91.631568 -12.359218) (xy 91.697885 -12.395953) (xy 91.759921 -12.439528) (xy 91.816974 -12.48945)
			(xy 91.868398 -12.545154) (xy 91.913609 -12.606009) (xy 91.952096 -12.671324) (xy 91.983422 -12.74036)
			(xy 92.007232 -12.812335) (xy 92.023257 -12.886433) (xy 92.031316 -12.961814) (xy 92.03182 -12.99972)
			(xy 92.607895 -12.99972) (xy 92.61193 -12.924016) (xy 92.623989 -12.849171) (xy 92.643935 -12.77603)
			(xy 92.671542 -12.705425) (xy 92.706498 -12.638154) (xy 92.748406 -12.574979) (xy 92.796792 -12.516617)
			(xy 92.851108 -12.463729) (xy 92.910737 -12.416914) (xy 92.975005 -12.376702) (xy 93.043182 -12.34355)
			(xy 93.114498 -12.317832) (xy 93.188143 -12.29984) (xy 93.263283 -12.289778) (xy 93.339067 -12.287759)
			(xy 93.414637 -12.293808) (xy 93.489135 -12.307855) (xy 93.561718 -12.329741) (xy 93.631564 -12.359218)
			(xy 93.697881 -12.395953) (xy 93.759917 -12.439528) (xy 93.81697 -12.48945) (xy 93.868394 -12.545154)
			(xy 93.913605 -12.606009) (xy 93.952092 -12.671324) (xy 93.983418 -12.74036) (xy 94.007228 -12.812335)
			(xy 94.023253 -12.886433) (xy 94.031312 -12.961814) (xy 94.031816 -12.99972) (xy 94.031312 -13.037626)
			(xy 94.023253 -13.113007) (xy 94.007228 -13.187105) (xy 93.983418 -13.25908) (xy 93.952092 -13.328116)
			(xy 93.913605 -13.393431) (xy 93.868394 -13.454286) (xy 93.81697 -13.50999) (xy 93.759917 -13.559912)
			(xy 93.697881 -13.603487) (xy 93.631564 -13.640222) (xy 93.561718 -13.669699) (xy 93.489135 -13.691585)
			(xy 93.414637 -13.705632) (xy 93.339067 -13.711681) (xy 93.263283 -13.709662) (xy 93.188143 -13.6996)
			(xy 93.114498 -13.681608) (xy 93.043182 -13.65589) (xy 92.975005 -13.622738) (xy 92.910737 -13.582526)
			(xy 92.851108 -13.535711) (xy 92.796792 -13.482823) (xy 92.748406 -13.424461) (xy 92.706498 -13.361286)
			(xy 92.671542 -13.294015) (xy 92.643935 -13.22341) (xy 92.623989 -13.150269) (xy 92.61193 -13.075424)
			(xy 92.607895 -12.99972) (xy 92.03182 -12.99972) (xy 92.031316 -13.037626) (xy 92.023257 -13.113007)
			(xy 92.007232 -13.187105) (xy 91.983422 -13.25908) (xy 91.952096 -13.328116) (xy 91.913609 -13.393431)
			(xy 91.868398 -13.454286) (xy 91.816974 -13.50999) (xy 91.759921 -13.559912) (xy 91.697885 -13.603487)
			(xy 91.631568 -13.640222) (xy 91.561722 -13.669699) (xy 91.489139 -13.691585) (xy 91.414641 -13.705632)
			(xy 91.339071 -13.711681) (xy 91.263287 -13.709662) (xy 91.188147 -13.6996) (xy 91.114502 -13.681608)
			(xy 91.043186 -13.65589) (xy 90.975009 -13.622738) (xy 90.910741 -13.582526) (xy 90.851112 -13.535711)
			(xy 90.796796 -13.482823) (xy 90.74841 -13.424461) (xy 90.706502 -13.361286) (xy 90.671546 -13.294015)
			(xy 90.643939 -13.22341) (xy 90.623993 -13.150269) (xy 90.611934 -13.075424) (xy 90.607899 -12.99972)
			(xy 66.116637 -12.99972) (xy 66.116708 -13.0048) (xy 66.116208 -13.040461) (xy 66.108222 -13.111335)
			(xy 66.092352 -13.18087) (xy 66.068795 -13.24819) (xy 66.03785 -13.312449) (xy 65.999904 -13.37284)
			(xy 65.955435 -13.428602) (xy 65.905002 -13.479035) (xy 65.84924 -13.523504) (xy 65.788849 -13.56145)
			(xy 65.72459 -13.592395) (xy 65.65727 -13.615952) (xy 65.587735 -13.631822) (xy 65.516861 -13.639808)
			(xy 65.445539 -13.639808) (xy 65.374665 -13.631822) (xy 65.30513 -13.615952) (xy 65.23781 -13.592395)
			(xy 65.173551 -13.56145) (xy 65.11316 -13.523504) (xy 65.057398 -13.479035) (xy 65.006965 -13.428602)
			(xy 64.962496 -13.37284) (xy 64.92455 -13.312449) (xy 64.893605 -13.24819) (xy 64.870048 -13.18087)
			(xy 64.854178 -13.111335) (xy 64.846192 -13.040461) (xy 12.115958 -13.040461) (xy 12.120924 -13.048481)
			(xy 12.159135 -13.12522) (xy 12.190103 -13.205157) (xy 12.213563 -13.28761) (xy 12.229315 -13.371877)
			(xy 12.237225 -13.457237) (xy 12.23772 -13.5001) (xy 12.237225 -13.542963) (xy 12.229315 -13.628323)
			(xy 12.213563 -13.71259) (xy 12.190103 -13.795043) (xy 12.159135 -13.87498) (xy 12.120924 -13.951719)
			(xy 12.075795 -14.024605) (xy 12.024134 -14.093016) (xy 11.96638 -14.156368) (xy 11.903028 -14.214122)
			(xy 11.834617 -14.265783) (xy 11.761731 -14.310912) (xy 11.684992 -14.349123) (xy 11.605055 -14.380091)
			(xy 11.522602 -14.403551) (xy 11.438335 -14.419303) (xy 11.352975 -14.427213) (xy 11.267249 -14.427213)
			(xy 11.181889 -14.419303) (xy 11.097622 -14.403551) (xy 11.015169 -14.380091) (xy 10.935232 -14.349123)
			(xy 10.858493 -14.310912) (xy 10.785607 -14.265783) (xy 10.717196 -14.214122) (xy 10.653844 -14.156368)
			(xy 10.59609 -14.093016) (xy 10.544429 -14.024605) (xy 10.4993 -13.951719) (xy 10.461089 -13.87498)
			(xy 10.430121 -13.795043) (xy 10.406661 -13.71259) (xy 10.390909 -13.628323) (xy 10.382999 -13.542963)
			(xy 8.834437 -13.542963) (xy 6.2484 -16.129) (xy 1.778 -16.129) (xy 0.7874 -17.1196) (xy 0.7874 -20.37155)
			(xy 1.342128 -20.37155) (xy 1.345089 -20.283689) (xy 1.356023 -20.196461) (xy 1.374839 -20.110587)
			(xy 1.401381 -20.026779) (xy 1.435431 -19.94573) (xy 1.476705 -19.868112) (xy 1.524864 -19.794565)
			(xy 1.579507 -19.7257) (xy 1.640182 -19.662085) (xy 1.706388 -19.604249) (xy 1.777576 -19.552669)
			(xy 1.853158 -19.507772) (xy 1.932507 -19.46993) (xy 2.014967 -19.439456) (xy 2.099855 -19.416602)
			(xy 2.186469 -19.401558) (xy 2.274092 -19.394448) (xy 2.361998 -19.395331) (xy 2.44946 -19.4042)
			(xy 2.535755 -19.42098) (xy 2.5781 -19.432778) (xy 2.611628 -19.442684) (xy 2.67843 -19.425412) (xy 3.853688 -18.250408)
			(xy 7.423404 -18.250408) (xy 10.858246 -14.815312) (xy 25.148286 -14.815312) (xy 25.332668 -14.999716)
			(xy 90.607899 -14.999716) (xy 90.611934 -14.924012) (xy 90.623993 -14.849167) (xy 90.643939 -14.776026)
			(xy 90.671546 -14.705421) (xy 90.706502 -14.63815) (xy 90.74841 -14.574975) (xy 90.796796 -14.516613)
			(xy 90.851112 -14.463725) (xy 90.910741 -14.41691) (xy 90.975009 -14.376698) (xy 91.043186 -14.343546)
			(xy 91.114502 -14.317828) (xy 91.188147 -14.299836) (xy 91.263287 -14.289774) (xy 91.339071 -14.287755)
			(xy 91.414641 -14.293804) (xy 91.489139 -14.307851) (xy 91.561722 -14.329737) (xy 91.631568 -14.359214)
			(xy 91.697885 -14.395949) (xy 91.759921 -14.439524) (xy 91.816974 -14.489446) (xy 91.868398 -14.54515)
			(xy 91.913609 -14.606005) (xy 91.952096 -14.67132) (xy 91.983422 -14.740356) (xy 92.007232 -14.812331)
			(xy 92.023257 -14.886429) (xy 92.031316 -14.96181) (xy 92.03182 -14.999716) (xy 92.607895 -14.999716)
			(xy 92.61193 -14.924012) (xy 92.623989 -14.849167) (xy 92.643935 -14.776026) (xy 92.671542 -14.705421)
			(xy 92.706498 -14.63815) (xy 92.748406 -14.574975) (xy 92.796792 -14.516613) (xy 92.851108 -14.463725)
			(xy 92.910737 -14.41691) (xy 92.975005 -14.376698) (xy 93.043182 -14.343546) (xy 93.114498 -14.317828)
			(xy 93.188143 -14.299836) (xy 93.263283 -14.289774) (xy 93.339067 -14.287755) (xy 93.414637 -14.293804)
			(xy 93.489135 -14.307851) (xy 93.561718 -14.329737) (xy 93.631564 -14.359214) (xy 93.697881 -14.395949)
			(xy 93.759178 -14.439005) (xy 98.549955 -14.439005) (xy 98.549955 -14.340719) (xy 98.557864 -14.242752)
			(xy 98.57363 -14.145739) (xy 98.597151 -14.05031) (xy 98.628275 -13.957082) (xy 98.6668 -13.866661)
			(xy 98.712475 -13.779634) (xy 98.765006 -13.696563) (xy 98.82405 -13.61799) (xy 98.889225 -13.544422)
			(xy 98.960109 -13.476337) (xy 99.036242 -13.414176) (xy 99.117129 -13.358344) (xy 99.202247 -13.309201)
			(xy 99.291044 -13.267067) (xy 99.382942 -13.232214) (xy 99.477348 -13.204869) (xy 99.573647 -13.18521)
			(xy 99.671216 -13.173363) (xy 99.769422 -13.169405) (xy 99.867628 -13.173363) (xy 99.965197 -13.18521)
			(xy 100.061496 -13.204869) (xy 100.155902 -13.232214) (xy 100.2478 -13.267067) (xy 100.336597 -13.309201)
			(xy 100.421715 -13.358344) (xy 100.502602 -13.414176) (xy 100.578735 -13.476337) (xy 100.649619 -13.544422)
			(xy 100.714794 -13.61799) (xy 100.773838 -13.696563) (xy 100.826369 -13.779634) (xy 100.872044 -13.866661)
			(xy 100.910569 -13.957082) (xy 100.941693 -14.05031) (xy 100.965214 -14.145739) (xy 100.98098 -14.242752)
			(xy 100.988889 -14.340719) (xy 100.989384 -14.389862) (xy 100.988889 -14.439005) (xy 100.98098 -14.536972)
			(xy 100.965214 -14.633985) (xy 100.941693 -14.729414) (xy 100.910569 -14.822642) (xy 100.872044 -14.913063)
			(xy 100.826369 -15.000091) (xy 100.773838 -15.083161) (xy 100.714794 -15.161734) (xy 100.649619 -15.235302)
			(xy 100.578735 -15.303387) (xy 100.502602 -15.365548) (xy 100.421715 -15.42138) (xy 100.336597 -15.470523)
			(xy 100.2478 -15.512657) (xy 100.155902 -15.54751) (xy 100.061496 -15.574855) (xy 99.965197 -15.594514)
			(xy 99.867628 -15.606361) (xy 99.769422 -15.610319) (xy 99.671216 -15.606361) (xy 99.573647 -15.594514)
			(xy 99.477348 -15.574855) (xy 99.382942 -15.54751) (xy 99.291044 -15.512657) (xy 99.202247 -15.470523)
			(xy 99.117129 -15.42138) (xy 99.036242 -15.365548) (xy 98.960109 -15.303387) (xy 98.889225 -15.235302)
			(xy 98.82405 -15.161734) (xy 98.765006 -15.083161) (xy 98.712475 -15.000091) (xy 98.6668 -14.913063)
			(xy 98.628275 -14.822642) (xy 98.597151 -14.729414) (xy 98.57363 -14.633985) (xy 98.557864 -14.536972)
			(xy 98.549955 -14.439005) (xy 93.759178 -14.439005) (xy 93.759917 -14.439524) (xy 93.81697 -14.489446)
			(xy 93.868394 -14.54515) (xy 93.913605 -14.606005) (xy 93.952092 -14.67132) (xy 93.983418 -14.740356)
			(xy 94.007228 -14.812331) (xy 94.023253 -14.886429) (xy 94.031312 -14.96181) (xy 94.031816 -14.999716)
			(xy 94.031312 -15.037622) (xy 94.023253 -15.113003) (xy 94.007228 -15.187101) (xy 93.983418 -15.259076)
			(xy 93.952092 -15.328112) (xy 93.913605 -15.393427) (xy 93.868394 -15.454282) (xy 93.81697 -15.509986)
			(xy 93.759917 -15.559908) (xy 93.697881 -15.603483) (xy 93.631564 -15.640218) (xy 93.561718 -15.669695)
			(xy 93.489135 -15.691581) (xy 93.414637 -15.705628) (xy 93.339067 -15.711677) (xy 93.263283 -15.709658)
			(xy 93.188143 -15.699596) (xy 93.114498 -15.681604) (xy 93.043182 -15.655886) (xy 92.975005 -15.622734)
			(xy 92.910737 -15.582522) (xy 92.851108 -15.535707) (xy 92.796792 -15.482819) (xy 92.748406 -15.424457)
			(xy 92.706498 -15.361282) (xy 92.671542 -15.294011) (xy 92.643935 -15.223406) (xy 92.623989 -15.150265)
			(xy 92.61193 -15.07542) (xy 92.607895 -14.999716) (xy 92.03182 -14.999716) (xy 92.031316 -15.037622)
			(xy 92.023257 -15.113003) (xy 92.007232 -15.187101) (xy 91.983422 -15.259076) (xy 91.952096 -15.328112)
			(xy 91.913609 -15.393427) (xy 91.868398 -15.454282) (xy 91.816974 -15.509986) (xy 91.759921 -15.559908)
			(xy 91.697885 -15.603483) (xy 91.631568 -15.640218) (xy 91.561722 -15.669695) (xy 91.489139 -15.691581)
			(xy 91.414641 -15.705628) (xy 91.339071 -15.711677) (xy 91.263287 -15.709658) (xy 91.188147 -15.699596)
			(xy 91.114502 -15.681604) (xy 91.043186 -15.655886) (xy 90.975009 -15.622734) (xy 90.910741 -15.582522)
			(xy 90.851112 -15.535707) (xy 90.796796 -15.482819) (xy 90.74841 -15.424457) (xy 90.706502 -15.361282)
			(xy 90.671546 -15.294011) (xy 90.643939 -15.223406) (xy 90.623993 -15.150265) (xy 90.611934 -15.07542)
			(xy 90.607899 -14.999716) (xy 25.332668 -14.999716) (xy 26.497475 -16.164661) (xy 34.594792 -16.164661)
			(xy 34.594792 -16.093339) (xy 34.602778 -16.022465) (xy 34.618648 -15.95293) (xy 34.642205 -15.88561)
			(xy 34.67315 -15.821351) (xy 34.711096 -15.76096) (xy 34.755565 -15.705198) (xy 34.805998 -15.654765)
			(xy 34.86176 -15.610296) (xy 34.922151 -15.57235) (xy 34.98641 -15.541405) (xy 35.05373 -15.517848)
			(xy 35.123265 -15.501978) (xy 35.194139 -15.493992) (xy 35.265461 -15.493992) (xy 35.336335 -15.501978)
			(xy 35.40587 -15.517848) (xy 35.47319 -15.541405) (xy 35.537449 -15.57235) (xy 35.59784 -15.610296)
			(xy 35.653602 -15.654765) (xy 35.704035 -15.705198) (xy 35.748504 -15.76096) (xy 35.78645 -15.821351)
			(xy 35.817395 -15.88561) (xy 35.840952 -15.95293) (xy 35.856822 -16.022465) (xy 35.864808 -16.093339)
			(xy 35.865308 -16.129) (xy 35.864808 -16.164661) (xy 35.856822 -16.235535) (xy 35.840952 -16.30507)
			(xy 35.817395 -16.37239) (xy 35.78645 -16.436649) (xy 35.748504 -16.49704) (xy 35.704035 -16.552802)
			(xy 35.685776 -16.571061) (xy 39.954192 -16.571061) (xy 39.954192 -16.499739) (xy 39.962178 -16.428865)
			(xy 39.978048 -16.35933) (xy 40.001605 -16.29201) (xy 40.03255 -16.227751) (xy 40.070496 -16.16736)
			(xy 40.114965 -16.111598) (xy 40.165398 -16.061165) (xy 40.22116 -16.016696) (xy 40.281551 -15.97875)
			(xy 40.34581 -15.947805) (xy 40.41313 -15.924248) (xy 40.482665 -15.908378) (xy 40.553539 -15.900392)
			(xy 40.624861 -15.900392) (xy 40.695735 -15.908378) (xy 40.76527 -15.924248) (xy 40.83259 -15.947805)
			(xy 40.896849 -15.97875) (xy 40.95724 -16.016696) (xy 41.013002 -16.061165) (xy 41.063435 -16.111598)
			(xy 41.107904 -16.16736) (xy 41.14585 -16.227751) (xy 41.176795 -16.29201) (xy 41.185561 -16.317061)
			(xy 49.047392 -16.317061) (xy 49.047392 -16.245739) (xy 49.055378 -16.174865) (xy 49.071248 -16.10533)
			(xy 49.094805 -16.03801) (xy 49.12575 -15.973751) (xy 49.163696 -15.91336) (xy 49.208165 -15.857598)
			(xy 49.258598 -15.807165) (xy 49.31436 -15.762696) (xy 49.374751 -15.72475) (xy 49.43901 -15.693805)
			(xy 49.50633 -15.670248) (xy 49.575865 -15.654378) (xy 49.646739 -15.646392) (xy 49.718061 -15.646392)
			(xy 49.788935 -15.654378) (xy 49.85847 -15.670248) (xy 49.92579 -15.693805) (xy 49.990049 -15.72475)
			(xy 50.05044 -15.762696) (xy 50.106202 -15.807165) (xy 50.156635 -15.857598) (xy 50.201104 -15.91336)
			(xy 50.23905 -15.973751) (xy 50.269995 -16.03801) (xy 50.293552 -16.10533) (xy 50.309422 -16.174865)
			(xy 50.317408 -16.245739) (xy 50.317908 -16.2814) (xy 50.317408 -16.317061) (xy 50.309422 -16.387935)
			(xy 50.293552 -16.45747) (xy 50.269995 -16.52479) (xy 50.23905 -16.589049) (xy 50.201104 -16.64944)
			(xy 50.156635 -16.705202) (xy 50.106202 -16.755635) (xy 50.05044 -16.800104) (xy 49.990049 -16.83805)
			(xy 49.92579 -16.868995) (xy 49.85847 -16.892552) (xy 49.788935 -16.908422) (xy 49.718061 -16.916408)
			(xy 49.646739 -16.916408) (xy 49.575865 -16.908422) (xy 49.50633 -16.892552) (xy 49.43901 -16.868995)
			(xy 49.374751 -16.83805) (xy 49.31436 -16.800104) (xy 49.258598 -16.755635) (xy 49.208165 -16.705202)
			(xy 49.163696 -16.64944) (xy 49.12575 -16.589049) (xy 49.094805 -16.52479) (xy 49.071248 -16.45747)
			(xy 49.055378 -16.387935) (xy 49.047392 -16.317061) (xy 41.185561 -16.317061) (xy 41.200352 -16.35933)
			(xy 41.216222 -16.428865) (xy 41.224208 -16.499739) (xy 41.224708 -16.5354) (xy 41.224208 -16.571061)
			(xy 41.216222 -16.641935) (xy 41.200352 -16.71147) (xy 41.176795 -16.77879) (xy 41.14585 -16.843049)
			(xy 41.107904 -16.90344) (xy 41.063435 -16.959202) (xy 41.013002 -17.009635) (xy 40.95724 -17.054104)
			(xy 40.896849 -17.09205) (xy 40.83259 -17.122995) (xy 40.76527 -17.146552) (xy 40.695735 -17.162422)
			(xy 40.624861 -17.170408) (xy 40.553539 -17.170408) (xy 40.482665 -17.162422) (xy 40.41313 -17.146552)
			(xy 40.34581 -17.122995) (xy 40.281551 -17.09205) (xy 40.22116 -17.054104) (xy 40.165398 -17.009635)
			(xy 40.114965 -16.959202) (xy 40.070496 -16.90344) (xy 40.03255 -16.843049) (xy 40.001605 -16.77879)
			(xy 39.978048 -16.71147) (xy 39.962178 -16.641935) (xy 39.954192 -16.571061) (xy 35.685776 -16.571061)
			(xy 35.653602 -16.603235) (xy 35.59784 -16.647704) (xy 35.537449 -16.68565) (xy 35.47319 -16.716595)
			(xy 35.40587 -16.740152) (xy 35.336335 -16.756022) (xy 35.265461 -16.764008) (xy 35.194139 -16.764008)
			(xy 35.123265 -16.756022) (xy 35.05373 -16.740152) (xy 34.98641 -16.716595) (xy 34.922151 -16.68565)
			(xy 34.86176 -16.647704) (xy 34.805998 -16.603235) (xy 34.755565 -16.552802) (xy 34.711096 -16.49704)
			(xy 34.67315 -16.436649) (xy 34.642205 -16.37239) (xy 34.618648 -16.30507) (xy 34.602778 -16.235535)
			(xy 34.594792 -16.164661) (xy 26.497475 -16.164661) (xy 27.28976 -16.95704) (xy 27.317446 -16.966692)
			(xy 27.345479 -16.976983) (xy 27.39886 -17.003745) (xy 27.448307 -17.037224) (xy 27.492978 -17.076851)
			(xy 27.532116 -17.121951) (xy 27.565054 -17.17176) (xy 27.591233 -17.225429) (xy 27.610209 -17.282048)
			(xy 27.621659 -17.340655) (xy 27.625388 -17.400253) (xy 27.621333 -17.459829) (xy 27.609563 -17.518372)
			(xy 27.590278 -17.574886) (xy 27.563805 -17.628412) (xy 27.530595 -17.67804) (xy 27.491211 -17.722925)
			(xy 27.446324 -17.762307) (xy 27.396695 -17.795515) (xy 27.343168 -17.821986) (xy 27.286653 -17.841268)
			(xy 27.228109 -17.853036) (xy 27.168533 -17.857088) (xy 27.108935 -17.853357) (xy 27.050329 -17.841904)
			(xy 26.993711 -17.822926) (xy 26.940042 -17.796744) (xy 26.890236 -17.763804) (xy 26.845137 -17.724664)
			(xy 26.805512 -17.679991) (xy 26.772035 -17.630543) (xy 26.745275 -17.57716) (xy 26.735024 -17.549114)
			(xy 26.725372 -17.521428) (xy 24.817578 -15.613888) (xy 12.308332 -15.613888) (xy 12.285717 -15.614392)
			(xy 12.2412 -15.622393) (xy 12.198802 -15.638147) (xy 12.159862 -15.661157) (xy 12.125611 -15.690697)
			(xy 12.097129 -15.725833) (xy 12.075316 -15.765456) (xy 12.060862 -15.808314) (xy 12.054222 -15.853054)
			(xy 12.055606 -15.898263) (xy 12.064971 -15.942514) (xy 12.082021 -15.984407) (xy 12.093702 -16.003778)
			(xy 12.116176 -16.040176) (xy 12.155113 -16.116349) (xy 12.186871 -16.195784) (xy 12.21118 -16.277806)
			(xy 12.227833 -16.361718) (xy 12.236688 -16.446807) (xy 12.237671 -16.53235) (xy 12.230773 -16.617619)
			(xy 12.216053 -16.701892) (xy 12.193635 -16.78445) (xy 12.163711 -16.864594) (xy 12.126534 -16.941642)
			(xy 12.08242 -17.01494) (xy 12.031745 -17.083864) (xy 11.974938 -17.147829) (xy 11.912483 -17.206291)
			(xy 11.84491 -17.258754) (xy 11.772793 -17.304772) (xy 11.696745 -17.343955) (xy 11.617412 -17.375968)
			(xy 11.535469 -17.40054) (xy 11.451611 -17.417463) (xy 11.366551 -17.426592) (xy 11.281012 -17.42785)
			(xy 11.195721 -17.421226) (xy 11.111402 -17.406776) (xy 11.028771 -17.384624) (xy 10.948532 -17.354958)
			(xy 10.871365 -17.318029) (xy 10.797926 -17.274151) (xy 10.728839 -17.223697) (xy 10.664692 -17.167097)
			(xy 10.606029 -17.10483) (xy 10.553349 -17.037426) (xy 10.507099 -16.965457) (xy 10.467673 -16.889536)
			(xy 10.451084 -16.850106) (xy 10.441993 -16.829254) (xy 10.417571 -16.790884) (xy 10.38671 -16.757472)
			(xy 10.350396 -16.730086) (xy 10.309787 -16.7096) (xy 10.266181 -16.696668) (xy 10.22097 -16.691703)
			(xy 10.175597 -16.694864) (xy 10.13151 -16.706049) (xy 10.090118 -16.724901) (xy 10.052742 -16.750819)
			(xy 10.036302 -16.76654) (xy 7.754112 -19.048476) (xy 4.184396 -19.048476) (xy 4.05511 -19.177762)
			(xy 4.043667 -19.189876) (xy 4.027044 -19.218748) (xy 4.018452 -19.250936) (xy 4.018477 -19.284252)
			(xy 4.027116 -19.316427) (xy 4.043782 -19.345274) (xy 4.067342 -19.36883) (xy 4.096192 -19.385492)
			(xy 4.128369 -19.394126) (xy 4.145026 -19.394678) (xy 5.81406 -19.394678) (xy 5.81406 -21.32584)
			(xy 3.882644 -21.32584) (xy 3.882644 -19.963384) (xy 3.882138 -19.940351) (xy 3.873829 -19.895041)
			(xy 3.857489 -19.85197) (xy 3.833654 -19.81255) (xy 3.803104 -19.778071) (xy 3.76684 -19.749664)
			(xy 3.72605 -19.728257) (xy 3.682069 -19.714553) (xy 3.636339 -19.709001) (xy 3.590357 -19.711782)
			(xy 3.54563 -19.722804) (xy 3.503621 -19.741708) (xy 3.465708 -19.767874) (xy 3.449066 -19.783806)
			(xy 3.243072 -19.990054) (xy 3.2258 -20.056856) (xy 3.235706 -20.090384) (xy 3.247501 -20.13273)
			(xy 3.264281 -20.219025) (xy 3.273149 -20.306487) (xy 3.274032 -20.394393) (xy 3.266921 -20.482016)
			(xy 3.251877 -20.56863) (xy 3.229023 -20.653518) (xy 3.198548 -20.735978) (xy 3.160706 -20.815327)
			(xy 3.115809 -20.890908) (xy 3.064228 -20.962096) (xy 3.006391 -21.028302) (xy 2.942777 -21.088977)
			(xy 2.873911 -21.143619) (xy 2.800364 -21.191777) (xy 2.722745 -21.233051) (xy 2.641696 -21.2671)
			(xy 2.557888 -21.293643) (xy 2.472014 -21.312458) (xy 2.384786 -21.323391) (xy 2.296925 -21.326352)
			(xy 2.209159 -21.321315) (xy 2.122214 -21.308322) (xy 2.036809 -21.287481) (xy 1.953652 -21.258965)
			(xy 1.87343 -21.223009) (xy 1.796809 -21.179911) (xy 1.724421 -21.130027) (xy 1.656867 -21.073772)
			(xy 1.594705 -21.011609) (xy 1.53845 -20.944055) (xy 1.488567 -20.871667) (xy 1.445469 -20.795045)
			(xy 1.409513 -20.714824) (xy 1.380997 -20.631666) (xy 1.360157 -20.546262) (xy 1.347165 -20.459316)
			(xy 1.342128 -20.37155) (xy 0.7874 -20.37155) (xy 0.7874 -23.36875) (xy 1.342128 -23.36875) (xy 1.345089 -23.280889)
			(xy 1.356023 -23.193661) (xy 1.374839 -23.107787) (xy 1.401381 -23.023979) (xy 1.435431 -22.94293)
			(xy 1.476705 -22.865312) (xy 1.524864 -22.791765) (xy 1.579507 -22.7229) (xy 1.640182 -22.659285)
			(xy 1.706388 -22.601449) (xy 1.777576 -22.549869) (xy 1.853158 -22.504972) (xy 1.932507 -22.46713)
			(xy 2.014967 -22.436656) (xy 2.099855 -22.413802) (xy 2.186469 -22.398758) (xy 2.274092 -22.391648)
			(xy 2.361998 -22.392531) (xy 2.44946 -22.4014) (xy 2.535755 -22.41818) (xy 2.5781 -22.429978) (xy 2.611628 -22.439884)
			(xy 2.67843 -22.422612) (xy 3.47853 -21.622512) (xy 6.692646 -21.622512) (xy 7.988046 -20.327112)
			(xy 10.27684 -20.327112) (xy 10.298831 -20.326623) (xy 10.342153 -20.319026) (xy 10.38352 -20.304083)
			(xy 10.421696 -20.282241) (xy 10.455541 -20.254151) (xy 10.484044 -20.220654) (xy 10.506354 -20.182749)
			(xy 10.521804 -20.141569) (xy 10.529932 -20.098343) (xy 10.530497 -20.054364) (xy 10.52348 -20.010944)
			(xy 10.509092 -19.969381) (xy 10.498836 -19.949922) (xy 10.4785 -19.91223) (xy 10.444049 -19.833815)
			(xy 10.416972 -19.752557) (xy 10.397502 -19.66915) (xy 10.385803 -19.584303) (xy 10.381976 -19.498738)
			(xy 10.386052 -19.413185) (xy 10.397998 -19.328373) (xy 10.417711 -19.245022) (xy 10.445023 -19.163844)
			(xy 10.479703 -19.085529) (xy 10.521454 -19.010744) (xy 10.569921 -18.940127) (xy 10.624692 -18.874278)
			(xy 10.685299 -18.813758) (xy 10.751228 -18.759084) (xy 10.821916 -18.710719) (xy 10.896761 -18.669077)
			(xy 10.975126 -18.634511) (xy 11.056344 -18.607317) (xy 11.139723 -18.587725) (xy 11.224553 -18.575903)
			(xy 11.310112 -18.571951) (xy 11.395671 -18.575903) (xy 11.480501 -18.587725) (xy 11.56388 -18.607317)
			(xy 11.645098 -18.634511) (xy 11.723463 -18.669077) (xy 11.798308 -18.710719) (xy 11.868996 -18.759084)
			(xy 11.934925 -18.813758) (xy 11.995532 -18.874278) (xy 12.050303 -18.940127) (xy 12.09877 -19.010744)
			(xy 12.140521 -19.085529) (xy 12.175201 -19.163844) (xy 12.202513 -19.245022) (xy 12.222226 -19.328373)
			(xy 12.234172 -19.413185) (xy 12.238248 -19.498738) (xy 12.234421 -19.584303) (xy 12.222722 -19.66915)
			(xy 12.203252 -19.752557) (xy 12.176175 -19.833815) (xy 12.141724 -19.91223) (xy 12.121388 -19.949922)
			(xy 12.111063 -19.969354) (xy 12.096643 -20.010927) (xy 12.089601 -20.054362) (xy 12.09015 -20.098361)
			(xy 12.098273 -20.141607) (xy 12.113726 -20.182807) (xy 12.136048 -20.220727) (xy 12.16457 -20.254234)
			(xy 12.198439 -20.282325) (xy 12.236642 -20.304159) (xy 12.278036 -20.319083) (xy 12.321383 -20.326651)
			(xy 12.343384 -20.327112) (xy 19.341846 -20.327112) (xy 19.570446 -20.098512) (xy 19.799808 -20.098512)
			(xy 19.821734 -20.098036) (xy 19.864929 -20.090472) (xy 19.906185 -20.075606) (xy 19.944276 -20.053878)
			(xy 19.978072 -20.025933) (xy 20.006569 -19.992602) (xy 20.028921 -19.954873) (xy 20.044464 -19.913868)
			(xy 20.052737 -19.870803) (xy 20.053495 -19.826957) (xy 20.046714 -19.783631) (xy 20.040092 -19.762724)
			(xy 20.027264 -19.723362) (xy 20.008634 -19.642693) (xy 19.998294 -19.560549) (xy 19.996352 -19.47778)
			(xy 20.002829 -19.395242) (xy 20.017656 -19.313788) (xy 20.040681 -19.234262) (xy 20.071666 -19.157487)
			(xy 20.110289 -19.084256) (xy 20.156152 -19.015328) (xy 20.20878 -18.951415) (xy 20.267628 -18.893179)
			(xy 20.332087 -18.841222) (xy 20.401491 -18.796082) (xy 20.475121 -18.758226) (xy 20.552216 -18.728045)
			(xy 20.631978 -18.705852) (xy 20.713582 -18.691877) (xy 20.754848 -18.688558) (xy 20.771336 -18.686912)
			(xy 20.802703 -18.676276) (xy 20.830275 -18.657924) (xy 20.852194 -18.633092) (xy 20.866981 -18.603455)
			(xy 20.87364 -18.57101) (xy 20.873212 -18.554446) (xy 20.871761 -18.527225) (xy 20.871635 -18.472707)
			(xy 20.872958 -18.44548) (xy 20.873378 -18.428951) (xy 20.866724 -18.396577) (xy 20.851966 -18.367004)
			(xy 20.830099 -18.342221) (xy 20.802594 -18.323896) (xy 20.7713 -18.313263) (xy 20.754848 -18.311622)
			(xy 20.714506 -18.308351) (xy 20.634695 -18.294868) (xy 20.556618 -18.273525) (xy 20.481047 -18.244531)
			(xy 20.40873 -18.208175) (xy 20.340382 -18.164816) (xy 20.276678 -18.114881) (xy 20.21825 -18.058866)
			(xy 20.165674 -17.997325) (xy 20.119472 -17.930865) (xy 20.080099 -17.860145) (xy 20.047946 -17.785864)
			(xy 20.023329 -17.708756) (xy 20.006494 -17.629585) (xy 19.997606 -17.549133) (xy 19.996753 -17.468195)
			(xy 20.003944 -17.387574) (xy 20.019108 -17.308065) (xy 20.042094 -17.230456) (xy 20.072675 -17.155514)
			(xy 20.110549 -17.08398) (xy 20.155341 -17.016561) (xy 20.206608 -16.953926) (xy 20.263844 -16.896692)
			(xy 20.326481 -16.845427) (xy 20.3939 -16.800637) (xy 20.465435 -16.762765) (xy 20.540379 -16.732186)
			(xy 20.617989 -16.709202) (xy 20.697498 -16.694041) (xy 20.77812 -16.686852) (xy 20.859057 -16.687708)
			(xy 20.939509 -16.696598) (xy 21.01868 -16.713436) (xy 21.095787 -16.738054) (xy 21.170067 -16.77021)
			(xy 21.240786 -16.809585) (xy 21.307244 -16.855789) (xy 21.368784 -16.908367) (xy 21.424797 -16.966797)
			(xy 21.47473 -17.030502) (xy 21.518087 -17.098851) (xy 21.554441 -17.17117) (xy 21.583432 -17.246741)
			(xy 21.604773 -17.324819) (xy 21.618253 -17.40463) (xy 21.621496 -17.444974) (xy 21.623168 -17.461457)
			(xy 21.633805 -17.492818) (xy 21.652154 -17.520386) (xy 21.67698 -17.542303) (xy 21.706609 -17.557093)
			(xy 21.739047 -17.56376) (xy 21.755608 -17.563338) (xy 21.782769 -17.561958) (xy 21.837159 -17.561958)
			(xy 21.86432 -17.563338) (xy 21.880887 -17.563732) (xy 21.91334 -17.557097) (xy 21.942986 -17.542324)
			(xy 21.967825 -17.52041) (xy 21.986179 -17.492837) (xy 21.996807 -17.461465) (xy 21.998432 -17.444974)
			(xy 22.001723 -17.404632) (xy 22.015204 -17.324816) (xy 22.036546 -17.246735) (xy 22.065538 -17.171159)
			(xy 22.101894 -17.098838) (xy 22.145254 -17.030485) (xy 22.195189 -16.966777) (xy 22.251206 -16.908345)
			(xy 22.312749 -16.855765) (xy 22.379211 -16.809559) (xy 22.449934 -16.770184) (xy 22.524219 -16.738028)
			(xy 22.60133 -16.713409) (xy 22.680505 -16.696573) (xy 22.760961 -16.687684) (xy 22.841902 -16.68683)
			(xy 22.922528 -16.694021) (xy 23.00204 -16.709186) (xy 23.079653 -16.732173) (xy 23.154599 -16.762756)
			(xy 23.226137 -16.800632) (xy 23.293558 -16.845427) (xy 23.356196 -16.896697) (xy 23.413432 -16.953936)
			(xy 23.464699 -17.016577) (xy 23.50949 -17.084) (xy 23.547362 -17.15554) (xy 23.577941 -17.230487)
			(xy 23.600925 -17.308101) (xy 23.616084 -17.387614) (xy 23.623271 -17.46824) (xy 23.622414 -17.549181)
			(xy 23.613521 -17.629637) (xy 23.59668 -17.708811) (xy 23.572057 -17.785921) (xy 23.539897 -17.860204)
			(xy 23.500518 -17.930925) (xy 23.454308 -17.997385) (xy 23.401726 -18.058925) (xy 23.34329 -18.114939)
			(xy 23.27958 -18.16487) (xy 23.211225 -18.208227) (xy 23.138901 -18.244579) (xy 23.063324 -18.273567)
			(xy 22.985242 -18.294905) (xy 22.905426 -18.308382) (xy 22.86508 -18.311622) (xy 22.848612 -18.31324)
			(xy 22.817287 -18.323865) (xy 22.789744 -18.342184) (xy 22.767834 -18.366966) (xy 22.753028 -18.396546)
			(xy 22.746321 -18.428937) (xy 22.746716 -18.44548) (xy 22.74824 -18.50009) (xy 22.746716 -18.554446)
			(xy 22.746248 -18.571015) (xy 22.752892 -18.603476) (xy 22.767678 -18.633129) (xy 22.789607 -18.65797)
			(xy 22.817196 -18.67632) (xy 22.848583 -18.68694) (xy 22.86508 -18.688558) (xy 22.906389 -18.691846)
			(xy 22.98807 -18.705864) (xy 23.067903 -18.728114) (xy 23.145059 -18.758365) (xy 23.218741 -18.796303)
			(xy 23.288183 -18.841536) (xy 23.352668 -18.893594) (xy 23.411525 -18.951938) (xy 23.464146 -19.015963)
			(xy 23.509986 -19.085007) (xy 23.548568 -19.158353) (xy 23.579494 -19.235242) (xy 23.602442 -19.314876)
			(xy 23.610316 -19.355562) (xy 23.614838 -19.378179) (xy 23.631112 -19.421334) (xy 23.654905 -19.460845)
			(xy 23.685436 -19.495414) (xy 23.721703 -19.523908) (xy 23.762516 -19.545391) (xy 23.806535 -19.559157)
			(xy 23.852316 -19.564756) (xy 23.898355 -19.562002) (xy 23.943142 -19.550988) (xy 23.985207 -19.532073)
			(xy 24.023168 -19.505879) (xy 24.03983 -19.489928) (xy 24.815292 -18.71472) (xy 26.999692 -18.71472)
			(xy 28.079446 -17.634712) (xy 28.996894 -17.634712) (xy 29.020862 -17.634123) (xy 29.067947 -17.625137)
			(xy 29.112513 -17.607484) (xy 29.15298 -17.581788) (xy 29.187911 -17.548962) (xy 29.216069 -17.510168)
			(xy 29.236455 -17.466784) (xy 29.248346 -17.420347) (xy 29.250386 -17.39646) (xy 29.252694 -17.366483)
			(xy 29.264188 -17.307467) (xy 29.283308 -17.250464) (xy 29.309726 -17.196455) (xy 29.342986 -17.146368)
			(xy 29.382517 -17.101066) (xy 29.427637 -17.061329) (xy 29.477572 -17.02784) (xy 29.53146 -17.001176)
			(xy 29.588375 -16.981795) (xy 29.647337 -16.970032) (xy 29.707332 -16.966088) (xy 29.767327 -16.970032)
			(xy 29.826289 -16.981795) (xy 29.883204 -17.001176) (xy 29.937092 -17.02784) (xy 29.987027 -17.061329)
			(xy 30.032147 -17.101066) (xy 30.071678 -17.146368) (xy 30.104938 -17.196455) (xy 30.131356 -17.250464)
			(xy 30.150476 -17.307467) (xy 30.16197 -17.366483) (xy 30.164278 -17.39646) (xy 30.166317 -17.420348)
			(xy 30.178207 -17.466788) (xy 30.198593 -17.510176) (xy 30.22675 -17.548973) (xy 30.261681 -17.581804)
			(xy 30.302147 -17.607505) (xy 30.346714 -17.625164) (xy 30.393801 -17.634156) (xy 30.41777 -17.634712)
			(xy 30.710886 -17.634712) (xy 30.741112 -17.616678) (xy 30.767688 -17.601309) (xy 30.824031 -17.576931)
			(xy 30.883127 -17.560304) (xy 30.943916 -17.551726) (xy 31.005305 -17.551352) (xy 31.066194 -17.559187)
			(xy 31.125488 -17.575092) (xy 31.182124 -17.59878) (xy 31.235086 -17.629827) (xy 31.283421 -17.667676)
			(xy 31.303868 -17.688661) (xy 71.399392 -17.688661) (xy 71.399392 -17.617339) (xy 71.407378 -17.546465)
			(xy 71.423248 -17.47693) (xy 71.446805 -17.40961) (xy 71.47775 -17.345351) (xy 71.515696 -17.28496)
			(xy 71.560165 -17.229198) (xy 71.610598 -17.178765) (xy 71.66636 -17.134296) (xy 71.726751 -17.09635)
			(xy 71.79101 -17.065405) (xy 71.85833 -17.041848) (xy 71.927865 -17.025978) (xy 71.998739 -17.017992)
			(xy 72.070061 -17.017992) (xy 72.140935 -17.025978) (xy 72.21047 -17.041848) (xy 72.27779 -17.065405)
			(xy 72.342049 -17.09635) (xy 72.40244 -17.134296) (xy 72.458202 -17.178765) (xy 72.508635 -17.229198)
			(xy 72.553104 -17.28496) (xy 72.59105 -17.345351) (xy 72.621995 -17.40961) (xy 72.645552 -17.47693)
			(xy 72.661422 -17.546465) (xy 72.669408 -17.617339) (xy 72.669908 -17.653) (xy 72.669408 -17.688661)
			(xy 72.661422 -17.759535) (xy 72.645552 -17.82907) (xy 72.621995 -17.89639) (xy 72.59105 -17.960649)
			(xy 72.553104 -18.02104) (xy 72.508635 -18.076802) (xy 72.458202 -18.127235) (xy 72.40244 -18.171704)
			(xy 72.342049 -18.20965) (xy 72.27779 -18.240595) (xy 72.21047 -18.264152) (xy 72.140935 -18.280022)
			(xy 72.070061 -18.288008) (xy 71.998739 -18.288008) (xy 71.927865 -18.280022) (xy 71.85833 -18.264152)
			(xy 71.79101 -18.240595) (xy 71.726751 -18.20965) (xy 71.66636 -18.171704) (xy 71.610598 -18.127235)
			(xy 71.560165 -18.076802) (xy 71.515696 -18.02104) (xy 71.47775 -17.960649) (xy 71.446805 -17.89639)
			(xy 71.423248 -17.82907) (xy 71.407378 -17.759535) (xy 71.399392 -17.688661) (xy 31.303868 -17.688661)
			(xy 31.326263 -17.711646) (xy 31.362842 -17.760949) (xy 31.392502 -17.814699) (xy 31.414711 -17.871932)
			(xy 31.429069 -17.93162) (xy 31.435319 -17.992691) (xy 31.433349 -18.05405) (xy 31.423194 -18.114595)
			(xy 31.405037 -18.173239) (xy 31.379203 -18.228929) (xy 31.346156 -18.280666) (xy 31.306489 -18.327521)
			(xy 31.260915 -18.368652) (xy 31.210251 -18.403322) (xy 31.155408 -18.430908) (xy 31.097368 -18.450915)
			(xy 31.037176 -18.462983) (xy 30.97591 -18.466897) (xy 30.914671 -18.462585) (xy 30.854558 -18.450125)
			(xy 30.82544 -18.4404) (xy 30.804866 -18.433288) (xy 29.14904 -18.433288) (xy 29.126718 -18.433791)
			(xy 29.082759 -18.441586) (xy 29.040838 -18.456943) (xy 29.002247 -18.47939) (xy 28.968172 -18.508235)
			(xy 28.939662 -18.542591) (xy 28.934164 -18.552261) (xy 35.966392 -18.552261) (xy 35.966392 -18.480939)
			(xy 35.974378 -18.410065) (xy 35.990248 -18.34053) (xy 36.013805 -18.27321) (xy 36.04475 -18.208951)
			(xy 36.082696 -18.14856) (xy 36.127165 -18.092798) (xy 36.177598 -18.042365) (xy 36.23336 -17.997896)
			(xy 36.293751 -17.95995) (xy 36.35801 -17.929005) (xy 36.42533 -17.905448) (xy 36.494865 -17.889578)
			(xy 36.565739 -17.881592) (xy 36.637061 -17.881592) (xy 36.707935 -17.889578) (xy 36.77747 -17.905448)
			(xy 36.84479 -17.929005) (xy 36.909049 -17.95995) (xy 36.96944 -17.997896) (xy 37.025202 -18.042365)
			(xy 37.075635 -18.092798) (xy 37.120104 -18.14856) (xy 37.15805 -18.208951) (xy 37.188995 -18.27321)
			(xy 37.212552 -18.34053) (xy 37.228422 -18.410065) (xy 37.236408 -18.480939) (xy 37.236908 -18.5166)
			(xy 37.236408 -18.552261) (xy 37.228422 -18.623135) (xy 37.221409 -18.653861) (xy 43.637192 -18.653861)
			(xy 43.637192 -18.582539) (xy 43.645178 -18.511665) (xy 43.661048 -18.44213) (xy 43.684605 -18.37481)
			(xy 43.71555 -18.310551) (xy 43.753496 -18.25016) (xy 43.797965 -18.194398) (xy 43.848398 -18.143965)
			(xy 43.90416 -18.099496) (xy 43.964551 -18.06155) (xy 44.02881 -18.030605) (xy 44.09613 -18.007048)
			(xy 44.165665 -17.991178) (xy 44.236539 -17.983192) (xy 44.307861 -17.983192) (xy 44.378735 -17.991178)
			(xy 44.44827 -18.007048) (xy 44.51559 -18.030605) (xy 44.579849 -18.06155) (xy 44.64024 -18.099496)
			(xy 44.696002 -18.143965) (xy 44.746435 -18.194398) (xy 44.790904 -18.25016) (xy 44.82885 -18.310551)
			(xy 44.859795 -18.37481) (xy 44.883352 -18.44213) (xy 44.896893 -18.501461) (xy 51.866792 -18.501461)
			(xy 51.866792 -18.430139) (xy 51.874778 -18.359265) (xy 51.890648 -18.28973) (xy 51.914205 -18.22241)
			(xy 51.94515 -18.158151) (xy 51.983096 -18.09776) (xy 52.027565 -18.041998) (xy 52.077998 -17.991565)
			(xy 52.13376 -17.947096) (xy 52.194151 -17.90915) (xy 52.25841 -17.878205) (xy 52.32573 -17.854648)
			(xy 52.395265 -17.838778) (xy 52.466139 -17.830792) (xy 52.537461 -17.830792) (xy 52.608335 -17.838778)
			(xy 52.67787 -17.854648) (xy 52.74519 -17.878205) (xy 52.809449 -17.90915) (xy 52.86984 -17.947096)
			(xy 52.925602 -17.991565) (xy 52.976035 -18.041998) (xy 53.020504 -18.09776) (xy 53.05845 -18.158151)
			(xy 53.089395 -18.22241) (xy 53.112952 -18.28973) (xy 53.128822 -18.359265) (xy 53.136808 -18.430139)
			(xy 53.137308 -18.4658) (xy 53.136808 -18.501461) (xy 53.128822 -18.572335) (xy 53.112952 -18.64187)
			(xy 53.089395 -18.70919) (xy 53.05845 -18.773449) (xy 53.020504 -18.83384) (xy 52.976035 -18.889602)
			(xy 52.957776 -18.907861) (xy 63.982592 -18.907861) (xy 63.982592 -18.836539) (xy 63.990578 -18.765665)
			(xy 64.006448 -18.69613) (xy 64.030005 -18.62881) (xy 64.06095 -18.564551) (xy 64.098896 -18.50416)
			(xy 64.143365 -18.448398) (xy 64.193798 -18.397965) (xy 64.24956 -18.353496) (xy 64.309951 -18.31555)
			(xy 64.37421 -18.284605) (xy 64.44153 -18.261048) (xy 64.511065 -18.245178) (xy 64.581939 -18.237192)
			(xy 64.653261 -18.237192) (xy 64.724135 -18.245178) (xy 64.79367 -18.261048) (xy 64.86099 -18.284605)
			(xy 64.925249 -18.31555) (xy 64.98564 -18.353496) (xy 65.041402 -18.397965) (xy 65.091835 -18.448398)
			(xy 65.136304 -18.50416) (xy 65.17425 -18.564551) (xy 65.205195 -18.62881) (xy 65.228752 -18.69613)
			(xy 65.244622 -18.765665) (xy 65.252608 -18.836539) (xy 65.253108 -18.8722) (xy 65.252608 -18.907861)
			(xy 65.244622 -18.978735) (xy 65.228752 -19.04827) (xy 65.205195 -19.11559) (xy 65.17425 -19.179849)
			(xy 65.136304 -19.24024) (xy 65.091835 -19.296002) (xy 65.041402 -19.346435) (xy 64.98564 -19.390904)
			(xy 64.925249 -19.42885) (xy 64.86099 -19.459795) (xy 64.79367 -19.483352) (xy 64.724135 -19.499222)
			(xy 64.653261 -19.507208) (xy 64.581939 -19.507208) (xy 64.511065 -19.499222) (xy 64.44153 -19.483352)
			(xy 64.37421 -19.459795) (xy 64.309951 -19.42885) (xy 64.24956 -19.390904) (xy 64.193798 -19.346435)
			(xy 64.143365 -19.296002) (xy 64.098896 -19.24024) (xy 64.06095 -19.179849) (xy 64.030005 -19.11559)
			(xy 64.006448 -19.04827) (xy 63.990578 -18.978735) (xy 63.982592 -18.907861) (xy 52.957776 -18.907861)
			(xy 52.925602 -18.940035) (xy 52.86984 -18.984504) (xy 52.809449 -19.02245) (xy 52.74519 -19.053395)
			(xy 52.67787 -19.076952) (xy 52.608335 -19.092822) (xy 52.537461 -19.100808) (xy 52.466139 -19.100808)
			(xy 52.395265 -19.092822) (xy 52.32573 -19.076952) (xy 52.25841 -19.053395) (xy 52.194151 -19.02245)
			(xy 52.13376 -18.984504) (xy 52.077998 -18.940035) (xy 52.027565 -18.889602) (xy 51.983096 -18.83384)
			(xy 51.94515 -18.773449) (xy 51.914205 -18.70919) (xy 51.890648 -18.64187) (xy 51.874778 -18.572335)
			(xy 51.866792 -18.501461) (xy 44.896893 -18.501461) (xy 44.899222 -18.511665) (xy 44.907208 -18.582539)
			(xy 44.907708 -18.6182) (xy 44.907208 -18.653861) (xy 44.899222 -18.724735) (xy 44.883352 -18.79427)
			(xy 44.859795 -18.86159) (xy 44.82885 -18.925849) (xy 44.790904 -18.98624) (xy 44.746435 -19.042002)
			(xy 44.696002 -19.092435) (xy 44.64024 -19.136904) (xy 44.579849 -19.17485) (xy 44.51559 -19.205795)
			(xy 44.44827 -19.229352) (xy 44.378735 -19.245222) (xy 44.307861 -19.253208) (xy 44.236539 -19.253208)
			(xy 44.165665 -19.245222) (xy 44.09613 -19.229352) (xy 44.02881 -19.205795) (xy 43.964551 -19.17485)
			(xy 43.90416 -19.136904) (xy 43.848398 -19.092435) (xy 43.797965 -19.042002) (xy 43.753496 -18.98624)
			(xy 43.71555 -18.925849) (xy 43.684605 -18.86159) (xy 43.661048 -18.79427) (xy 43.645178 -18.724735)
			(xy 43.637192 -18.653861) (xy 37.221409 -18.653861) (xy 37.212552 -18.69267) (xy 37.188995 -18.75999)
			(xy 37.15805 -18.824249) (xy 37.120104 -18.88464) (xy 37.075635 -18.940402) (xy 37.025202 -18.990835)
			(xy 36.96944 -19.035304) (xy 36.909049 -19.07325) (xy 36.84479 -19.104195) (xy 36.77747 -19.127752)
			(xy 36.707935 -19.143622) (xy 36.637061 -19.151608) (xy 36.565739 -19.151608) (xy 36.494865 -19.143622)
			(xy 36.42533 -19.127752) (xy 36.35801 -19.104195) (xy 36.293751 -19.07325) (xy 36.23336 -19.035304)
			(xy 36.177598 -18.990835) (xy 36.127165 -18.940402) (xy 36.082696 -18.88464) (xy 36.04475 -18.824249)
			(xy 36.013805 -18.75999) (xy 35.990248 -18.69267) (xy 35.974378 -18.623135) (xy 35.966392 -18.552261)
			(xy 28.934164 -18.552261) (xy 28.917595 -18.5814) (xy 28.902649 -18.623469) (xy 28.895285 -18.667502)
			(xy 28.89504 -18.689828) (xy 28.894755 -18.720744) (xy 28.887045 -18.782085) (xy 28.871147 -18.84183)
			(xy 28.847352 -18.89889) (xy 28.816092 -18.952229) (xy 28.777936 -19.000873) (xy 28.73358 -19.043939)
			(xy 28.68383 -19.080641) (xy 28.629592 -19.110312) (xy 28.571853 -19.132412) (xy 28.511665 -19.146538)
			(xy 28.450123 -19.152433) (xy 28.388348 -19.149991) (xy 28.327464 -19.139254) (xy 28.268579 -19.120419)
			(xy 28.212766 -19.093829) (xy 28.16104 -19.059967) (xy 28.137358 -19.040094) (xy 28.118998 -19.024875)
			(xy 28.077791 -19.000881) (xy 28.032834 -18.984988) (xy 27.985703 -18.977754) (xy 27.938049 -18.979432)
			(xy 27.891544 -18.989964) (xy 27.847816 -19.008979) (xy 27.8084 -19.035813) (xy 27.791156 -19.052286)
			(xy 27.3304 -19.512788) (xy 25.146 -19.512788) (xy 23.794968 -20.864068) (xy 26.785314 -20.864068)
			(xy 26.789385 -20.808446) (xy 26.801511 -20.754009) (xy 26.821434 -20.701918) (xy 26.84873 -20.653283)
			(xy 26.882816 -20.60914) (xy 26.922965 -20.570431) (xy 26.968323 -20.53798) (xy 27.017923 -20.512479)
			(xy 27.070707 -20.494472) (xy 27.12555 -20.484342) (xy 27.181284 -20.482305) (xy 27.236721 -20.488405)
			(xy 27.290678 -20.502511) (xy 27.342007 -20.524323) (xy 27.389613 -20.553377) (xy 27.432481 -20.589052)
			(xy 27.469698 -20.630589) (xy 27.500471 -20.677102) (xy 27.524143 -20.727599) (xy 27.540211 -20.781006)
			(xy 27.548331 -20.836182) (xy 27.54884 -20.864068) (xy 27.548331 -20.891954) (xy 27.544959 -20.914868)
			(xy 28.106114 -20.914868) (xy 28.110185 -20.859246) (xy 28.122311 -20.804809) (xy 28.142234 -20.752718)
			(xy 28.16953 -20.704083) (xy 28.203616 -20.65994) (xy 28.243765 -20.621231) (xy 28.289123 -20.58878)
			(xy 28.338723 -20.563279) (xy 28.391507 -20.545272) (xy 28.44635 -20.535142) (xy 28.502084 -20.533105)
			(xy 28.557521 -20.539205) (xy 28.611478 -20.553311) (xy 28.662807 -20.575123) (xy 28.710413 -20.604177)
			(xy 28.753281 -20.639852) (xy 28.790498 -20.681389) (xy 28.821271 -20.727902) (xy 28.844943 -20.778399)
			(xy 28.861011 -20.831806) (xy 28.869131 -20.886982) (xy 28.86964 -20.914868) (xy 28.869131 -20.942754)
			(xy 28.865759 -20.965668) (xy 29.376114 -20.965668) (xy 29.380185 -20.910046) (xy 29.392311 -20.855609)
			(xy 29.412234 -20.803518) (xy 29.43953 -20.754883) (xy 29.473616 -20.71074) (xy 29.513765 -20.672031)
			(xy 29.559123 -20.63958) (xy 29.608723 -20.614079) (xy 29.661507 -20.596072) (xy 29.71635 -20.585942)
			(xy 29.772084 -20.583905) (xy 29.827521 -20.590005) (xy 29.881478 -20.604111) (xy 29.932807 -20.625923)
			(xy 29.980413 -20.654977) (xy 30.023281 -20.690652) (xy 30.060498 -20.732189) (xy 30.091271 -20.778702)
			(xy 30.114943 -20.829199) (xy 30.131011 -20.882606) (xy 30.13848 -20.933357) (xy 30.79846 -20.933357)
			(xy 30.803541 -20.877812) (xy 30.816655 -20.823599) (xy 30.837521 -20.771872) (xy 30.865696 -20.723734)
			(xy 30.900578 -20.680211) (xy 30.941425 -20.642229) (xy 30.987367 -20.6106) (xy 31.037424 -20.585995)
			(xy 31.090529 -20.56894) (xy 31.145552 -20.559798) (xy 31.201319 -20.558765) (xy 31.229046 -20.561808)
			(xy 31.252129 -20.564202) (xy 31.298459 -20.561641) (xy 31.343555 -20.550712) (xy 31.385918 -20.53178)
			(xy 31.42414 -20.505472) (xy 31.456952 -20.472664) (xy 31.483265 -20.434445) (xy 31.502202 -20.392084)
			(xy 31.513136 -20.34699) (xy 31.515703 -20.30066) (xy 31.513272 -20.277582) (xy 31.510233 -20.249862)
			(xy 31.511274 -20.194108) (xy 31.520421 -20.1391) (xy 31.537478 -20.08601) (xy 31.562082 -20.035968)
			(xy 31.593709 -19.990041) (xy 31.631684 -19.949207) (xy 31.6752 -19.914337) (xy 31.723328 -19.886173)
			(xy 31.775044 -19.865315) (xy 31.829245 -19.852208) (xy 31.884776 -19.847131) (xy 31.940456 -19.850192)
			(xy 31.995096 -19.861327) (xy 32.047533 -19.880296) (xy 32.096651 -19.906698) (xy 32.141401 -19.939968)
			(xy 32.180832 -19.979399) (xy 32.214102 -20.024149) (xy 32.240504 -20.073267) (xy 32.259473 -20.125704)
			(xy 32.263766 -20.146772) (xy 101.18801 -20.146772) (xy 101.192081 -20.09115) (xy 101.204207 -20.036713)
			(xy 101.22413 -19.984622) (xy 101.251426 -19.935987) (xy 101.285512 -19.891844) (xy 101.325661 -19.853135)
			(xy 101.371019 -19.820684) (xy 101.420619 -19.795183) (xy 101.473403 -19.777176) (xy 101.528246 -19.767046)
			(xy 101.58398 -19.765009) (xy 101.639417 -19.771109) (xy 101.693374 -19.785215) (xy 101.744703 -19.807027)
			(xy 101.792309 -19.836081) (xy 101.835177 -19.871756) (xy 101.872394 -19.913293) (xy 101.872597 -19.9136)
			(xy 106.787948 -19.9136) (xy 106.792019 -19.857978) (xy 106.804145 -19.803541) (xy 106.824068 -19.75145)
			(xy 106.851364 -19.702815) (xy 106.88545 -19.658672) (xy 106.925599 -19.619963) (xy 106.970957 -19.587512)
			(xy 107.020557 -19.562011) (xy 107.073341 -19.544004) (xy 107.128184 -19.533874) (xy 107.183918 -19.531837)
			(xy 107.239355 -19.537937) (xy 107.293312 -19.552043) (xy 107.344641 -19.573855) (xy 107.392247 -19.602909)
			(xy 107.435115 -19.638584) (xy 107.472332 -19.680121) (xy 107.503105 -19.726634) (xy 107.526777 -19.777131)
			(xy 107.542845 -19.830538) (xy 107.550965 -19.885714) (xy 107.551474 -19.9136) (xy 107.550965 -19.941486)
			(xy 107.542845 -19.996662) (xy 107.526777 -20.050069) (xy 107.503105 -20.100566) (xy 107.472332 -20.147079)
			(xy 107.435115 -20.188616) (xy 107.392247 -20.224291) (xy 107.344641 -20.253345) (xy 107.293312 -20.275157)
			(xy 107.239355 -20.289263) (xy 107.183918 -20.295363) (xy 107.128184 -20.293326) (xy 107.073341 -20.283196)
			(xy 107.020557 -20.265189) (xy 106.970957 -20.239688) (xy 106.925599 -20.207237) (xy 106.88545 -20.168528)
			(xy 106.851364 -20.124385) (xy 106.824068 -20.07575) (xy 106.804145 -20.023659) (xy 106.792019 -19.969222)
			(xy 106.787948 -19.9136) (xy 101.872597 -19.9136) (xy 101.903167 -19.959806) (xy 101.926839 -20.010303)
			(xy 101.942907 -20.06371) (xy 101.951027 -20.118886) (xy 101.951536 -20.146772) (xy 101.951027 -20.174658)
			(xy 101.942907 -20.229834) (xy 101.926839 -20.283241) (xy 101.903167 -20.333738) (xy 101.872394 -20.380251)
			(xy 101.835177 -20.421788) (xy 101.792309 -20.457463) (xy 101.744703 -20.486517) (xy 101.693374 -20.508329)
			(xy 101.639417 -20.522435) (xy 101.58398 -20.528535) (xy 101.528246 -20.526498) (xy 101.473403 -20.516368)
			(xy 101.420619 -20.498361) (xy 101.371019 -20.47286) (xy 101.325661 -20.440409) (xy 101.285512 -20.4017)
			(xy 101.251426 -20.357557) (xy 101.22413 -20.308922) (xy 101.204207 -20.256831) (xy 101.192081 -20.202394)
			(xy 101.18801 -20.146772) (xy 32.263766 -20.146772) (xy 32.270608 -20.180344) (xy 32.273669 -20.236024)
			(xy 32.268592 -20.291555) (xy 32.255485 -20.345756) (xy 32.234627 -20.397472) (xy 32.206463 -20.4456)
			(xy 32.171593 -20.489116) (xy 32.130759 -20.527091) (xy 32.084832 -20.558718) (xy 32.03479 -20.583322)
			(xy 31.9817 -20.600379) (xy 31.926692 -20.609526) (xy 31.870938 -20.610567) (xy 31.843218 -20.607528)
			(xy 31.820141 -20.605056) (xy 31.773804 -20.607624) (xy 31.728703 -20.61856) (xy 31.686335 -20.6375)
			(xy 31.64811 -20.663817) (xy 31.615297 -20.696634) (xy 31.588985 -20.734863) (xy 31.57005 -20.777232)
			(xy 31.559119 -20.822335) (xy 31.556558 -20.868672) (xy 31.558992 -20.891754) (xy 31.562035 -20.919481)
			(xy 31.561002 -20.975248) (xy 31.55186 -21.030271) (xy 31.534805 -21.083376) (xy 31.5102 -21.133433)
			(xy 31.478571 -21.179375) (xy 31.440589 -21.220222) (xy 31.397066 -21.255104) (xy 31.348928 -21.283279)
			(xy 31.297201 -21.304145) (xy 31.242988 -21.317259) (xy 31.187443 -21.32234) (xy 31.13175 -21.31928)
			(xy 31.077096 -21.308146) (xy 31.024645 -21.289172) (xy 30.975515 -21.262765) (xy 30.930753 -21.229487)
			(xy 30.891313 -21.190047) (xy 30.858035 -21.145285) (xy 30.831628 -21.096155) (xy 30.812654 -21.043704)
			(xy 30.80152 -20.98905) (xy 30.79846 -20.933357) (xy 30.13848 -20.933357) (xy 30.139131 -20.937782)
			(xy 30.13964 -20.965668) (xy 30.139131 -20.993554) (xy 30.131011 -21.04873) (xy 30.114943 -21.102137)
			(xy 30.091271 -21.152634) (xy 30.060498 -21.199147) (xy 30.023281 -21.240684) (xy 29.980413 -21.276359)
			(xy 29.932807 -21.305413) (xy 29.881478 -21.327225) (xy 29.827521 -21.341331) (xy 29.772084 -21.347431)
			(xy 29.71635 -21.345394) (xy 29.661507 -21.335264) (xy 29.608723 -21.317257) (xy 29.559123 -21.291756)
			(xy 29.513765 -21.259305) (xy 29.473616 -21.220596) (xy 29.43953 -21.176453) (xy 29.412234 -21.127818)
			(xy 29.392311 -21.075727) (xy 29.380185 -21.02129) (xy 29.376114 -20.965668) (xy 28.865759 -20.965668)
			(xy 28.861011 -20.99793) (xy 28.844943 -21.051337) (xy 28.821271 -21.101834) (xy 28.790498 -21.148347)
			(xy 28.753281 -21.189884) (xy 28.710413 -21.225559) (xy 28.662807 -21.254613) (xy 28.611478 -21.276425)
			(xy 28.557521 -21.290531) (xy 28.502084 -21.296631) (xy 28.44635 -21.294594) (xy 28.391507 -21.284464)
			(xy 28.338723 -21.266457) (xy 28.289123 -21.240956) (xy 28.243765 -21.208505) (xy 28.203616 -21.169796)
			(xy 28.16953 -21.125653) (xy 28.142234 -21.077018) (xy 28.122311 -21.024927) (xy 28.110185 -20.97049)
			(xy 28.106114 -20.914868) (xy 27.544959 -20.914868) (xy 27.540211 -20.94713) (xy 27.524143 -21.000537)
			(xy 27.500471 -21.051034) (xy 27.469698 -21.097547) (xy 27.432481 -21.139084) (xy 27.389613 -21.174759)
			(xy 27.342007 -21.203813) (xy 27.290678 -21.225625) (xy 27.236721 -21.239731) (xy 27.181284 -21.245831)
			(xy 27.12555 -21.243794) (xy 27.070707 -21.233664) (xy 27.017923 -21.215657) (xy 26.968323 -21.190156)
			(xy 26.922965 -21.157705) (xy 26.882816 -21.118996) (xy 26.84873 -21.074853) (xy 26.821434 -21.026218)
			(xy 26.801511 -20.974127) (xy 26.789385 -20.91969) (xy 26.785314 -20.864068) (xy 23.794968 -20.864068)
			(xy 23.761954 -20.897088) (xy 23.62073 -20.897088) (xy 23.604026 -20.897615) (xy 23.571768 -20.906304)
			(xy 23.542872 -20.92307) (xy 23.519317 -20.946762) (xy 23.502721 -20.975755) (xy 23.494219 -21.008064)
			(xy 23.494395 -21.041471) (xy 23.503237 -21.073688) (xy 23.511256 -21.08835) (xy 23.530868 -21.122581)
			(xy 23.56404 -21.194167) (xy 23.590123 -21.268628) (xy 23.608873 -21.345266) (xy 23.620112 -21.423359)
			(xy 23.623736 -21.502173) (xy 23.619711 -21.580968) (xy 23.608073 -21.659003) (xy 23.588933 -21.735544)
			(xy 23.562471 -21.809872) (xy 23.528935 -21.881287) (xy 23.48864 -21.949119) (xy 23.441966 -22.01273)
			(xy 23.389351 -22.071522) (xy 23.377027 -22.082861) (xy 40.462192 -22.082861) (xy 40.462192 -22.011539)
			(xy 40.470178 -21.940665) (xy 40.486048 -21.87113) (xy 40.509605 -21.80381) (xy 40.54055 -21.739551)
			(xy 40.578496 -21.67916) (xy 40.622965 -21.623398) (xy 40.673398 -21.572965) (xy 40.72916 -21.528496)
			(xy 40.789551 -21.49055) (xy 40.85381 -21.459605) (xy 40.92113 -21.436048) (xy 40.990665 -21.420178)
			(xy 41.061539 -21.412192) (xy 41.132861 -21.412192) (xy 41.203735 -21.420178) (xy 41.27327 -21.436048)
			(xy 41.34059 -21.459605) (xy 41.404849 -21.49055) (xy 41.46524 -21.528496) (xy 41.491529 -21.549461)
			(xy 45.440592 -21.549461) (xy 45.440592 -21.478139) (xy 45.448578 -21.407265) (xy 45.464448 -21.33773)
			(xy 45.488005 -21.27041) (xy 45.51895 -21.206151) (xy 45.556896 -21.14576) (xy 45.601365 -21.089998)
			(xy 45.651798 -21.039565) (xy 45.70756 -20.995096) (xy 45.767951 -20.95715) (xy 45.83221 -20.926205)
			(xy 45.89953 -20.902648) (xy 45.969065 -20.886778) (xy 46.039939 -20.878792) (xy 46.111261 -20.878792)
			(xy 46.182135 -20.886778) (xy 46.25167 -20.902648) (xy 46.256105 -20.9042) (xy 102.787956 -20.9042)
			(xy 102.792027 -20.848578) (xy 102.804153 -20.794141) (xy 102.824076 -20.74205) (xy 102.851372 -20.693415)
			(xy 102.885458 -20.649272) (xy 102.925607 -20.610563) (xy 102.970965 -20.578112) (xy 103.020565 -20.552611)
			(xy 103.073349 -20.534604) (xy 103.128192 -20.524474) (xy 103.183926 -20.522437) (xy 103.239363 -20.528537)
			(xy 103.29332 -20.542643) (xy 103.344649 -20.564455) (xy 103.357941 -20.572567) (xy 104.388702 -20.572567)
			(xy 104.389236 -20.517088) (xy 104.397803 -20.462272) (xy 104.41422 -20.409275) (xy 104.438142 -20.359216)
			(xy 104.469064 -20.313151) (xy 104.506333 -20.272051) (xy 104.549163 -20.236784) (xy 104.596651 -20.208094)
			(xy 104.647794 -20.186586) (xy 104.701513 -20.172715) (xy 104.756675 -20.166772) (xy 104.812116 -20.168883)
			(xy 104.866666 -20.179003) (xy 104.919175 -20.19692) (xy 104.968534 -20.222255) (xy 104.991408 -20.237958)
			(xy 105.009323 -20.250186) (xy 105.048407 -20.26899) (xy 105.090116 -20.280885) (xy 105.133239 -20.285524)
			(xy 105.176523 -20.282774) (xy 105.218712 -20.272713) (xy 105.25858 -20.255634) (xy 105.294969 -20.232033)
			(xy 105.311194 -20.217638) (xy 105.331957 -20.199226) (xy 105.377741 -20.167876) (xy 105.427584 -20.143489)
			(xy 105.480435 -20.12658) (xy 105.535178 -20.117507) (xy 105.590657 -20.116461) (xy 105.645703 -20.123464)
			(xy 105.699153 -20.138368) (xy 105.74988 -20.160858) (xy 105.796814 -20.190461) (xy 105.838964 -20.226551)
			(xy 105.87544 -20.268366) (xy 105.905473 -20.315026) (xy 105.928429 -20.365544) (xy 105.943824 -20.418855)
			(xy 105.951333 -20.473834) (xy 105.950798 -20.52932) (xy 105.942229 -20.584144) (xy 105.925808 -20.637148)
			(xy 105.901881 -20.687214) (xy 105.889559 -20.705568) (xy 114.122182 -20.705568) (xy 114.122182 -20.645632)
			(xy 114.130005 -20.58621) (xy 114.145518 -20.528317) (xy 114.168454 -20.472944) (xy 114.198421 -20.421038)
			(xy 114.234908 -20.373488) (xy 114.277288 -20.331108) (xy 114.324838 -20.294621) (xy 114.376744 -20.264654)
			(xy 114.432117 -20.241718) (xy 114.49001 -20.226205) (xy 114.549432 -20.218382) (xy 114.609368 -20.218382)
			(xy 114.66879 -20.226205) (xy 114.726683 -20.241718) (xy 114.782056 -20.264654) (xy 114.833962 -20.294621)
			(xy 114.881512 -20.331108) (xy 114.923892 -20.373488) (xy 114.960379 -20.421038) (xy 114.990346 -20.472944)
			(xy 115.013282 -20.528317) (xy 115.028795 -20.58621) (xy 115.036618 -20.645632) (xy 115.037108 -20.6756)
			(xy 115.036618 -20.705568) (xy 115.028795 -20.76499) (xy 115.013282 -20.822883) (xy 114.990346 -20.878256)
			(xy 114.960379 -20.930162) (xy 114.923892 -20.977712) (xy 114.881512 -21.020092) (xy 114.833962 -21.056579)
			(xy 114.782056 -21.086546) (xy 114.726683 -21.109482) (xy 114.66879 -21.124995) (xy 114.609368 -21.132818)
			(xy 114.549432 -21.132818) (xy 114.49001 -21.124995) (xy 114.432117 -21.109482) (xy 114.376744 -21.086546)
			(xy 114.324838 -21.056579) (xy 114.277288 -21.020092) (xy 114.234908 -20.977712) (xy 114.198421 -20.930162)
			(xy 114.168454 -20.878256) (xy 114.145518 -20.822883) (xy 114.130005 -20.76499) (xy 114.122182 -20.705568)
			(xy 105.889559 -20.705568) (xy 105.870953 -20.733284) (xy 105.833676 -20.774388) (xy 105.790838 -20.809658)
			(xy 105.743341 -20.838349) (xy 105.69219 -20.859856) (xy 105.638462 -20.873725) (xy 105.583291 -20.879664)
			(xy 105.527842 -20.877548) (xy 105.473285 -20.86742) (xy 105.42077 -20.849495) (xy 105.371407 -20.82415)
			(xy 105.348532 -20.808442) (xy 105.330591 -20.796254) (xy 105.291514 -20.777446) (xy 105.24981 -20.765548)
			(xy 105.206692 -20.760903) (xy 105.163411 -20.763649) (xy 105.121225 -20.773703) (xy 105.081359 -20.790776)
			(xy 105.044971 -20.81437) (xy 105.028746 -20.828762) (xy 105.007988 -20.847173) (xy 104.962207 -20.878514)
			(xy 104.912369 -20.902893) (xy 104.859524 -20.919794) (xy 104.804789 -20.928861) (xy 104.749317 -20.929902)
			(xy 104.69428 -20.922897) (xy 104.640838 -20.907992) (xy 104.59012 -20.885502) (xy 104.543194 -20.855902)
			(xy 104.501052 -20.819816) (xy 104.464582 -20.778005) (xy 104.434554 -20.731352) (xy 104.411602 -20.680841)
			(xy 104.39621 -20.627538) (xy 104.388702 -20.572567) (xy 103.357941 -20.572567) (xy 103.392255 -20.593509)
			(xy 103.435123 -20.629184) (xy 103.47234 -20.670721) (xy 103.503113 -20.717234) (xy 103.526785 -20.767731)
			(xy 103.542853 -20.821138) (xy 103.550973 -20.876314) (xy 103.551482 -20.9042) (xy 103.550973 -20.932086)
			(xy 103.542853 -20.987262) (xy 103.526785 -21.040669) (xy 103.503113 -21.091166) (xy 103.47234 -21.137679)
			(xy 103.435123 -21.179216) (xy 103.392255 -21.214891) (xy 103.344649 -21.243945) (xy 103.29332 -21.265757)
			(xy 103.239363 -21.279863) (xy 103.183926 -21.285963) (xy 103.128192 -21.283926) (xy 103.073349 -21.273796)
			(xy 103.020565 -21.255789) (xy 102.970965 -21.230288) (xy 102.925607 -21.197837) (xy 102.885458 -21.159128)
			(xy 102.851372 -21.114985) (xy 102.824076 -21.06635) (xy 102.804153 -21.014259) (xy 102.792027 -20.959822)
			(xy 102.787956 -20.9042) (xy 46.256105 -20.9042) (xy 46.31899 -20.926205) (xy 46.383249 -20.95715)
			(xy 46.44364 -20.995096) (xy 46.499402 -21.039565) (xy 46.549835 -21.089998) (xy 46.594304 -21.14576)
			(xy 46.63225 -21.206151) (xy 46.663195 -21.27041) (xy 46.686752 -21.33773) (xy 46.702622 -21.407265)
			(xy 46.710608 -21.478139) (xy 46.711108 -21.5138) (xy 46.710608 -21.549461) (xy 46.702622 -21.620335)
			(xy 46.686752 -21.68987) (xy 46.66837 -21.7424) (xy 104.342182 -21.7424) (xy 104.346253 -21.686778)
			(xy 104.358379 -21.632341) (xy 104.378302 -21.58025) (xy 104.405598 -21.531615) (xy 104.439684 -21.487472)
			(xy 104.479833 -21.448763) (xy 104.525191 -21.416312) (xy 104.574791 -21.390811) (xy 104.627575 -21.372804)
			(xy 104.682418 -21.362674) (xy 104.738152 -21.360637) (xy 104.793589 -21.366737) (xy 104.847546 -21.380843)
			(xy 104.898875 -21.402655) (xy 104.946481 -21.431709) (xy 104.989349 -21.467384) (xy 105.026566 -21.508921)
			(xy 105.057339 -21.555434) (xy 105.081011 -21.605931) (xy 105.097079 -21.659338) (xy 105.105199 -21.714514)
			(xy 105.105708 -21.7424) (xy 105.105199 -21.770286) (xy 105.097079 -21.825462) (xy 105.081011 -21.878869)
			(xy 105.057339 -21.929366) (xy 105.026566 -21.975879) (xy 104.989349 -22.017416) (xy 104.946481 -22.053091)
			(xy 104.90703 -22.077168) (xy 114.680982 -22.077168) (xy 114.680982 -22.017232) (xy 114.688805 -21.95781)
			(xy 114.704318 -21.899917) (xy 114.727254 -21.844544) (xy 114.757221 -21.792638) (xy 114.793708 -21.745088)
			(xy 114.836088 -21.702708) (xy 114.883638 -21.666221) (xy 114.935544 -21.636254) (xy 114.990917 -21.613318)
			(xy 115.04881 -21.597805) (xy 115.108232 -21.589982) (xy 115.168168 -21.589982) (xy 115.22759 -21.597805)
			(xy 115.285483 -21.613318) (xy 115.340856 -21.636254) (xy 115.392762 -21.666221) (xy 115.440312 -21.702708)
			(xy 115.482692 -21.745088) (xy 115.519179 -21.792638) (xy 115.549146 -21.844544) (xy 115.572082 -21.899917)
			(xy 115.587595 -21.95781) (xy 115.595418 -22.017232) (xy 115.595908 -22.0472) (xy 115.595418 -22.077168)
			(xy 115.587595 -22.13659) (xy 115.572082 -22.194483) (xy 115.549146 -22.249856) (xy 115.519179 -22.301762)
			(xy 115.482692 -22.349312) (xy 115.440312 -22.391692) (xy 115.392762 -22.428179) (xy 115.340856 -22.458146)
			(xy 115.285483 -22.481082) (xy 115.22759 -22.496595) (xy 115.168168 -22.504418) (xy 115.108232 -22.504418)
			(xy 115.04881 -22.496595) (xy 114.990917 -22.481082) (xy 114.935544 -22.458146) (xy 114.883638 -22.428179)
			(xy 114.836088 -22.391692) (xy 114.793708 -22.349312) (xy 114.757221 -22.301762) (xy 114.727254 -22.249856)
			(xy 114.704318 -22.194483) (xy 114.688805 -22.13659) (xy 114.680982 -22.077168) (xy 104.90703 -22.077168)
			(xy 104.898875 -22.082145) (xy 104.847546 -22.103957) (xy 104.793589 -22.118063) (xy 104.738152 -22.124163)
			(xy 104.682418 -22.122126) (xy 104.627575 -22.111996) (xy 104.574791 -22.093989) (xy 104.525191 -22.068488)
			(xy 104.479833 -22.036037) (xy 104.439684 -21.997328) (xy 104.405598 -21.953185) (xy 104.378302 -21.90455)
			(xy 104.358379 -21.852459) (xy 104.346253 -21.798022) (xy 104.342182 -21.7424) (xy 46.66837 -21.7424)
			(xy 46.663195 -21.75719) (xy 46.63225 -21.821449) (xy 46.594304 -21.88184) (xy 46.549835 -21.937602)
			(xy 46.499402 -21.988035) (xy 46.44364 -22.032504) (xy 46.383249 -22.07045) (xy 46.31899 -22.101395)
			(xy 46.25167 -22.124952) (xy 46.182135 -22.140822) (xy 46.111261 -22.148808) (xy 46.039939 -22.148808)
			(xy 45.969065 -22.140822) (xy 45.89953 -22.124952) (xy 45.83221 -22.101395) (xy 45.767951 -22.07045)
			(xy 45.70756 -22.032504) (xy 45.651798 -21.988035) (xy 45.601365 -21.937602) (xy 45.556896 -21.88184)
			(xy 45.51895 -21.821449) (xy 45.488005 -21.75719) (xy 45.464448 -21.68987) (xy 45.448578 -21.620335)
			(xy 45.440592 -21.549461) (xy 41.491529 -21.549461) (xy 41.521002 -21.572965) (xy 41.571435 -21.623398)
			(xy 41.615904 -21.67916) (xy 41.65385 -21.739551) (xy 41.684795 -21.80381) (xy 41.708352 -21.87113)
			(xy 41.724222 -21.940665) (xy 41.732208 -22.011539) (xy 41.732708 -22.0472) (xy 41.732208 -22.082861)
			(xy 41.724222 -22.153735) (xy 41.708352 -22.22327) (xy 41.684795 -22.29059) (xy 41.65385 -22.354849)
			(xy 41.615904 -22.41524) (xy 41.571435 -22.471002) (xy 41.521002 -22.521435) (xy 41.46524 -22.565904)
			(xy 41.404849 -22.60385) (xy 41.34059 -22.634795) (xy 41.27327 -22.658352) (xy 41.203735 -22.674222)
			(xy 41.132861 -22.682208) (xy 41.061539 -22.682208) (xy 40.990665 -22.674222) (xy 40.92113 -22.658352)
			(xy 40.85381 -22.634795) (xy 40.789551 -22.60385) (xy 40.72916 -22.565904) (xy 40.673398 -22.521435)
			(xy 40.622965 -22.471002) (xy 40.578496 -22.41524) (xy 40.54055 -22.354849) (xy 40.509605 -22.29059)
			(xy 40.486048 -22.22327) (xy 40.470178 -22.153735) (xy 40.462192 -22.082861) (xy 23.377027 -22.082861)
			(xy 23.33129 -22.124943) (xy 23.268328 -22.172489) (xy 23.201057 -22.213714) (xy 23.13011 -22.248231)
			(xy 23.056154 -22.275715) (xy 22.979884 -22.295908) (xy 22.941026 -22.302724) (xy 22.890988 -22.310852)
			(xy 22.8346 -22.3774) (xy 20.9296 -22.3774) (xy 20.9296 -22.304502) (xy 20.890188 -22.309874) (xy 20.810739 -22.313833)
			(xy 20.731283 -22.310016) (xy 20.652579 -22.29846) (xy 20.57538 -22.279274) (xy 20.500423 -22.252643)
			(xy 20.428424 -22.21882) (xy 20.360072 -22.178129) (xy 20.296019 -22.130959) (xy 20.236878 -22.07776)
			(xy 20.183213 -22.019041) (xy 20.135538 -21.955363) (xy 20.094308 -21.887334) (xy 20.059917 -21.815605)
			(xy 20.032694 -21.74086) (xy 20.012899 -21.663815) (xy 20.000721 -21.585205) (xy 19.996277 -21.505782)
			(xy 19.999608 -21.426304) (xy 20.010683 -21.347532) (xy 20.029396 -21.270217) (xy 20.055569 -21.195098)
			(xy 20.088952 -21.122894) (xy 20.108672 -21.08835) (xy 20.116642 -21.073657) (xy 20.125509 -21.041445)
			(xy 20.125705 -21.008036) (xy 20.117216 -20.975722) (xy 20.100624 -20.946723) (xy 20.077068 -20.92303)
			(xy 20.048167 -20.906269) (xy 20.015903 -20.89759) (xy 19.999198 -20.897088) (xy 19.901154 -20.897088)
			(xy 19.672554 -21.125688) (xy 8.318754 -21.125688) (xy 7.023354 -22.421088) (xy 5.94106 -22.421088)
			(xy 5.924411 -22.421608) (xy 5.892249 -22.430234) (xy 5.863415 -22.446889) (xy 5.839872 -22.470437)
			(xy 5.823224 -22.499275) (xy 5.814605 -22.531439) (xy 5.814228 -22.542945) (xy 10.382999 -22.542945)
			(xy 10.382999 -22.457219) (xy 10.390909 -22.371859) (xy 10.406661 -22.287592) (xy 10.430121 -22.205139)
			(xy 10.461089 -22.125202) (xy 10.4993 -22.048463) (xy 10.544429 -21.975577) (xy 10.59609 -21.907166)
			(xy 10.653844 -21.843814) (xy 10.717196 -21.78606) (xy 10.785607 -21.734399) (xy 10.858493 -21.68927)
			(xy 10.935232 -21.651059) (xy 11.015169 -21.620091) (xy 11.097622 -21.596631) (xy 11.181889 -21.580879)
			(xy 11.267249 -21.572969) (xy 11.352975 -21.572969) (xy 11.438335 -21.580879) (xy 11.522602 -21.596631)
			(xy 11.605055 -21.620091) (xy 11.684992 -21.651059) (xy 11.761731 -21.68927) (xy 11.834617 -21.734399)
			(xy 11.903028 -21.78606) (xy 11.96638 -21.843814) (xy 12.024134 -21.907166) (xy 12.075795 -21.975577)
			(xy 12.120924 -22.048463) (xy 12.159135 -22.125202) (xy 12.190103 -22.205139) (xy 12.213563 -22.287592)
			(xy 12.229315 -22.371859) (xy 12.237225 -22.457219) (xy 12.23772 -22.500082) (xy 12.237225 -22.542945)
			(xy 12.229315 -22.628305) (xy 12.213563 -22.712572) (xy 12.190103 -22.795025) (xy 12.159135 -22.874962)
			(xy 12.120924 -22.951701) (xy 12.075795 -23.024587) (xy 12.024134 -23.092998) (xy 11.96638 -23.15635)
			(xy 11.903028 -23.214104) (xy 11.834617 -23.265765) (xy 11.761731 -23.310894) (xy 11.684992 -23.349105)
			(xy 11.605055 -23.380073) (xy 11.522602 -23.403533) (xy 11.438335 -23.419285) (xy 11.352975 -23.427195)
			(xy 11.267249 -23.427195) (xy 11.181889 -23.419285) (xy 11.097622 -23.403533) (xy 11.015169 -23.380073)
			(xy 10.935232 -23.349105) (xy 10.858493 -23.310894) (xy 10.785607 -23.265765) (xy 10.717196 -23.214104)
			(xy 10.653844 -23.15635) (xy 10.59609 -23.092998) (xy 10.544429 -23.024587) (xy 10.4993 -22.951701)
			(xy 10.461089 -22.874962) (xy 10.430121 -22.795025) (xy 10.406661 -22.712572) (xy 10.390909 -22.628305)
			(xy 10.382999 -22.542945) (xy 5.814228 -22.542945) (xy 5.81406 -22.548088) (xy 5.81406 -23.50008)
			(xy 19.996152 -23.50008) (xy 20.000196 -23.41905) (xy 20.012288 -23.338826) (xy 20.032307 -23.260204)
			(xy 20.060056 -23.183966) (xy 20.095257 -23.11087) (xy 20.137561 -23.041642) (xy 20.186548 -22.97697)
			(xy 20.241731 -22.917498) (xy 20.302561 -22.863815) (xy 20.368434 -22.816455) (xy 20.438695 -22.77589)
			(xy 20.512646 -22.742522) (xy 20.589552 -22.716683) (xy 20.668649 -22.69863) (xy 20.74915 -22.688542)
			(xy 20.830255 -22.686519) (xy 20.911159 -22.692582) (xy 20.991057 -22.70667) (xy 21.069155 -22.728643)
			(xy 21.144677 -22.758284) (xy 21.216873 -22.795296) (xy 21.285025 -22.839313) (xy 21.348455 -22.889898)
			(xy 21.406534 -22.946546) (xy 21.458684 -23.008696) (xy 21.504386 -23.075729) (xy 21.543187 -23.146979)
			(xy 21.574701 -23.221739) (xy 21.598615 -23.299265) (xy 21.61469 -23.378787) (xy 21.622768 -23.459515)
			(xy 21.623274 -23.50008) (xy 21.996148 -23.50008) (xy 22.000192 -23.41905) (xy 22.012284 -23.338826)
			(xy 22.032303 -23.260204) (xy 22.060052 -23.183966) (xy 22.095253 -23.11087) (xy 22.137557 -23.041642)
			(xy 22.186544 -22.97697) (xy 22.241727 -22.917498) (xy 22.302557 -22.863815) (xy 22.36843 -22.816455)
			(xy 22.438691 -22.77589) (xy 22.512642 -22.742522) (xy 22.589548 -22.716683) (xy 22.668645 -22.69863)
			(xy 22.749146 -22.688542) (xy 22.830251 -22.686519) (xy 22.911155 -22.692582) (xy 22.991053 -22.70667)
			(xy 23.069151 -22.728643) (xy 23.144673 -22.758284) (xy 23.216869 -22.795296) (xy 23.285021 -22.839313)
			(xy 23.348451 -22.889898) (xy 23.40653 -22.946546) (xy 23.45868 -23.008696) (xy 23.504382 -23.075729)
			(xy 23.543183 -23.146979) (xy 23.574697 -23.221739) (xy 23.598611 -23.299265) (xy 23.614686 -23.378787)
			(xy 23.622764 -23.459515) (xy 23.623074 -23.484332) (xy 26.792943 -23.484332) (xy 26.796946 -23.39647)
			(xy 26.808922 -23.309336) (xy 26.828773 -23.223652) (xy 26.856332 -23.140128) (xy 26.891373 -23.059456)
			(xy 26.933604 -22.982305) (xy 26.982676 -22.909314) (xy 27.038183 -22.841088) (xy 27.099663 -22.778192)
			(xy 27.166608 -22.721147) (xy 27.238463 -22.670426) (xy 27.314633 -22.626449) (xy 27.394486 -22.589581)
			(xy 27.477361 -22.560128) (xy 27.562571 -22.538332) (xy 27.64941 -22.524376) (xy 27.737158 -22.518373)
			(xy 27.748182 -22.518624) (xy 29.333444 -22.518624) (xy 31.26486 -22.518624) (xy 31.26486 -23.225861)
			(xy 32.740592 -23.225861) (xy 32.740592 -23.154539) (xy 32.748578 -23.083665) (xy 32.764448 -23.01413)
			(xy 32.788005 -22.94681) (xy 32.81895 -22.882551) (xy 32.856896 -22.82216) (xy 32.901365 -22.766398)
			(xy 32.951798 -22.715965) (xy 33.00756 -22.671496) (xy 33.067951 -22.63355) (xy 33.13221 -22.602605)
			(xy 33.19953 -22.579048) (xy 33.269065 -22.563178) (xy 33.339939 -22.555192) (xy 33.411261 -22.555192)
			(xy 33.482135 -22.563178) (xy 33.55167 -22.579048) (xy 33.61899 -22.602605) (xy 33.683249 -22.63355)
			(xy 33.74364 -22.671496) (xy 33.799402 -22.715965) (xy 33.849835 -22.766398) (xy 33.894304 -22.82216)
			(xy 33.93225 -22.882551) (xy 33.963027 -22.946461) (xy 34.874192 -22.946461) (xy 34.874192 -22.875139)
			(xy 34.882178 -22.804265) (xy 34.898048 -22.73473) (xy 34.921605 -22.66741) (xy 34.95255 -22.603151)
			(xy 34.990496 -22.54276) (xy 35.034965 -22.486998) (xy 35.085398 -22.436565) (xy 35.14116 -22.392096)
			(xy 35.201551 -22.35415) (xy 35.26581 -22.323205) (xy 35.33313 -22.299648) (xy 35.402665 -22.283778)
			(xy 35.473539 -22.275792) (xy 35.544861 -22.275792) (xy 35.615735 -22.283778) (xy 35.68527 -22.299648)
			(xy 35.75259 -22.323205) (xy 35.816849 -22.35415) (xy 35.87724 -22.392096) (xy 35.933002 -22.436565)
			(xy 35.983435 -22.486998) (xy 36.027904 -22.54276) (xy 36.06585 -22.603151) (xy 36.096795 -22.66741)
			(xy 36.120352 -22.73473) (xy 36.121812 -22.741128) (xy 101.98811 -22.741128) (xy 101.992181 -22.685506)
			(xy 102.004307 -22.631069) (xy 102.02423 -22.578978) (xy 102.051526 -22.530343) (xy 102.085612 -22.4862)
			(xy 102.125761 -22.447491) (xy 102.171119 -22.41504) (xy 102.220719 -22.389539) (xy 102.273503 -22.371532)
			(xy 102.328346 -22.361402) (xy 102.38408 -22.359365) (xy 102.439517 -22.365465) (xy 102.493474 -22.379571)
			(xy 102.544803 -22.401383) (xy 102.592409 -22.430437) (xy 102.635277 -22.466112) (xy 102.669583 -22.5044)
			(xy 103.588056 -22.5044) (xy 103.592127 -22.448778) (xy 103.604253 -22.394341) (xy 103.624176 -22.34225)
			(xy 103.651472 -22.293615) (xy 103.685558 -22.249472) (xy 103.725707 -22.210763) (xy 103.771065 -22.178312)
			(xy 103.820665 -22.152811) (xy 103.873449 -22.134804) (xy 103.928292 -22.124674) (xy 103.984026 -22.122637)
			(xy 104.039463 -22.128737) (xy 104.09342 -22.142843) (xy 104.144749 -22.164655) (xy 104.192355 -22.193709)
			(xy 104.235223 -22.229384) (xy 104.27244 -22.270921) (xy 104.303213 -22.317434) (xy 104.326885 -22.367931)
			(xy 104.342953 -22.421338) (xy 104.351073 -22.476514) (xy 104.351582 -22.5044) (xy 104.351073 -22.532286)
			(xy 104.342953 -22.587462) (xy 104.326885 -22.640869) (xy 104.303213 -22.691366) (xy 104.27244 -22.737879)
			(xy 104.235223 -22.779416) (xy 104.192355 -22.815091) (xy 104.144749 -22.844145) (xy 104.09342 -22.865957)
			(xy 104.039463 -22.880063) (xy 103.984026 -22.886163) (xy 103.928292 -22.884126) (xy 103.873449 -22.873996)
			(xy 103.820665 -22.855989) (xy 103.771065 -22.830488) (xy 103.725707 -22.798037) (xy 103.685558 -22.759328)
			(xy 103.651472 -22.715185) (xy 103.624176 -22.66655) (xy 103.604253 -22.614459) (xy 103.592127 -22.560022)
			(xy 103.588056 -22.5044) (xy 102.669583 -22.5044) (xy 102.672494 -22.507649) (xy 102.703267 -22.554162)
			(xy 102.726939 -22.604659) (xy 102.743007 -22.658066) (xy 102.751127 -22.713242) (xy 102.751636 -22.741128)
			(xy 102.751127 -22.769014) (xy 102.743007 -22.82419) (xy 102.726939 -22.877597) (xy 102.703267 -22.928094)
			(xy 102.672494 -22.974607) (xy 102.635277 -23.016144) (xy 102.592409 -23.051819) (xy 102.544803 -23.080873)
			(xy 102.493474 -23.102685) (xy 102.439517 -23.116791) (xy 102.38408 -23.122891) (xy 102.328346 -23.120854)
			(xy 102.273503 -23.110724) (xy 102.220719 -23.092717) (xy 102.171119 -23.067216) (xy 102.125761 -23.034765)
			(xy 102.085612 -22.996056) (xy 102.051526 -22.951913) (xy 102.02423 -22.903278) (xy 102.004307 -22.851187)
			(xy 101.992181 -22.79675) (xy 101.98811 -22.741128) (xy 36.121812 -22.741128) (xy 36.136222 -22.804265)
			(xy 36.144208 -22.875139) (xy 36.144708 -22.9108) (xy 36.144208 -22.946461) (xy 36.136222 -23.017335)
			(xy 36.120352 -23.08687) (xy 36.096795 -23.15419) (xy 36.06585 -23.218449) (xy 36.027904 -23.27884)
			(xy 35.983435 -23.334602) (xy 35.933002 -23.385035) (xy 35.87724 -23.429504) (xy 35.816849 -23.46745)
			(xy 35.75259 -23.498395) (xy 35.68527 -23.521952) (xy 35.615735 -23.537822) (xy 35.544861 -23.545808)
			(xy 35.473539 -23.545808) (xy 35.402665 -23.537822) (xy 35.33313 -23.521952) (xy 35.26581 -23.498395)
			(xy 35.201551 -23.46745) (xy 35.14116 -23.429504) (xy 35.085398 -23.385035) (xy 35.034965 -23.334602)
			(xy 34.990496 -23.27884) (xy 34.95255 -23.218449) (xy 34.921605 -23.15419) (xy 34.898048 -23.08687)
			(xy 34.882178 -23.017335) (xy 34.874192 -22.946461) (xy 33.963027 -22.946461) (xy 33.963195 -22.94681)
			(xy 33.986752 -23.01413) (xy 34.002622 -23.083665) (xy 34.010608 -23.154539) (xy 34.011108 -23.1902)
			(xy 34.010608 -23.225861) (xy 34.002622 -23.296735) (xy 33.986752 -23.36627) (xy 33.963195 -23.43359)
			(xy 33.93225 -23.497849) (xy 33.894304 -23.55824) (xy 33.849835 -23.614002) (xy 33.799402 -23.664435)
			(xy 33.74364 -23.708904) (xy 33.683249 -23.74685) (xy 33.61899 -23.777795) (xy 33.55167 -23.801352)
			(xy 33.482135 -23.817222) (xy 33.411261 -23.825208) (xy 33.339939 -23.825208) (xy 33.269065 -23.817222)
			(xy 33.19953 -23.801352) (xy 33.13221 -23.777795) (xy 33.067951 -23.74685) (xy 33.00756 -23.708904)
			(xy 32.951798 -23.664435) (xy 32.901365 -23.614002) (xy 32.856896 -23.55824) (xy 32.81895 -23.497849)
			(xy 32.788005 -23.43359) (xy 32.764448 -23.36627) (xy 32.748578 -23.296735) (xy 32.740592 -23.225861)
			(xy 31.26486 -23.225861) (xy 31.26486 -24.140261) (xy 68.783192 -24.140261) (xy 68.783192 -24.068939)
			(xy 68.791178 -23.998065) (xy 68.807048 -23.92853) (xy 68.830605 -23.86121) (xy 68.86155 -23.796951)
			(xy 68.899496 -23.73656) (xy 68.943965 -23.680798) (xy 68.994398 -23.630365) (xy 69.05016 -23.585896)
			(xy 69.110551 -23.54795) (xy 69.17481 -23.517005) (xy 69.24213 -23.493448) (xy 69.311665 -23.477578)
			(xy 69.382539 -23.469592) (xy 69.453861 -23.469592) (xy 69.494472 -23.474168) (xy 114.833382 -23.474168)
			(xy 114.833382 -23.414232) (xy 114.841205 -23.35481) (xy 114.856718 -23.296917) (xy 114.879654 -23.241544)
			(xy 114.909621 -23.189638) (xy 114.946108 -23.142088) (xy 114.988488 -23.099708) (xy 115.036038 -23.063221)
			(xy 115.087944 -23.033254) (xy 115.143317 -23.010318) (xy 115.20121 -22.994805) (xy 115.260632 -22.986982)
			(xy 115.320568 -22.986982) (xy 115.37999 -22.994805) (xy 115.437883 -23.010318) (xy 115.493256 -23.033254)
			(xy 115.545162 -23.063221) (xy 115.592712 -23.099708) (xy 115.635092 -23.142088) (xy 115.671579 -23.189638)
			(xy 115.701546 -23.241544) (xy 115.724482 -23.296917) (xy 115.739995 -23.35481) (xy 115.747818 -23.414232)
			(xy 115.748308 -23.4442) (xy 115.747818 -23.474168) (xy 115.739995 -23.53359) (xy 115.724482 -23.591483)
			(xy 115.701546 -23.646856) (xy 115.671579 -23.698762) (xy 115.635092 -23.746312) (xy 115.592712 -23.788692)
			(xy 115.545162 -23.825179) (xy 115.493256 -23.855146) (xy 115.437883 -23.878082) (xy 115.37999 -23.893595)
			(xy 115.320568 -23.901418) (xy 115.260632 -23.901418) (xy 115.20121 -23.893595) (xy 115.143317 -23.878082)
			(xy 115.087944 -23.855146) (xy 115.036038 -23.825179) (xy 114.988488 -23.788692) (xy 114.946108 -23.746312)
			(xy 114.909621 -23.698762) (xy 114.879654 -23.646856) (xy 114.856718 -23.591483) (xy 114.841205 -23.53359)
			(xy 114.833382 -23.474168) (xy 69.494472 -23.474168) (xy 69.524735 -23.477578) (xy 69.59427 -23.493448)
			(xy 69.66159 -23.517005) (xy 69.725849 -23.54795) (xy 69.78624 -23.585896) (xy 69.842002 -23.630365)
			(xy 69.892435 -23.680798) (xy 69.936904 -23.73656) (xy 69.97485 -23.796951) (xy 70.005795 -23.86121)
			(xy 70.029352 -23.92853) (xy 70.045222 -23.998065) (xy 70.053208 -24.068939) (xy 70.053708 -24.1046)
			(xy 70.053208 -24.140261) (xy 70.045222 -24.211135) (xy 70.029352 -24.28067) (xy 70.005795 -24.34799)
			(xy 69.97485 -24.412249) (xy 69.936904 -24.47264) (xy 69.892435 -24.528402) (xy 69.842002 -24.578835)
			(xy 69.78624 -24.623304) (xy 69.725849 -24.66125) (xy 69.711899 -24.667968) (xy 114.376182 -24.667968)
			(xy 114.376182 -24.608032) (xy 114.384005 -24.54861) (xy 114.399518 -24.490717) (xy 114.422454 -24.435344)
			(xy 114.452421 -24.383438) (xy 114.488908 -24.335888) (xy 114.531288 -24.293508) (xy 114.578838 -24.257021)
			(xy 114.630744 -24.227054) (xy 114.686117 -24.204118) (xy 114.74401 -24.188605) (xy 114.803432 -24.180782)
			(xy 114.863368 -24.180782) (xy 114.92279 -24.188605) (xy 114.980683 -24.204118) (xy 115.036056 -24.227054)
			(xy 115.087962 -24.257021) (xy 115.135512 -24.293508) (xy 115.177892 -24.335888) (xy 115.214379 -24.383438)
			(xy 115.244346 -24.435344) (xy 115.267282 -24.490717) (xy 115.282795 -24.54861) (xy 115.290618 -24.608032)
			(xy 115.291108 -24.638) (xy 115.290618 -24.667968) (xy 115.282795 -24.72739) (xy 115.267282 -24.785283)
			(xy 115.244346 -24.840656) (xy 115.214379 -24.892562) (xy 115.177892 -24.940112) (xy 115.135512 -24.982492)
			(xy 115.087962 -25.018979) (xy 115.036056 -25.048946) (xy 114.980683 -25.071882) (xy 114.92279 -25.087395)
			(xy 114.863368 -25.095218) (xy 114.803432 -25.095218) (xy 114.74401 -25.087395) (xy 114.686117 -25.071882)
			(xy 114.630744 -25.048946) (xy 114.578838 -25.018979) (xy 114.531288 -24.982492) (xy 114.488908 -24.940112)
			(xy 114.452421 -24.892562) (xy 114.422454 -24.840656) (xy 114.399518 -24.785283) (xy 114.384005 -24.72739)
			(xy 114.376182 -24.667968) (xy 69.711899 -24.667968) (xy 69.66159 -24.692195) (xy 69.59427 -24.715752)
			(xy 69.524735 -24.731622) (xy 69.453861 -24.739608) (xy 69.382539 -24.739608) (xy 69.311665 -24.731622)
			(xy 69.24213 -24.715752) (xy 69.17481 -24.692195) (xy 69.110551 -24.66125) (xy 69.05016 -24.623304)
			(xy 68.994398 -24.578835) (xy 68.943965 -24.528402) (xy 68.899496 -24.47264) (xy 68.86155 -24.412249)
			(xy 68.830605 -24.34799) (xy 68.807048 -24.28067) (xy 68.791178 -24.211135) (xy 68.783192 -24.140261)
			(xy 31.26486 -24.140261) (xy 31.26486 -24.45004) (xy 29.333444 -24.45004) (xy 29.333444 -22.518624)
			(xy 27.748182 -22.518624) (xy 27.825088 -22.520375) (xy 27.912473 -22.530365) (xy 27.998586 -22.54826)
			(xy 28.082716 -22.573911) (xy 28.164164 -22.607106) (xy 28.242257 -22.64757) (xy 28.316346 -22.694968)
			(xy 28.385818 -22.748907) (xy 28.450097 -22.80894) (xy 28.508651 -22.874569) (xy 28.560995 -22.945251)
			(xy 28.606694 -23.0204) (xy 28.64537 -23.099393) (xy 28.676702 -23.181576) (xy 28.700432 -23.266268)
			(xy 28.716362 -23.352767) (xy 28.72436 -23.440355) (xy 28.72486 -23.484332) (xy 28.72436 -23.528309)
			(xy 28.716362 -23.615897) (xy 28.700432 -23.702396) (xy 28.676702 -23.787088) (xy 28.64537 -23.869271)
			(xy 28.606694 -23.948264) (xy 28.560995 -24.023413) (xy 28.508651 -24.094095) (xy 28.450097 -24.159724)
			(xy 28.385818 -24.219757) (xy 28.316346 -24.273696) (xy 28.242257 -24.321094) (xy 28.164164 -24.361558)
			(xy 28.082716 -24.394753) (xy 27.998586 -24.420404) (xy 27.912473 -24.438299) (xy 27.825088 -24.448289)
			(xy 27.737158 -24.450291) (xy 27.64941 -24.444288) (xy 27.562571 -24.430332) (xy 27.477361 -24.408536)
			(xy 27.394486 -24.379083) (xy 27.314633 -24.342215) (xy 27.238463 -24.298238) (xy 27.166608 -24.247517)
			(xy 27.099663 -24.190472) (xy 27.038183 -24.127576) (xy 26.982676 -24.05935) (xy 26.933604 -23.986359)
			(xy 26.891373 -23.909208) (xy 26.856332 -23.828536) (xy 26.828773 -23.745012) (xy 26.808922 -23.659328)
			(xy 26.796946 -23.572194) (xy 26.792943 -23.484332) (xy 23.623074 -23.484332) (xy 23.62327 -23.50008)
			(xy 23.622764 -23.540645) (xy 23.614686 -23.621373) (xy 23.598611 -23.700895) (xy 23.574697 -23.778421)
			(xy 23.543183 -23.853181) (xy 23.504382 -23.924431) (xy 23.45868 -23.991464) (xy 23.40653 -24.053614)
			(xy 23.348451 -24.110262) (xy 23.285021 -24.160847) (xy 23.216869 -24.204864) (xy 23.144673 -24.241876)
			(xy 23.069151 -24.271517) (xy 22.991053 -24.29349) (xy 22.911155 -24.307578) (xy 22.830251 -24.313641)
			(xy 22.749146 -24.311618) (xy 22.668645 -24.30153) (xy 22.589548 -24.283477) (xy 22.512642 -24.257638)
			(xy 22.438691 -24.22427) (xy 22.36843 -24.183705) (xy 22.302557 -24.136345) (xy 22.241727 -24.082662)
			(xy 22.186544 -24.02319) (xy 22.137557 -23.958518) (xy 22.095253 -23.88929) (xy 22.060052 -23.816194)
			(xy 22.032303 -23.739956) (xy 22.012284 -23.661334) (xy 22.000192 -23.58111) (xy 21.996148 -23.50008)
			(xy 21.623274 -23.50008) (xy 21.622768 -23.540645) (xy 21.61469 -23.621373) (xy 21.598615 -23.700895)
			(xy 21.574701 -23.778421) (xy 21.543187 -23.853181) (xy 21.504386 -23.924431) (xy 21.458684 -23.991464)
			(xy 21.406534 -24.053614) (xy 21.348455 -24.110262) (xy 21.285025 -24.160847) (xy 21.216873 -24.204864)
			(xy 21.144677 -24.241876) (xy 21.069155 -24.271517) (xy 20.991057 -24.29349) (xy 20.911159 -24.307578)
			(xy 20.830255 -24.313641) (xy 20.74915 -24.311618) (xy 20.668649 -24.30153) (xy 20.589552 -24.283477)
			(xy 20.512646 -24.257638) (xy 20.438695 -24.22427) (xy 20.368434 -24.183705) (xy 20.302561 -24.136345)
			(xy 20.241731 -24.082662) (xy 20.186548 -24.02319) (xy 20.137561 -23.958518) (xy 20.095257 -23.88929)
			(xy 20.060056 -23.816194) (xy 20.032307 -23.739956) (xy 20.012288 -23.661334) (xy 20.000196 -23.58111)
			(xy 19.996152 -23.50008) (xy 5.81406 -23.50008) (xy 5.81406 -24.32304) (xy 3.882644 -24.32304) (xy 3.882644 -22.960584)
			(xy 3.882138 -22.937551) (xy 3.873829 -22.892241) (xy 3.857489 -22.84917) (xy 3.833654 -22.80975)
			(xy 3.803104 -22.775271) (xy 3.76684 -22.746864) (xy 3.72605 -22.725457) (xy 3.682069 -22.711753)
			(xy 3.636339 -22.706201) (xy 3.590357 -22.708982) (xy 3.54563 -22.720004) (xy 3.503621 -22.738908)
			(xy 3.465708 -22.765074) (xy 3.449066 -22.781006) (xy 3.243072 -22.987254) (xy 3.2258 -23.054056)
			(xy 3.235706 -23.087584) (xy 3.247501 -23.12993) (xy 3.264281 -23.216225) (xy 3.273149 -23.303687)
			(xy 3.274032 -23.391593) (xy 3.266921 -23.479216) (xy 3.251877 -23.56583) (xy 3.229023 -23.650718)
			(xy 3.198548 -23.733178) (xy 3.160706 -23.812527) (xy 3.115809 -23.888108) (xy 3.064228 -23.959296)
			(xy 3.006391 -24.025502) (xy 2.942777 -24.086177) (xy 2.873911 -24.140819) (xy 2.800364 -24.188977)
			(xy 2.722745 -24.230251) (xy 2.641696 -24.2643) (xy 2.557888 -24.290843) (xy 2.472014 -24.309658)
			(xy 2.384786 -24.320591) (xy 2.296925 -24.323552) (xy 2.209159 -24.318515) (xy 2.122214 -24.305522)
			(xy 2.036809 -24.284681) (xy 1.953652 -24.256165) (xy 1.87343 -24.220209) (xy 1.796809 -24.177111)
			(xy 1.724421 -24.127227) (xy 1.656867 -24.070972) (xy 1.594705 -24.008809) (xy 1.53845 -23.941255)
			(xy 1.488567 -23.868867) (xy 1.445469 -23.792245) (xy 1.409513 -23.712024) (xy 1.380997 -23.628866)
			(xy 1.360157 -23.543462) (xy 1.347165 -23.456516) (xy 1.342128 -23.36875) (xy 0.7874 -23.36875) (xy 0.7874 -24.4856)
			(xy 1.844739 -25.542939) (xy 10.382999 -25.542939) (xy 10.382999 -25.457213) (xy 10.390909 -25.371853)
			(xy 10.406661 -25.287586) (xy 10.430121 -25.205133) (xy 10.461089 -25.125196) (xy 10.4993 -25.048457)
			(xy 10.544429 -24.975571) (xy 10.59609 -24.90716) (xy 10.653844 -24.843808) (xy 10.717196 -24.786054)
			(xy 10.785607 -24.734393) (xy 10.858493 -24.689264) (xy 10.935232 -24.651053) (xy 11.015169 -24.620085)
			(xy 11.097622 -24.596625) (xy 11.181889 -24.580873) (xy 11.267249 -24.572963) (xy 11.352975 -24.572963)
			(xy 11.438335 -24.580873) (xy 11.522602 -24.596625) (xy 11.605055 -24.620085) (xy 11.684992 -24.651053)
			(xy 11.761731 -24.689264) (xy 11.834617 -24.734393) (xy 11.903028 -24.786054) (xy 11.96638 -24.843808)
			(xy 12.024134 -24.90716) (xy 12.075795 -24.975571) (xy 12.120924 -25.048457) (xy 12.159135 -25.125196)
			(xy 12.190103 -25.205133) (xy 12.213563 -25.287586) (xy 12.229315 -25.371853) (xy 12.237225 -25.457213)
			(xy 12.23772 -25.500076) (xy 12.237225 -25.542939) (xy 12.229315 -25.628299) (xy 12.213563 -25.712566)
			(xy 12.190103 -25.795019) (xy 12.159135 -25.874956) (xy 12.120924 -25.951695) (xy 12.075795 -26.024581)
			(xy 12.024134 -26.092992) (xy 11.96638 -26.156344) (xy 11.903028 -26.214098) (xy 11.834617 -26.265759)
			(xy 11.761731 -26.310888) (xy 11.684992 -26.349099) (xy 11.605055 -26.380067) (xy 11.522602 -26.403527)
			(xy 11.438335 -26.419279) (xy 11.352975 -26.427189) (xy 11.267249 -26.427189) (xy 11.181889 -26.419279)
			(xy 11.097622 -26.403527) (xy 11.015169 -26.380067) (xy 10.935232 -26.349099) (xy 10.858493 -26.310888)
			(xy 10.785607 -26.265759) (xy 10.717196 -26.214098) (xy 10.653844 -26.156344) (xy 10.59609 -26.092992)
			(xy 10.544429 -26.024581) (xy 10.4993 -25.951695) (xy 10.461089 -25.874956) (xy 10.430121 -25.795019)
			(xy 10.406661 -25.712566) (xy 10.390909 -25.628299) (xy 10.382999 -25.542939) (xy 1.844739 -25.542939)
			(xy 3.28676 -26.98496) (xy 3.298567 -26.996109) (xy 3.326551 -27.01256) (xy 3.357785 -27.021406)
			(xy 3.39024 -27.02207) (xy 3.42181 -27.014511) (xy 3.436366 -27.007312) (xy 3.495267 -26.976421)
			(xy 3.616096 -26.920802) (xy 3.73999 -26.872391) (xy 3.866518 -26.831356) (xy 3.995242 -26.797839)
			(xy 4.125715 -26.771956) (xy 4.257486 -26.753797) (xy 4.390097 -26.743425) (xy 4.523089 -26.740875)
			(xy 4.656 -26.746158) (xy 4.788369 -26.759254) (xy 4.919739 -26.780117) (xy 5.049653 -26.808677)
			(xy 5.17766 -26.844833) (xy 5.303318 -26.88846) (xy 5.426191 -26.939407) (xy 5.545851 -26.997498)
			(xy 5.661886 -27.062531) (xy 5.773892 -27.13428) (xy 5.88148 -27.212497) (xy 5.984279 -27.296911)
			(xy 6.081931 -27.387229) (xy 6.174099 -27.483137) (xy 6.215838 -27.532031) (xy 19.996675 -27.532031)
			(xy 19.997523 -27.451084) (xy 20.006408 -27.370622) (xy 20.023241 -27.29144) (xy 20.047857 -27.214322)
			(xy 20.080012 -27.14003) (xy 20.119388 -27.069301) (xy 20.165596 -27.002833) (xy 20.218177 -26.941283)
			(xy 20.276613 -26.885262) (xy 20.340325 -26.835322) (xy 20.408682 -26.791959) (xy 20.481009 -26.7556)
			(xy 20.55659 -26.726606) (xy 20.634678 -26.705264) (xy 20.714499 -26.691784) (xy 20.754848 -26.688542)
			(xy 20.771338 -26.686913) (xy 20.802708 -26.676275) (xy 20.830281 -26.65792) (xy 20.8522 -26.633085)
			(xy 20.866986 -26.603444) (xy 20.873642 -26.570995) (xy 20.873212 -26.55443) (xy 20.871759 -26.527209)
			(xy 20.871634 -26.472691) (xy 20.872958 -26.445464) (xy 20.873393 -26.428936) (xy 20.866735 -26.396561)
			(xy 20.851974 -26.366987) (xy 20.830104 -26.342204) (xy 20.802596 -26.32388) (xy 20.771301 -26.313247)
			(xy 20.754848 -26.311606) (xy 20.714505 -26.308352) (xy 20.634695 -26.294869) (xy 20.556618 -26.273526)
			(xy 20.481047 -26.244533) (xy 20.40873 -26.208177) (xy 20.340382 -26.164817) (xy 20.276679 -26.114883)
			(xy 20.21825 -26.058868) (xy 20.165675 -25.997327) (xy 20.119472 -25.930868) (xy 20.080099 -25.860148)
			(xy 20.047946 -25.785867) (xy 20.023329 -25.70876) (xy 20.006494 -25.629589) (xy 19.997605 -25.549137)
			(xy 19.996752 -25.4682) (xy 20.003942 -25.387579) (xy 20.019105 -25.30807) (xy 20.042091 -25.230461)
			(xy 20.072671 -25.155519) (xy 20.110545 -25.083985) (xy 20.155336 -25.016566) (xy 20.206603 -24.95393)
			(xy 20.263837 -24.896696) (xy 20.326474 -24.845431) (xy 20.393893 -24.80064) (xy 20.465427 -24.762767)
			(xy 20.54037 -24.732188) (xy 20.617979 -24.709203) (xy 20.697488 -24.694041) (xy 20.778109 -24.686852)
			(xy 20.859046 -24.687706) (xy 20.939498 -24.696595) (xy 21.018669 -24.713432) (xy 21.095776 -24.738049)
			(xy 21.170057 -24.770203) (xy 21.240776 -24.809577) (xy 21.307235 -24.855781) (xy 21.368775 -24.908357)
			(xy 21.424789 -24.966786) (xy 21.474722 -25.03049) (xy 21.518081 -25.098838) (xy 21.554436 -25.171156)
			(xy 21.583429 -25.246727) (xy 21.604771 -25.324804) (xy 21.618253 -25.404614) (xy 21.621496 -25.444958)
			(xy 21.623181 -25.46144) (xy 21.633814 -25.492801) (xy 21.65216 -25.520368) (xy 21.676984 -25.542286)
			(xy 21.706611 -25.557077) (xy 21.739048 -25.563744) (xy 21.755608 -25.563322) (xy 21.782769 -25.561942)
			(xy 21.837159 -25.561942) (xy 21.86432 -25.563322) (xy 21.880888 -25.563731) (xy 21.913342 -25.557095)
			(xy 21.942991 -25.54232) (xy 21.96783 -25.520403) (xy 21.986183 -25.492826) (xy 21.996809 -25.46145)
			(xy 21.998432 -25.444958) (xy 22.001677 -25.404612) (xy 22.015157 -25.324797) (xy 22.036498 -25.246716)
			(xy 22.06549 -25.171141) (xy 22.101846 -25.098819) (xy 22.145205 -25.030466) (xy 22.19514 -24.966758)
			(xy 22.251156 -24.908325) (xy 22.312699 -24.855745) (xy 22.37916 -24.809539) (xy 22.449882 -24.770162)
			(xy 22.524166 -24.738005) (xy 22.601277 -24.713386) (xy 22.680452 -24.696548) (xy 22.760907 -24.687658)
			(xy 22.841848 -24.686803) (xy 22.922474 -24.693993) (xy 23.001987 -24.709155) (xy 23.0796 -24.732141)
			(xy 23.154546 -24.762722) (xy 23.226084 -24.800597) (xy 23.293506 -24.84539) (xy 23.356146 -24.896659)
			(xy 23.413383 -24.953896) (xy 23.464651 -25.016535) (xy 23.509444 -25.083957) (xy 23.547319 -25.155495)
			(xy 23.5779 -25.230442) (xy 23.600885 -25.308055) (xy 23.616048 -25.387568) (xy 23.623237 -25.468193)
			(xy 23.622382 -25.549134) (xy 23.613492 -25.62959) (xy 23.596654 -25.708765) (xy 23.572034 -25.785875)
			(xy 23.539877 -25.860159) (xy 23.5005 -25.930882) (xy 23.454294 -25.997343) (xy 23.401714 -26.058886)
			(xy 23.343281 -26.114901) (xy 23.279573 -26.164836) (xy 23.21122 -26.208195) (xy 23.138898 -26.24455)
			(xy 23.063322 -26.273542) (xy 22.985241 -26.294884) (xy 22.905426 -26.308364) (xy 22.86508 -26.311606)
			(xy 22.848615 -26.313241) (xy 22.817291 -26.323864) (xy 22.78975 -26.34218) (xy 22.76784 -26.366958)
			(xy 22.753033 -26.396534) (xy 22.75121 -26.405332) (xy 26.792943 -26.405332) (xy 26.796946 -26.31747)
			(xy 26.808922 -26.230336) (xy 26.828773 -26.144652) (xy 26.856332 -26.061128) (xy 26.891373 -25.980456)
			(xy 26.933604 -25.903305) (xy 26.982676 -25.830314) (xy 27.038183 -25.762088) (xy 27.099663 -25.699192)
			(xy 27.166608 -25.642147) (xy 27.238463 -25.591426) (xy 27.314633 -25.547449) (xy 27.394486 -25.510581)
			(xy 27.477361 -25.481128) (xy 27.562571 -25.459332) (xy 27.64941 -25.445376) (xy 27.737158 -25.439373)
			(xy 27.748182 -25.439624) (xy 29.333444 -25.439624) (xy 31.26486 -25.439624) (xy 31.26486 -25.765861)
			(xy 32.181792 -25.765861) (xy 32.181792 -25.694539) (xy 32.189778 -25.623665) (xy 32.205648 -25.55413)
			(xy 32.229205 -25.48681) (xy 32.26015 -25.422551) (xy 32.298096 -25.36216) (xy 32.342565 -25.306398)
			(xy 32.392998 -25.255965) (xy 32.44876 -25.211496) (xy 32.509151 -25.17355) (xy 32.57341 -25.142605)
			(xy 32.64073 -25.119048) (xy 32.710265 -25.103178) (xy 32.781139 -25.095192) (xy 32.852461 -25.095192)
			(xy 32.923335 -25.103178) (xy 32.99287 -25.119048) (xy 33.06019 -25.142605) (xy 33.124449 -25.17355)
			(xy 33.18484 -25.211496) (xy 33.240602 -25.255965) (xy 33.291035 -25.306398) (xy 33.335504 -25.36216)
			(xy 33.37345 -25.422551) (xy 33.404395 -25.48681) (xy 33.427952 -25.55413) (xy 33.443822 -25.623665)
			(xy 33.451808 -25.694539) (xy 33.452308 -25.7302) (xy 33.451808 -25.765861) (xy 33.443822 -25.836735)
			(xy 33.427952 -25.90627) (xy 33.404395 -25.97359) (xy 33.37345 -26.037849) (xy 33.368793 -26.045261)
			(xy 39.547792 -26.045261) (xy 39.547792 -25.973939) (xy 39.555778 -25.903065) (xy 39.571648 -25.83353)
			(xy 39.595205 -25.76621) (xy 39.62615 -25.701951) (xy 39.664096 -25.64156) (xy 39.708565 -25.585798)
			(xy 39.758998 -25.535365) (xy 39.81476 -25.490896) (xy 39.875151 -25.45295) (xy 39.93941 -25.422005)
			(xy 40.00673 -25.398448) (xy 40.076265 -25.382578) (xy 40.147139 -25.374592) (xy 40.218461 -25.374592)
			(xy 40.289335 -25.382578) (xy 40.35887 -25.398448) (xy 40.42619 -25.422005) (xy 40.490449 -25.45295)
			(xy 40.55084 -25.490896) (xy 40.606602 -25.535365) (xy 40.633898 -25.562661) (xy 54.330592 -25.562661)
			(xy 54.330592 -25.491339) (xy 54.338578 -25.420465) (xy 54.354448 -25.35093) (xy 54.378005 -25.28361)
			(xy 54.40895 -25.219351) (xy 54.446896 -25.15896) (xy 54.491365 -25.103198) (xy 54.541798 -25.052765)
			(xy 54.59756 -25.008296) (xy 54.657951 -24.97035) (xy 54.72221 -24.939405) (xy 54.78953 -24.915848)
			(xy 54.859065 -24.899978) (xy 54.929939 -24.891992) (xy 55.001261 -24.891992) (xy 55.072135 -24.899978)
			(xy 55.14167 -24.915848) (xy 55.20899 -24.939405) (xy 55.273249 -24.97035) (xy 55.33364 -25.008296)
			(xy 55.389402 -25.052765) (xy 55.439835 -25.103198) (xy 55.484304 -25.15896) (xy 55.52225 -25.219351)
			(xy 55.553195 -25.28361) (xy 55.576752 -25.35093) (xy 55.592622 -25.420465) (xy 55.597196 -25.461061)
			(xy 63.271392 -25.461061) (xy 63.271392 -25.389739) (xy 63.279378 -25.318865) (xy 63.295248 -25.24933)
			(xy 63.318805 -25.18201) (xy 63.34975 -25.117751) (xy 63.387696 -25.05736) (xy 63.432165 -25.001598)
			(xy 63.482598 -24.951165) (xy 63.53836 -24.906696) (xy 63.598751 -24.86875) (xy 63.66301 -24.837805)
			(xy 63.73033 -24.814248) (xy 63.799865 -24.798378) (xy 63.870739 -24.790392) (xy 63.942061 -24.790392)
			(xy 64.012935 -24.798378) (xy 64.08247 -24.814248) (xy 64.14979 -24.837805) (xy 64.214049 -24.86875)
			(xy 64.27444 -24.906696) (xy 64.330202 -24.951165) (xy 64.380635 -25.001598) (xy 64.425104 -25.05736)
			(xy 64.46305 -25.117751) (xy 64.493995 -25.18201) (xy 64.517552 -25.24933) (xy 64.533422 -25.318865)
			(xy 64.541408 -25.389739) (xy 64.541908 -25.4254) (xy 64.541408 -25.461061) (xy 64.533422 -25.531935)
			(xy 64.517552 -25.60147) (xy 64.49558 -25.664261) (xy 70.942192 -25.664261) (xy 70.942192 -25.592939)
			(xy 70.950178 -25.522065) (xy 70.966048 -25.45253) (xy 70.989605 -25.38521) (xy 71.02055 -25.320951)
			(xy 71.058496 -25.26056) (xy 71.102965 -25.204798) (xy 71.153398 -25.154365) (xy 71.20916 -25.109896)
			(xy 71.269551 -25.07195) (xy 71.33381 -25.041005) (xy 71.40113 -25.017448) (xy 71.470665 -25.001578)
			(xy 71.541539 -24.993592) (xy 71.612861 -24.993592) (xy 71.683735 -25.001578) (xy 71.75327 -25.017448)
			(xy 71.82059 -25.041005) (xy 71.884849 -25.07195) (xy 71.94524 -25.109896) (xy 72.001002 -25.154365)
			(xy 72.051435 -25.204798) (xy 72.095904 -25.26056) (xy 72.13385 -25.320951) (xy 72.164795 -25.38521)
			(xy 72.188352 -25.45253) (xy 72.204222 -25.522065) (xy 72.212208 -25.592939) (xy 72.212708 -25.6286)
			(xy 72.212208 -25.664261) (xy 72.206484 -25.715061) (xy 77.546192 -25.715061) (xy 77.546192 -25.643739)
			(xy 77.554178 -25.572865) (xy 77.570048 -25.50333) (xy 77.593605 -25.43601) (xy 77.62455 -25.371751)
			(xy 77.662496 -25.31136) (xy 77.706965 -25.255598) (xy 77.757398 -25.205165) (xy 77.81316 -25.160696)
			(xy 77.873551 -25.12275) (xy 77.93781 -25.091805) (xy 78.00513 -25.068248) (xy 78.074665 -25.052378)
			(xy 78.145539 -25.044392) (xy 78.216861 -25.044392) (xy 78.287735 -25.052378) (xy 78.35727 -25.068248)
			(xy 78.42459 -25.091805) (xy 78.488849 -25.12275) (xy 78.54924 -25.160696) (xy 78.605002 -25.205165)
			(xy 78.655435 -25.255598) (xy 78.699904 -25.31136) (xy 78.73785 -25.371751) (xy 78.768795 -25.43601)
			(xy 78.792352 -25.50333) (xy 78.808222 -25.572865) (xy 78.816208 -25.643739) (xy 78.816708 -25.6794)
			(xy 78.816208 -25.715061) (xy 78.808222 -25.785935) (xy 78.792352 -25.85547) (xy 78.768795 -25.92279)
			(xy 78.73785 -25.987049) (xy 78.699904 -26.04744) (xy 78.655435 -26.103202) (xy 78.605002 -26.153635)
			(xy 78.569356 -26.182062) (xy 90.185476 -26.182062) (xy 90.185476 -26.122126) (xy 90.193299 -26.062704)
			(xy 90.208812 -26.004811) (xy 90.231748 -25.949438) (xy 90.261715 -25.897532) (xy 90.298202 -25.849982)
			(xy 90.340582 -25.807602) (xy 90.388132 -25.771115) (xy 90.440038 -25.741148) (xy 90.495411 -25.718212)
			(xy 90.553304 -25.702699) (xy 90.612726 -25.694876) (xy 90.672662 -25.694876) (xy 90.732084 -25.702699)
			(xy 90.789977 -25.718212) (xy 90.84535 -25.741148) (xy 90.897256 -25.771115) (xy 90.944806 -25.807602)
			(xy 90.987186 -25.849982) (xy 91.023673 -25.897532) (xy 91.05364 -25.949438) (xy 91.069931 -25.988768)
			(xy 114.350782 -25.988768) (xy 114.350782 -25.928832) (xy 114.358605 -25.86941) (xy 114.374118 -25.811517)
			(xy 114.397054 -25.756144) (xy 114.427021 -25.704238) (xy 114.463508 -25.656688) (xy 114.505888 -25.614308)
			(xy 114.553438 -25.577821) (xy 114.605344 -25.547854) (xy 114.660717 -25.524918) (xy 114.71861 -25.509405)
			(xy 114.778032 -25.501582) (xy 114.837968 -25.501582) (xy 114.89739 -25.509405) (xy 114.955283 -25.524918)
			(xy 115.010656 -25.547854) (xy 115.062562 -25.577821) (xy 115.110112 -25.614308) (xy 115.152492 -25.656688)
			(xy 115.188979 -25.704238) (xy 115.218946 -25.756144) (xy 115.241882 -25.811517) (xy 115.257395 -25.86941)
			(xy 115.265218 -25.928832) (xy 115.265708 -25.9588) (xy 115.265218 -25.988768) (xy 115.257395 -26.04819)
			(xy 115.241882 -26.106083) (xy 115.218946 -26.161456) (xy 115.188979 -26.213362) (xy 115.152492 -26.260912)
			(xy 115.110112 -26.303292) (xy 115.062562 -26.339779) (xy 115.010656 -26.369746) (xy 114.955283 -26.392682)
			(xy 114.89739 -26.408195) (xy 114.837968 -26.416018) (xy 114.778032 -26.416018) (xy 114.71861 -26.408195)
			(xy 114.660717 -26.392682) (xy 114.605344 -26.369746) (xy 114.553438 -26.339779) (xy 114.505888 -26.303292)
			(xy 114.463508 -26.260912) (xy 114.427021 -26.213362) (xy 114.397054 -26.161456) (xy 114.374118 -26.106083)
			(xy 114.358605 -26.04819) (xy 114.350782 -25.988768) (xy 91.069931 -25.988768) (xy 91.076576 -26.004811)
			(xy 91.092089 -26.062704) (xy 91.099912 -26.122126) (xy 91.100402 -26.152094) (xy 91.099912 -26.182062)
			(xy 91.092089 -26.241484) (xy 91.076576 -26.299377) (xy 91.05364 -26.35475) (xy 91.023673 -26.406656)
			(xy 90.987186 -26.454206) (xy 90.944806 -26.496586) (xy 90.897256 -26.533073) (xy 90.84535 -26.56304)
			(xy 90.789977 -26.585976) (xy 90.732084 -26.601489) (xy 90.672662 -26.609312) (xy 90.612726 -26.609312)
			(xy 90.553304 -26.601489) (xy 90.495411 -26.585976) (xy 90.440038 -26.56304) (xy 90.388132 -26.533073)
			(xy 90.340582 -26.496586) (xy 90.298202 -26.454206) (xy 90.261715 -26.406656) (xy 90.231748 -26.35475)
			(xy 90.208812 -26.299377) (xy 90.193299 -26.241484) (xy 90.185476 -26.182062) (xy 78.569356 -26.182062)
			(xy 78.54924 -26.198104) (xy 78.488849 -26.23605) (xy 78.42459 -26.266995) (xy 78.35727 -26.290552)
			(xy 78.287735 -26.306422) (xy 78.216861 -26.314408) (xy 78.145539 -26.314408) (xy 78.074665 -26.306422)
			(xy 78.00513 -26.290552) (xy 77.93781 -26.266995) (xy 77.873551 -26.23605) (xy 77.81316 -26.198104)
			(xy 77.757398 -26.153635) (xy 77.706965 -26.103202) (xy 77.662496 -26.04744) (xy 77.62455 -25.987049)
			(xy 77.593605 -25.92279) (xy 77.570048 -25.85547) (xy 77.554178 -25.785935) (xy 77.546192 -25.715061)
			(xy 72.206484 -25.715061) (xy 72.204222 -25.735135) (xy 72.188352 -25.80467) (xy 72.164795 -25.87199)
			(xy 72.13385 -25.936249) (xy 72.095904 -25.99664) (xy 72.051435 -26.052402) (xy 72.001002 -26.102835)
			(xy 71.94524 -26.147304) (xy 71.884849 -26.18525) (xy 71.82059 -26.216195) (xy 71.75327 -26.239752)
			(xy 71.683735 -26.255622) (xy 71.612861 -26.263608) (xy 71.541539 -26.263608) (xy 71.470665 -26.255622)
			(xy 71.40113 -26.239752) (xy 71.33381 -26.216195) (xy 71.269551 -26.18525) (xy 71.20916 -26.147304)
			(xy 71.153398 -26.102835) (xy 71.102965 -26.052402) (xy 71.058496 -25.99664) (xy 71.02055 -25.936249)
			(xy 70.989605 -25.87199) (xy 70.966048 -25.80467) (xy 70.950178 -25.735135) (xy 70.942192 -25.664261)
			(xy 64.49558 -25.664261) (xy 64.493995 -25.66879) (xy 64.46305 -25.733049) (xy 64.425104 -25.79344)
			(xy 64.380635 -25.849202) (xy 64.330202 -25.899635) (xy 64.27444 -25.944104) (xy 64.214049 -25.98205)
			(xy 64.14979 -26.012995) (xy 64.08247 -26.036552) (xy 64.012935 -26.052422) (xy 63.942061 -26.060408)
			(xy 63.870739 -26.060408) (xy 63.799865 -26.052422) (xy 63.73033 -26.036552) (xy 63.66301 -26.012995)
			(xy 63.598751 -25.98205) (xy 63.53836 -25.944104) (xy 63.482598 -25.899635) (xy 63.432165 -25.849202)
			(xy 63.387696 -25.79344) (xy 63.34975 -25.733049) (xy 63.318805 -25.66879) (xy 63.295248 -25.60147)
			(xy 63.279378 -25.531935) (xy 63.271392 -25.461061) (xy 55.597196 -25.461061) (xy 55.600608 -25.491339)
			(xy 55.601108 -25.527) (xy 55.600608 -25.562661) (xy 55.592622 -25.633535) (xy 55.576752 -25.70307)
			(xy 55.553195 -25.77039) (xy 55.52225 -25.834649) (xy 55.484304 -25.89504) (xy 55.439835 -25.950802)
			(xy 55.389402 -26.001235) (xy 55.33364 -26.045704) (xy 55.273249 -26.08365) (xy 55.20899 -26.114595)
			(xy 55.14167 -26.138152) (xy 55.072135 -26.154022) (xy 55.001261 -26.162008) (xy 54.929939 -26.162008)
			(xy 54.859065 -26.154022) (xy 54.78953 -26.138152) (xy 54.72221 -26.114595) (xy 54.657951 -26.08365)
			(xy 54.59756 -26.045704) (xy 54.541798 -26.001235) (xy 54.491365 -25.950802) (xy 54.446896 -25.89504)
			(xy 54.40895 -25.834649) (xy 54.378005 -25.77039) (xy 54.354448 -25.70307) (xy 54.338578 -25.633535)
			(xy 54.330592 -25.562661) (xy 40.633898 -25.562661) (xy 40.657035 -25.585798) (xy 40.701504 -25.64156)
			(xy 40.73945 -25.701951) (xy 40.770395 -25.76621) (xy 40.793952 -25.83353) (xy 40.809822 -25.903065)
			(xy 40.817808 -25.973939) (xy 40.818308 -26.0096) (xy 40.817808 -26.045261) (xy 40.809822 -26.116135)
			(xy 40.793952 -26.18567) (xy 40.770395 -26.25299) (xy 40.73945 -26.317249) (xy 40.701504 -26.37764)
			(xy 40.657035 -26.433402) (xy 40.606602 -26.483835) (xy 40.55084 -26.528304) (xy 40.490449 -26.56625)
			(xy 40.42619 -26.597195) (xy 40.35887 -26.620752) (xy 40.289335 -26.636622) (xy 40.218461 -26.644608)
			(xy 40.147139 -26.644608) (xy 40.076265 -26.636622) (xy 40.00673 -26.620752) (xy 39.93941 -26.597195)
			(xy 39.875151 -26.56625) (xy 39.81476 -26.528304) (xy 39.758998 -26.483835) (xy 39.708565 -26.433402)
			(xy 39.664096 -26.37764) (xy 39.62615 -26.317249) (xy 39.595205 -26.25299) (xy 39.571648 -26.18567)
			(xy 39.555778 -26.116135) (xy 39.547792 -26.045261) (xy 33.368793 -26.045261) (xy 33.335504 -26.09824)
			(xy 33.291035 -26.154002) (xy 33.240602 -26.204435) (xy 33.18484 -26.248904) (xy 33.124449 -26.28685)
			(xy 33.06019 -26.317795) (xy 32.99287 -26.341352) (xy 32.923335 -26.357222) (xy 32.852461 -26.365208)
			(xy 32.781139 -26.365208) (xy 32.710265 -26.357222) (xy 32.64073 -26.341352) (xy 32.57341 -26.317795)
			(xy 32.509151 -26.28685) (xy 32.44876 -26.248904) (xy 32.392998 -26.204435) (xy 32.342565 -26.154002)
			(xy 32.298096 -26.09824) (xy 32.26015 -26.037849) (xy 32.229205 -25.97359) (xy 32.205648 -25.90627)
			(xy 32.189778 -25.836735) (xy 32.181792 -25.765861) (xy 31.26486 -25.765861) (xy 31.26486 -27.37104)
			(xy 29.333444 -27.37104) (xy 29.333444 -25.439624) (xy 27.748182 -25.439624) (xy 27.825088 -25.441375)
			(xy 27.912473 -25.451365) (xy 27.998586 -25.46926) (xy 28.082716 -25.494911) (xy 28.164164 -25.528106)
			(xy 28.242257 -25.56857) (xy 28.316346 -25.615968) (xy 28.385818 -25.669907) (xy 28.450097 -25.72994)
			(xy 28.508651 -25.795569) (xy 28.560995 -25.866251) (xy 28.606694 -25.9414) (xy 28.64537 -26.020393)
			(xy 28.676702 -26.102576) (xy 28.700432 -26.187268) (xy 28.716362 -26.273767) (xy 28.72436 -26.361355)
			(xy 28.72486 -26.405332) (xy 28.72436 -26.449309) (xy 28.716362 -26.536897) (xy 28.700432 -26.623396)
			(xy 28.676702 -26.708088) (xy 28.64537 -26.790271) (xy 28.606694 -26.869264) (xy 28.560995 -26.944413)
			(xy 28.508651 -27.015095) (xy 28.450097 -27.080724) (xy 28.385818 -27.140757) (xy 28.316346 -27.194696)
			(xy 28.242257 -27.242094) (xy 28.164164 -27.282558) (xy 28.082716 -27.315753) (xy 27.998586 -27.341404)
			(xy 27.912473 -27.359299) (xy 27.825088 -27.369289) (xy 27.737158 -27.371291) (xy 27.64941 -27.365288)
			(xy 27.562571 -27.351332) (xy 27.477361 -27.329536) (xy 27.394486 -27.300083) (xy 27.314633 -27.263215)
			(xy 27.238463 -27.219238) (xy 27.166608 -27.168517) (xy 27.099663 -27.111472) (xy 27.038183 -27.048576)
			(xy 26.982676 -26.98035) (xy 26.933604 -26.907359) (xy 26.891373 -26.830208) (xy 26.856332 -26.749536)
			(xy 26.828773 -26.666012) (xy 26.808922 -26.580328) (xy 26.796946 -26.493194) (xy 26.792943 -26.405332)
			(xy 22.75121 -26.405332) (xy 22.746323 -26.428922) (xy 22.746716 -26.445464) (xy 22.74824 -26.500074)
			(xy 22.747727 -26.545195) (xy 22.739125 -26.635025) (xy 22.72193 -26.723613) (xy 22.709632 -26.767028)
			(xy 22.458172 -26.767028) (xy 22.399498 -26.80081) (xy 22.38248 -26.830528) (xy 22.364155 -26.861233)
			(xy 22.321887 -26.91891) (xy 22.273644 -26.971692) (xy 22.21999 -27.018963) (xy 22.161551 -27.060171)
			(xy 22.130512 -27.077924) (xy 22.115946 -27.086618) (xy 22.091669 -27.110292) (xy 22.07446 -27.13951)
			(xy 22.065525 -27.172222) (xy 22.06498 -27.189176) (xy 22.06498 -27.403044) (xy 22.027257 -27.413294)
			(xy 21.95052 -27.428226) (xy 21.872805 -27.436711) (xy 21.794654 -27.438692) (xy 21.755608 -27.436826)
			(xy 21.739059 -27.43638) (xy 21.706633 -27.442994) (xy 21.677004 -27.457734) (xy 21.652169 -27.479605)
			(xy 21.633802 -27.507134) (xy 21.623143 -27.538463) (xy 21.621496 -27.554936) (xy 21.618264 -27.595286)
			(xy 21.604807 -27.675111) (xy 21.583488 -27.753204) (xy 21.554516 -27.828794) (xy 21.518178 -27.901132)
			(xy 21.474834 -27.969502) (xy 21.454571 -27.995368) (xy 33.197782 -27.995368) (xy 33.197782 -27.935432)
			(xy 33.205605 -27.87601) (xy 33.221118 -27.818117) (xy 33.244054 -27.762744) (xy 33.274021 -27.710838)
			(xy 33.310508 -27.663288) (xy 33.352888 -27.620908) (xy 33.400438 -27.584421) (xy 33.452344 -27.554454)
			(xy 33.507717 -27.531518) (xy 33.56561 -27.516005) (xy 33.625032 -27.508182) (xy 33.684968 -27.508182)
			(xy 33.74439 -27.516005) (xy 33.802283 -27.531518) (xy 33.857656 -27.554454) (xy 33.909562 -27.584421)
			(xy 33.93568 -27.604462) (xy 90.373182 -27.604462) (xy 90.373182 -27.544526) (xy 90.381005 -27.485104)
			(xy 90.396518 -27.427211) (xy 90.419454 -27.371838) (xy 90.449421 -27.319932) (xy 90.485908 -27.272382)
			(xy 90.528288 -27.230002) (xy 90.575838 -27.193515) (xy 90.627744 -27.163548) (xy 90.683117 -27.140612)
			(xy 90.74101 -27.125099) (xy 90.800432 -27.117276) (xy 90.860368 -27.117276) (xy 90.91979 -27.125099)
			(xy 90.977683 -27.140612) (xy 91.033056 -27.163548) (xy 91.084962 -27.193515) (xy 91.132512 -27.230002)
			(xy 91.174892 -27.272382) (xy 91.211379 -27.319932) (xy 91.241346 -27.371838) (xy 91.264282 -27.427211)
			(xy 91.279795 -27.485104) (xy 91.287618 -27.544526) (xy 91.288108 -27.574494) (xy 91.287618 -27.604462)
			(xy 91.279795 -27.663884) (xy 91.264282 -27.721777) (xy 91.241346 -27.77715) (xy 91.211379 -27.829056)
			(xy 91.174892 -27.876606) (xy 91.132512 -27.918986) (xy 91.084962 -27.955473) (xy 91.033056 -27.98544)
			(xy 90.977683 -28.008376) (xy 90.91979 -28.023889) (xy 90.860368 -28.031712) (xy 90.800432 -28.031712)
			(xy 90.74101 -28.023889) (xy 90.683117 -28.008376) (xy 90.627744 -27.98544) (xy 90.575838 -27.955473)
			(xy 90.528288 -27.918986) (xy 90.485908 -27.876606) (xy 90.449421 -27.829056) (xy 90.419454 -27.77715)
			(xy 90.396518 -27.721777) (xy 90.381005 -27.663884) (xy 90.373182 -27.604462) (xy 33.93568 -27.604462)
			(xy 33.957112 -27.620908) (xy 33.999492 -27.663288) (xy 34.035979 -27.710838) (xy 34.065946 -27.762744)
			(xy 34.088882 -27.818117) (xy 34.104395 -27.87601) (xy 34.112218 -27.935432) (xy 34.112708 -27.9654)
			(xy 34.112218 -27.995368) (xy 34.104395 -28.05479) (xy 34.088882 -28.112683) (xy 34.065946 -28.168056)
			(xy 34.035979 -28.219962) (xy 33.999492 -28.267512) (xy 33.957112 -28.309892) (xy 33.909562 -28.346379)
			(xy 33.857656 -28.376346) (xy 33.802283 -28.399282) (xy 33.74439 -28.414795) (xy 33.684968 -28.422618)
			(xy 33.625032 -28.422618) (xy 33.56561 -28.414795) (xy 33.507717 -28.399282) (xy 33.452344 -28.376346)
			(xy 33.400438 -28.346379) (xy 33.352888 -28.309892) (xy 33.310508 -28.267512) (xy 33.274021 -28.219962)
			(xy 33.244054 -28.168056) (xy 33.221118 -28.112683) (xy 33.205605 -28.05479) (xy 33.197782 -27.995368)
			(xy 21.454571 -27.995368) (xy 21.424913 -28.033228) (xy 21.368909 -28.09168) (xy 21.307375 -28.144279)
			(xy 21.24092 -28.190506) (xy 21.170202 -28.229903) (xy 21.09592 -28.262079) (xy 21.018809 -28.286718)
			(xy 20.939632 -28.303575) (xy 20.859172 -28.312483) (xy 20.778226 -28.313354) (xy 20.697593 -28.30618)
			(xy 20.618071 -28.291031) (xy 20.540448 -28.268058) (xy 20.465491 -28.237488) (xy 20.393941 -28.199623)
			(xy 20.326506 -28.154837) (xy 20.263855 -28.103574) (xy 20.206605 -28.046341) (xy 20.155324 -27.983704)
			(xy 20.110519 -27.916283) (xy 20.072632 -27.844744) (xy 20.04204 -27.769796) (xy 20.019045 -27.692179)
			(xy 20.003873 -27.612662) (xy 19.996675 -27.532031) (xy 6.215838 -27.532031) (xy 6.260462 -27.584304)
			(xy 6.340721 -27.690378) (xy 6.414597 -27.800992) (xy 6.481836 -27.915762) (xy 6.542203 -28.034291)
			(xy 6.595489 -28.156167) (xy 6.64151 -28.280968) (xy 6.680106 -28.408262) (xy 6.711143 -28.537606)
			(xy 6.712094 -28.542933) (xy 10.382999 -28.542933) (xy 10.382999 -28.457207) (xy 10.390909 -28.371847)
			(xy 10.406661 -28.28758) (xy 10.430121 -28.205127) (xy 10.461089 -28.12519) (xy 10.4993 -28.048451)
			(xy 10.544429 -27.975565) (xy 10.59609 -27.907154) (xy 10.653844 -27.843802) (xy 10.717196 -27.786048)
			(xy 10.785607 -27.734387) (xy 10.858493 -27.689258) (xy 10.935232 -27.651047) (xy 11.015169 -27.620079)
			(xy 11.097622 -27.596619) (xy 11.181889 -27.580867) (xy 11.267249 -27.572957) (xy 11.352975 -27.572957)
			(xy 11.438335 -27.580867) (xy 11.522602 -27.596619) (xy 11.605055 -27.620079) (xy 11.684992 -27.651047)
			(xy 11.761731 -27.689258) (xy 11.834617 -27.734387) (xy 11.903028 -27.786048) (xy 11.96638 -27.843802)
			(xy 12.024134 -27.907154) (xy 12.075795 -27.975565) (xy 12.120924 -28.048451) (xy 12.159135 -28.12519)
			(xy 12.190103 -28.205127) (xy 12.213563 -28.28758) (xy 12.229315 -28.371847) (xy 12.237225 -28.457207)
			(xy 12.23772 -28.50007) (xy 12.237225 -28.542933) (xy 12.229315 -28.628293) (xy 12.213563 -28.71256)
			(xy 12.190103 -28.795013) (xy 12.159135 -28.87495) (xy 12.120924 -28.951689) (xy 12.075795 -29.024575)
			(xy 12.024134 -29.092986) (xy 11.96638 -29.156338) (xy 11.903028 -29.214092) (xy 11.834617 -29.265753)
			(xy 11.761731 -29.310882) (xy 11.684992 -29.349093) (xy 11.605055 -29.380061) (xy 11.522602 -29.403521)
			(xy 11.473562 -29.412688) (xy 25.600642 -29.412688) (xy 25.600642 -29.352752) (xy 25.608465 -29.29333)
			(xy 25.623978 -29.235437) (xy 25.646914 -29.180064) (xy 25.676881 -29.128158) (xy 25.713368 -29.080608)
			(xy 25.755748 -29.038228) (xy 25.803298 -29.001741) (xy 25.855204 -28.971774) (xy 25.910577 -28.948838)
			(xy 25.96847 -28.933325) (xy 26.027892 -28.925502) (xy 26.087828 -28.925502) (xy 26.14725 -28.933325)
			(xy 26.205143 -28.948838) (xy 26.260516 -28.971774) (xy 26.312422 -29.001741) (xy 26.359972 -29.038228)
			(xy 26.402352 -29.080608) (xy 26.429132 -29.115508) (xy 32.207182 -29.115508) (xy 32.207182 -29.055572)
			(xy 32.215005 -28.99615) (xy 32.230518 -28.938257) (xy 32.253454 -28.882884) (xy 32.283421 -28.830978)
			(xy 32.319908 -28.783428) (xy 32.362288 -28.741048) (xy 32.409838 -28.704561) (xy 32.461744 -28.674594)
			(xy 32.517117 -28.651658) (xy 32.57501 -28.636145) (xy 32.634432 -28.628322) (xy 32.694368 -28.628322)
			(xy 32.75379 -28.636145) (xy 32.811683 -28.651658) (xy 32.867056 -28.674594) (xy 32.918962 -28.704561)
			(xy 32.966512 -28.741048) (xy 33.008892 -28.783428) (xy 33.045379 -28.830978) (xy 33.075346 -28.882884)
			(xy 33.098282 -28.938257) (xy 33.113795 -28.99615) (xy 33.121618 -29.055572) (xy 33.122108 -29.08554)
			(xy 33.121618 -29.115508) (xy 33.116702 -29.152846) (xy 90.423982 -29.152846) (xy 90.423982 -29.09291)
			(xy 90.431805 -29.033488) (xy 90.447318 -28.975595) (xy 90.470254 -28.920222) (xy 90.500221 -28.868316)
			(xy 90.536708 -28.820766) (xy 90.579088 -28.778386) (xy 90.626638 -28.741899) (xy 90.678544 -28.711932)
			(xy 90.733917 -28.688996) (xy 90.79181 -28.673483) (xy 90.851232 -28.66566) (xy 90.911168 -28.66566)
			(xy 90.97059 -28.673483) (xy 91.028483 -28.688996) (xy 91.083856 -28.711932) (xy 91.135762 -28.741899)
			(xy 91.183312 -28.778386) (xy 91.225692 -28.820766) (xy 91.262179 -28.868316) (xy 91.292146 -28.920222)
			(xy 91.315082 -28.975595) (xy 91.330595 -29.033488) (xy 91.338418 -29.09291) (xy 91.338908 -29.122878)
			(xy 91.338418 -29.152846) (xy 91.330595 -29.212268) (xy 91.315082 -29.270161) (xy 91.292146 -29.325534)
			(xy 91.262179 -29.37744) (xy 91.225692 -29.42499) (xy 91.183312 -29.46737) (xy 91.135762 -29.503857)
			(xy 91.083856 -29.533824) (xy 91.028483 -29.55676) (xy 90.97059 -29.572273) (xy 90.911168 -29.580096)
			(xy 90.851232 -29.580096) (xy 90.79181 -29.572273) (xy 90.733917 -29.55676) (xy 90.678544 -29.533824)
			(xy 90.626638 -29.503857) (xy 90.579088 -29.46737) (xy 90.536708 -29.42499) (xy 90.500221 -29.37744)
			(xy 90.470254 -29.325534) (xy 90.447318 -29.270161) (xy 90.431805 -29.212268) (xy 90.423982 -29.152846)
			(xy 33.116702 -29.152846) (xy 33.113795 -29.17493) (xy 33.098282 -29.232823) (xy 33.075346 -29.288196)
			(xy 33.045379 -29.340102) (xy 33.008892 -29.387652) (xy 32.966512 -29.430032) (xy 32.918962 -29.466519)
			(xy 32.867056 -29.496486) (xy 32.811683 -29.519422) (xy 32.75379 -29.534935) (xy 32.694368 -29.542758)
			(xy 32.634432 -29.542758) (xy 32.57501 -29.534935) (xy 32.517117 -29.519422) (xy 32.461744 -29.496486)
			(xy 32.409838 -29.466519) (xy 32.362288 -29.430032) (xy 32.319908 -29.387652) (xy 32.283421 -29.340102)
			(xy 32.253454 -29.288196) (xy 32.230518 -29.232823) (xy 32.215005 -29.17493) (xy 32.207182 -29.115508)
			(xy 26.429132 -29.115508) (xy 26.438839 -29.128158) (xy 26.468806 -29.180064) (xy 26.491742 -29.235437)
			(xy 26.507255 -29.29333) (xy 26.515078 -29.352752) (xy 26.515568 -29.38272) (xy 26.515078 -29.412688)
			(xy 26.507255 -29.47211) (xy 26.491742 -29.530003) (xy 26.468806 -29.585376) (xy 26.438839 -29.637282)
			(xy 26.402352 -29.684832) (xy 26.359972 -29.727212) (xy 26.312422 -29.763699) (xy 26.260516 -29.793666)
			(xy 26.205143 -29.816602) (xy 26.14725 -29.832115) (xy 26.087828 -29.839938) (xy 26.027892 -29.839938)
			(xy 25.96847 -29.832115) (xy 25.910577 -29.816602) (xy 25.855204 -29.793666) (xy 25.803298 -29.763699)
			(xy 25.755748 -29.727212) (xy 25.713368 -29.684832) (xy 25.676881 -29.637282) (xy 25.646914 -29.585376)
			(xy 25.623978 -29.530003) (xy 25.608465 -29.47211) (xy 25.600642 -29.412688) (xy 11.473562 -29.412688)
			(xy 11.438335 -29.419273) (xy 11.352975 -29.427183) (xy 11.267249 -29.427183) (xy 11.181889 -29.419273)
			(xy 11.097622 -29.403521) (xy 11.015169 -29.380061) (xy 10.935232 -29.349093) (xy 10.858493 -29.310882)
			(xy 10.785607 -29.265753) (xy 10.717196 -29.214092) (xy 10.653844 -29.156338) (xy 10.59609 -29.092986)
			(xy 10.544429 -29.024575) (xy 10.4993 -28.951689) (xy 10.461089 -28.87495) (xy 10.430121 -28.795013)
			(xy 10.406661 -28.71256) (xy 10.390909 -28.628293) (xy 10.382999 -28.542933) (xy 6.712094 -28.542933)
			(xy 6.734514 -28.668553) (xy 6.750137 -28.800648) (xy 6.757958 -28.933434) (xy 6.758432 -28.999942)
			(xy 6.758432 -30.456886) (xy 7.844553 -31.542927) (xy 10.382999 -31.542927) (xy 10.382999 -31.457201)
			(xy 10.390909 -31.371841) (xy 10.406661 -31.287574) (xy 10.430121 -31.205121) (xy 10.461089 -31.125184)
			(xy 10.4993 -31.048445) (xy 10.544429 -30.975559) (xy 10.59609 -30.907148) (xy 10.653844 -30.843796)
			(xy 10.717196 -30.786042) (xy 10.785607 -30.734381) (xy 10.858493 -30.689252) (xy 10.935232 -30.651041)
			(xy 11.015169 -30.620073) (xy 11.097622 -30.596613) (xy 11.181889 -30.580861) (xy 11.267249 -30.572951)
			(xy 11.352975 -30.572951) (xy 11.438335 -30.580861) (xy 11.522602 -30.596613) (xy 11.605055 -30.620073)
			(xy 11.684992 -30.651041) (xy 11.761731 -30.689252) (xy 11.834617 -30.734381) (xy 11.903028 -30.786042)
			(xy 11.96638 -30.843796) (xy 12.024134 -30.907148) (xy 12.075795 -30.975559) (xy 12.120924 -31.048445)
			(xy 12.159135 -31.125184) (xy 12.190103 -31.205121) (xy 12.213563 -31.287574) (xy 12.229315 -31.371841)
			(xy 12.237225 -31.457201) (xy 12.23772 -31.500064) (xy 12.237225 -31.542927) (xy 12.229315 -31.628287)
			(xy 12.213563 -31.712554) (xy 12.190103 -31.795007) (xy 12.159135 -31.874944) (xy 12.120924 -31.951683)
			(xy 12.075795 -32.024569) (xy 12.024134 -32.09298) (xy 11.96638 -32.156332) (xy 11.903028 -32.214086)
			(xy 11.834617 -32.265747) (xy 11.761731 -32.310876) (xy 11.684992 -32.349087) (xy 11.605055 -32.380055)
			(xy 11.522602 -32.403515) (xy 11.438335 -32.419267) (xy 11.352975 -32.427177) (xy 11.267249 -32.427177)
			(xy 11.181889 -32.419267) (xy 11.097622 -32.403515) (xy 11.015169 -32.380055) (xy 10.935232 -32.349087)
			(xy 10.858493 -32.310876) (xy 10.785607 -32.265747) (xy 10.717196 -32.214086) (xy 10.653844 -32.156332)
			(xy 10.59609 -32.09298) (xy 10.544429 -32.024569) (xy 10.4993 -31.951683) (xy 10.461089 -31.874944)
			(xy 10.430121 -31.795007) (xy 10.406661 -31.712554) (xy 10.390909 -31.628287) (xy 10.382999 -31.542927)
			(xy 7.844553 -31.542927) (xy 10.223754 -33.921954) (xy 10.24072 -33.93815) (xy 10.279409 -33.964658)
			(xy 10.322302 -33.983622) (xy 10.367946 -33.994399) (xy 10.414792 -33.996624) (xy 10.461251 -33.990221)
			(xy 10.505749 -33.975408) (xy 10.546776 -33.952686) (xy 10.582941 -33.922827) (xy 10.598404 -33.90519)
			(xy 10.626572 -33.872268) (xy 10.688098 -33.811254) (xy 10.755045 -33.756245) (xy 10.826832 -33.707719)
			(xy 10.902832 -33.6661) (xy 10.982381 -33.63175) (xy 11.064788 -33.60497) (xy 11.149334 -33.585991)
			(xy 11.23528 -33.574981) (xy 11.32188 -33.572035) (xy 11.408376 -33.577179) (xy 11.494016 -33.590367)
			(xy 11.578052 -33.611485) (xy 11.659752 -33.640349) (xy 11.738405 -33.676706) (xy 11.813323 -33.720241)
			(xy 11.883855 -33.770574) (xy 11.949385 -33.827265) (xy 12.009342 -33.889821) (xy 12.063203 -33.957696)
			(xy 12.110499 -34.030299) (xy 12.150817 -34.106997) (xy 12.183807 -34.18712) (xy 12.20918 -34.269971)
			(xy 12.226715 -34.354828) (xy 12.236259 -34.44095) (xy 12.237729 -34.527587) (xy 12.231113 -34.613983)
			(xy 12.216468 -34.699385) (xy 12.205716 -34.741358) (xy 12.196826 -34.774378) (xy 12.214352 -34.83991)
			(xy 12.840208 -35.465512) (xy 17.147794 -35.465512) (xy 17.173956 -35.452812) (xy 17.200836 -35.440298)
			(xy 17.257082 -35.421535) (xy 17.315281 -35.410195) (xy 17.374457 -35.406468) (xy 17.433618 -35.410416)
			(xy 17.491774 -35.421974) (xy 17.547949 -35.440948) (xy 17.601203 -35.467019) (xy 17.650643 -35.499751)
			(xy 17.67332 -35.518852) (xy 17.691677 -35.534048) (xy 17.732871 -35.557995) (xy 17.777808 -35.573843)
			(xy 17.824911 -35.581035) (xy 17.872529 -35.57932) (xy 17.918993 -35.568757) (xy 17.962672 -35.549717)
			(xy 18.002036 -35.522868) (xy 18.019268 -35.506406) (xy 22.276308 -31.249112) (xy 23.708106 -31.249112)
			(xy 24.190706 -30.766512) (xy 27.775154 -30.766512) (xy 28.204414 -31.195772) (xy 28.71851 -31.195772)
			(xy 28.741345 -31.195297) (xy 28.786282 -31.187148) (xy 28.829037 -31.171097) (xy 28.868235 -31.14766)
			(xy 28.90261 -31.117592) (xy 28.931056 -31.081864) (xy 28.952656 -31.041625) (xy 28.966715 -30.998173)
			(xy 28.972778 -30.952908) (xy 28.970651 -30.907288) (xy 28.960402 -30.862783) (xy 28.942361 -30.820828)
			(xy 28.930092 -30.801564) (xy 28.913961 -30.776357) (xy 28.887669 -30.722596) (xy 28.868607 -30.665867)
			(xy 28.8571 -30.607138) (xy 28.853345 -30.547411) (xy 28.857405 -30.487703) (xy 28.869211 -30.429034)
			(xy 28.888563 -30.372403) (xy 28.915129 -30.318777) (xy 28.948456 -30.26907) (xy 28.987977 -30.224131)
			(xy 29.033018 -30.184724) (xy 29.082809 -30.151523) (xy 29.136503 -30.125094) (xy 29.193183 -30.105888)
			(xy 29.251882 -30.094231) (xy 29.3116 -30.090323) (xy 29.371318 -30.094231) (xy 29.430017 -30.105888)
			(xy 29.486697 -30.125094) (xy 29.540391 -30.151523) (xy 29.590182 -30.184724) (xy 29.635223 -30.224131)
			(xy 29.674744 -30.26907) (xy 29.708071 -30.318777) (xy 29.734637 -30.372403) (xy 29.753989 -30.429034)
			(xy 29.765795 -30.487703) (xy 29.769855 -30.547411) (xy 29.7661 -30.607138) (xy 29.754593 -30.665867)
			(xy 29.735531 -30.722596) (xy 29.709239 -30.776357) (xy 29.693108 -30.801564) (xy 29.680908 -30.820861)
			(xy 29.662909 -30.862811) (xy 29.652693 -30.907302) (xy 29.651781 -30.927036) (xy 88.620582 -30.927036)
			(xy 88.620582 -30.8671) (xy 88.628405 -30.807678) (xy 88.643918 -30.749785) (xy 88.666854 -30.694412)
			(xy 88.696821 -30.642506) (xy 88.733308 -30.594956) (xy 88.775688 -30.552576) (xy 88.823238 -30.516089)
			(xy 88.875144 -30.486122) (xy 88.930517 -30.463186) (xy 88.98841 -30.447673) (xy 89.047832 -30.43985)
			(xy 89.107768 -30.43985) (xy 89.16719 -30.447673) (xy 89.225083 -30.463186) (xy 89.280456 -30.486122)
			(xy 89.332362 -30.516089) (xy 89.379912 -30.552576) (xy 89.422292 -30.594956) (xy 89.458779 -30.642506)
			(xy 89.488746 -30.694412) (xy 89.511682 -30.749785) (xy 89.527195 -30.807678) (xy 89.535018 -30.8671)
			(xy 89.535508 -30.897068) (xy 89.535018 -30.927036) (xy 89.527195 -30.986458) (xy 89.511682 -31.044351)
			(xy 89.488746 -31.099724) (xy 89.458779 -31.15163) (xy 89.422292 -31.19918) (xy 89.379912 -31.24156)
			(xy 89.332362 -31.278047) (xy 89.280456 -31.308014) (xy 89.225083 -31.33095) (xy 89.16719 -31.346463)
			(xy 89.107768 -31.354286) (xy 89.047832 -31.354286) (xy 88.98841 -31.346463) (xy 88.930517 -31.33095)
			(xy 88.875144 -31.308014) (xy 88.823238 -31.278047) (xy 88.775688 -31.24156) (xy 88.733308 -31.19918)
			(xy 88.696821 -31.15163) (xy 88.666854 -31.099724) (xy 88.643918 -31.044351) (xy 88.628405 -30.986458)
			(xy 88.620582 -30.927036) (xy 29.651781 -30.927036) (xy 29.650586 -30.952903) (xy 29.656659 -30.998146)
			(xy 29.670714 -31.041578) (xy 29.6923 -31.0818) (xy 29.720724 -31.117521) (xy 29.75507 -31.14759)
			(xy 29.794234 -31.171042) (xy 29.836958 -31.187121) (xy 29.881866 -31.195311) (xy 29.90469 -31.195772)
			(xy 30.203394 -31.195772) (xy 30.229556 -31.183072) (xy 30.257182 -31.170234) (xy 30.315038 -31.151163)
			(xy 30.374912 -31.139938) (xy 30.435747 -31.136757) (xy 30.496466 -31.141676) (xy 30.555996 -31.154608)
			(xy 30.613283 -31.175324) (xy 30.667314 -31.203459) (xy 30.717135 -31.238514) (xy 30.761864 -31.27987)
			(xy 30.80071 -31.326795) (xy 30.832986 -31.37846) (xy 30.858122 -31.43395) (xy 30.875672 -31.492285)
			(xy 30.885327 -31.552433) (xy 30.886654 -31.582868) (xy 30.887607 -31.599212) (xy 30.896797 -31.630624)
			(xy 30.913678 -31.658662) (xy 30.93714 -31.681481) (xy 30.965635 -31.697579) (xy 30.99729 -31.705894)
			(xy 31.013654 -31.706312) (xy 31.524194 -31.706312) (xy 31.550356 -31.693612) (xy 31.578125 -31.680723)
			(xy 31.636284 -31.661607) (xy 31.696473 -31.650412) (xy 31.757616 -31.647339) (xy 31.818623 -31.652442)
			(xy 31.878407 -31.665631) (xy 31.935899 -31.686669) (xy 31.990074 -31.715182) (xy 32.039965 -31.750661)
			(xy 32.084683 -31.792473) (xy 32.095224 -31.805368) (xy 87.401382 -31.805368) (xy 87.401382 -31.745432)
			(xy 87.409205 -31.68601) (xy 87.424718 -31.628117) (xy 87.447654 -31.572744) (xy 87.477621 -31.520838)
			(xy 87.514108 -31.473288) (xy 87.556488 -31.430908) (xy 87.604038 -31.394421) (xy 87.655944 -31.364454)
			(xy 87.711317 -31.341518) (xy 87.76921 -31.326005) (xy 87.828632 -31.318182) (xy 87.888568 -31.318182)
			(xy 87.94799 -31.326005) (xy 88.005883 -31.341518) (xy 88.061256 -31.364454) (xy 88.113162 -31.394421)
			(xy 88.160712 -31.430908) (xy 88.203092 -31.473288) (xy 88.22052 -31.496) (xy 92.886782 -31.496)
			(xy 92.890853 -31.440378) (xy 92.902979 -31.385941) (xy 92.922902 -31.33385) (xy 92.950198 -31.285215)
			(xy 92.984284 -31.241072) (xy 93.024433 -31.202363) (xy 93.069791 -31.169912) (xy 93.119391 -31.144411)
			(xy 93.172175 -31.126404) (xy 93.227018 -31.116274) (xy 93.282752 -31.114237) (xy 93.338189 -31.120337)
			(xy 93.392146 -31.134443) (xy 93.443475 -31.156255) (xy 93.491081 -31.185309) (xy 93.533949 -31.220984)
			(xy 93.571166 -31.262521) (xy 93.601939 -31.309034) (xy 93.625611 -31.359531) (xy 93.641679 -31.412938)
			(xy 93.649799 -31.468114) (xy 93.650308 -31.496) (xy 93.649799 -31.523886) (xy 93.641679 -31.579062)
			(xy 93.625611 -31.632469) (xy 93.601939 -31.682966) (xy 93.571166 -31.729479) (xy 93.533949 -31.771016)
			(xy 93.491081 -31.806691) (xy 93.443475 -31.835745) (xy 93.392146 -31.857557) (xy 93.338189 -31.871663)
			(xy 93.282752 -31.877763) (xy 93.227018 -31.875726) (xy 93.172175 -31.865596) (xy 93.119391 -31.847589)
			(xy 93.069791 -31.822088) (xy 93.024433 -31.789637) (xy 92.984284 -31.750928) (xy 92.950198 -31.706785)
			(xy 92.922902 -31.65815) (xy 92.902979 -31.606059) (xy 92.890853 -31.551622) (xy 92.886782 -31.496)
			(xy 88.22052 -31.496) (xy 88.239579 -31.520838) (xy 88.269546 -31.572744) (xy 88.292482 -31.628117)
			(xy 88.307995 -31.68601) (xy 88.315818 -31.745432) (xy 88.316308 -31.7754) (xy 88.315818 -31.805368)
			(xy 88.307995 -31.86479) (xy 88.292482 -31.922683) (xy 88.269546 -31.978056) (xy 88.239579 -32.029962)
			(xy 88.203092 -32.077512) (xy 88.160712 -32.119892) (xy 88.113162 -32.156379) (xy 88.061256 -32.186346)
			(xy 88.005883 -32.209282) (xy 87.94799 -32.224795) (xy 87.888568 -32.232618) (xy 87.828632 -32.232618)
			(xy 87.76921 -32.224795) (xy 87.711317 -32.209282) (xy 87.655944 -32.186346) (xy 87.604038 -32.156379)
			(xy 87.556488 -32.119892) (xy 87.514108 -32.077512) (xy 87.477621 -32.029962) (xy 87.447654 -31.978056)
			(xy 87.424718 -31.922683) (xy 87.409205 -31.86479) (xy 87.401382 -31.805368) (xy 32.095224 -31.805368)
			(xy 32.12343 -31.839872) (xy 32.155514 -31.892012) (xy 32.180363 -31.947963) (xy 32.197533 -32.006726)
			(xy 32.206718 -32.067254) (xy 32.207754 -32.128466) (xy 32.200623 -32.189269) (xy 32.185451 -32.24858)
			(xy 32.162511 -32.30534) (xy 32.147764 -32.332168) (xy 32.131 -32.361378) (xy 32.131 -35.391852)
			(xy 32.131471 -35.413849) (xy 32.139054 -35.457185) (xy 32.153985 -35.498568) (xy 32.175817 -35.536763)
			(xy 32.203898 -35.570629) (xy 32.237391 -35.599155) (xy 32.275295 -35.621488) (xy 32.316478 -35.636963)
			(xy 32.35971 -35.645116) (xy 32.4037 -35.645705) (xy 32.447135 -35.638712) (xy 32.488718 -35.624345)
			(xy 32.50819 -35.614102) (xy 32.53963 -35.597188) (xy 32.605534 -35.569729) (xy 32.674101 -35.54983)
			(xy 32.744465 -35.537741) (xy 32.815741 -35.533615) (xy 32.887031 -35.537504) (xy 32.957435 -35.549358)
			(xy 33.026068 -35.569029) (xy 33.090589 -35.595661) (xy 75.641192 -35.595661) (xy 75.641192 -35.524339)
			(xy 75.649178 -35.453465) (xy 75.665048 -35.38393) (xy 75.688605 -35.31661) (xy 75.71955 -35.252351)
			(xy 75.757496 -35.19196) (xy 75.801965 -35.136198) (xy 75.852398 -35.085765) (xy 75.90816 -35.041296)
			(xy 75.968551 -35.00335) (xy 76.03281 -34.972405) (xy 76.10013 -34.948848) (xy 76.169665 -34.932978)
			(xy 76.240539 -34.924992) (xy 76.311861 -34.924992) (xy 76.382735 -34.932978) (xy 76.45227 -34.948848)
			(xy 76.51959 -34.972405) (xy 76.583849 -35.00335) (xy 76.584868 -35.00399) (xy 87.656906 -35.00399)
			(xy 87.656906 -34.944054) (xy 87.664729 -34.884632) (xy 87.680242 -34.826739) (xy 87.703178 -34.771366)
			(xy 87.733145 -34.71946) (xy 87.769632 -34.67191) (xy 87.812012 -34.62953) (xy 87.859562 -34.593043)
			(xy 87.911468 -34.563076) (xy 87.966841 -34.54014) (xy 88.024734 -34.524627) (xy 88.084156 -34.516804)
			(xy 88.144092 -34.516804) (xy 88.203514 -34.524627) (xy 88.261407 -34.54014) (xy 88.31678 -34.563076)
			(xy 88.368686 -34.593043) (xy 88.416236 -34.62953) (xy 88.458616 -34.67191) (xy 88.495103 -34.71946)
			(xy 88.52507 -34.771366) (xy 88.548006 -34.826739) (xy 88.563519 -34.884632) (xy 88.571342 -34.944054)
			(xy 88.571832 -34.974022) (xy 88.571342 -35.00399) (xy 88.563519 -35.063412) (xy 88.548006 -35.121305)
			(xy 88.52507 -35.176678) (xy 88.495103 -35.228584) (xy 88.458616 -35.276134) (xy 88.416236 -35.318514)
			(xy 88.368686 -35.355001) (xy 88.31678 -35.384968) (xy 88.261407 -35.407904) (xy 88.203514 -35.423417)
			(xy 88.144092 -35.43124) (xy 88.084156 -35.43124) (xy 88.024734 -35.423417) (xy 87.966841 -35.407904)
			(xy 87.911468 -35.384968) (xy 87.859562 -35.355001) (xy 87.812012 -35.318514) (xy 87.769632 -35.276134)
			(xy 87.733145 -35.228584) (xy 87.703178 -35.176678) (xy 87.680242 -35.121305) (xy 87.664729 -35.063412)
			(xy 87.656906 -35.00399) (xy 76.584868 -35.00399) (xy 76.64424 -35.041296) (xy 76.700002 -35.085765)
			(xy 76.750435 -35.136198) (xy 76.794904 -35.19196) (xy 76.83285 -35.252351) (xy 76.863795 -35.31661)
			(xy 76.887352 -35.38393) (xy 76.903222 -35.453465) (xy 76.911208 -35.524339) (xy 76.911708 -35.56)
			(xy 76.911208 -35.595661) (xy 76.903222 -35.666535) (xy 76.887352 -35.73607) (xy 76.863795 -35.80339)
			(xy 76.83285 -35.867649) (xy 76.794904 -35.92804) (xy 76.750435 -35.983802) (xy 76.700002 -36.034235)
			(xy 76.64424 -36.078704) (xy 76.583849 -36.11665) (xy 76.51959 -36.147595) (xy 76.45227 -36.171152)
			(xy 76.382735 -36.187022) (xy 76.311861 -36.195008) (xy 76.240539 -36.195008) (xy 76.169665 -36.187022)
			(xy 76.10013 -36.171152) (xy 76.03281 -36.147595) (xy 75.968551 -36.11665) (xy 75.90816 -36.078704)
			(xy 75.852398 -36.034235) (xy 75.801965 -35.983802) (xy 75.757496 -35.92804) (xy 75.71955 -35.867649)
			(xy 75.688605 -35.80339) (xy 75.665048 -35.73607) (xy 75.649178 -35.666535) (xy 75.641192 -35.595661)
			(xy 33.090589 -35.595661) (xy 33.092062 -35.596269) (xy 33.154588 -35.630734) (xy 33.212858 -35.671989)
			(xy 33.266135 -35.719516) (xy 33.313751 -35.772715) (xy 33.355103 -35.830915) (xy 33.389672 -35.893384)
			(xy 33.417022 -35.959333) (xy 33.436807 -36.027932) (xy 33.448778 -36.098317) (xy 33.452786 -36.1696)
			(xy 33.448778 -36.240883) (xy 33.436807 -36.311268) (xy 33.417022 -36.379867) (xy 33.389672 -36.445816)
			(xy 33.355103 -36.508285) (xy 33.313751 -36.566485) (xy 33.266135 -36.619684) (xy 33.212858 -36.667211)
			(xy 33.154588 -36.708466) (xy 33.092062 -36.742931) (xy 33.026068 -36.770171) (xy 32.957435 -36.789842)
			(xy 32.887031 -36.801696) (xy 32.815741 -36.805585) (xy 32.744465 -36.801459) (xy 32.674101 -36.78937)
			(xy 32.605534 -36.769471) (xy 32.53963 -36.742012) (xy 32.50819 -36.725098) (xy 32.488722 -36.714835)
			(xy 32.447138 -36.70044) (xy 32.403696 -36.693424) (xy 32.359694 -36.693998) (xy 32.31645 -36.702144)
			(xy 32.275255 -36.717618) (xy 32.237343 -36.739959) (xy 32.203846 -36.768497) (xy 32.175767 -36.802379)
			(xy 32.153945 -36.840592) (xy 32.139033 -36.881994) (xy 32.133025 -36.916461) (xy 67.360792 -36.916461)
			(xy 67.360792 -36.845139) (xy 67.368778 -36.774265) (xy 67.384648 -36.70473) (xy 67.408205 -36.63741)
			(xy 67.43915 -36.573151) (xy 67.477096 -36.51276) (xy 67.521565 -36.456998) (xy 67.571998 -36.406565)
			(xy 67.62776 -36.362096) (xy 67.688151 -36.32415) (xy 67.75241 -36.293205) (xy 67.81973 -36.269648)
			(xy 67.889265 -36.253778) (xy 67.960139 -36.245792) (xy 68.031461 -36.245792) (xy 68.102335 -36.253778)
			(xy 68.17187 -36.269648) (xy 68.23919 -36.293205) (xy 68.303449 -36.32415) (xy 68.36384 -36.362096)
			(xy 68.419602 -36.406565) (xy 68.470035 -36.456998) (xy 68.514504 -36.51276) (xy 68.533171 -36.542468)
			(xy 87.769682 -36.542468) (xy 87.769682 -36.482532) (xy 87.777505 -36.42311) (xy 87.793018 -36.365217)
			(xy 87.815954 -36.309844) (xy 87.845921 -36.257938) (xy 87.882408 -36.210388) (xy 87.924788 -36.168008)
			(xy 87.972338 -36.131521) (xy 88.024244 -36.101554) (xy 88.079617 -36.078618) (xy 88.13751 -36.063105)
			(xy 88.196932 -36.055282) (xy 88.256868 -36.055282) (xy 88.31629 -36.063105) (xy 88.374183 -36.078618)
			(xy 88.429556 -36.101554) (xy 88.481462 -36.131521) (xy 88.529012 -36.168008) (xy 88.571392 -36.210388)
			(xy 88.607879 -36.257938) (xy 88.637846 -36.309844) (xy 88.660782 -36.365217) (xy 88.676295 -36.42311)
			(xy 88.684118 -36.482532) (xy 88.684608 -36.5125) (xy 88.684118 -36.542468) (xy 88.676295 -36.60189)
			(xy 88.660782 -36.659783) (xy 88.637846 -36.715156) (xy 88.607879 -36.767062) (xy 88.571392 -36.814612)
			(xy 88.529012 -36.856992) (xy 88.481462 -36.893479) (xy 88.429556 -36.923446) (xy 88.374183 -36.946382)
			(xy 88.31629 -36.961895) (xy 88.256868 -36.969718) (xy 88.196932 -36.969718) (xy 88.13751 -36.961895)
			(xy 88.079617 -36.946382) (xy 88.024244 -36.923446) (xy 87.972338 -36.893479) (xy 87.924788 -36.856992)
			(xy 87.882408 -36.814612) (xy 87.845921 -36.767062) (xy 87.815954 -36.715156) (xy 87.793018 -36.659783)
			(xy 87.777505 -36.60189) (xy 87.769682 -36.542468) (xy 68.533171 -36.542468) (xy 68.55245 -36.573151)
			(xy 68.583395 -36.63741) (xy 68.606952 -36.70473) (xy 68.622822 -36.774265) (xy 68.630808 -36.845139)
			(xy 68.631308 -36.8808) (xy 68.630808 -36.916461) (xy 68.622822 -36.987335) (xy 68.606952 -37.05687)
			(xy 68.583395 -37.12419) (xy 68.55245 -37.188449) (xy 68.514504 -37.24884) (xy 68.470035 -37.304602)
			(xy 68.419602 -37.355035) (xy 68.36384 -37.399504) (xy 68.303449 -37.43745) (xy 68.23919 -37.468395)
			(xy 68.17187 -37.491952) (xy 68.102335 -37.507822) (xy 68.031461 -37.515808) (xy 67.960139 -37.515808)
			(xy 67.889265 -37.507822) (xy 67.81973 -37.491952) (xy 67.75241 -37.468395) (xy 67.688151 -37.43745)
			(xy 67.62776 -37.399504) (xy 67.571998 -37.355035) (xy 67.521565 -37.304602) (xy 67.477096 -37.24884)
			(xy 67.43915 -37.188449) (xy 67.408205 -37.12419) (xy 67.384648 -37.05687) (xy 67.368778 -36.987335)
			(xy 67.360792 -36.916461) (xy 32.133025 -36.916461) (xy 32.131477 -36.925345) (xy 32.131 -36.947348)
			(xy 32.131 -37.265102) (xy 32.193738 -37.33673) (xy 32.240982 -37.34308) (xy 32.275804 -37.348234)
			(xy 32.344113 -37.365255) (xy 32.410122 -37.38972) (xy 32.473023 -37.42133) (xy 32.532046 -37.459697)
			(xy 32.586468 -37.504351) (xy 32.635622 -37.554746) (xy 32.678906 -37.610264) (xy 32.71579 -37.670225)
			(xy 32.745822 -37.733894) (xy 32.768634 -37.800493) (xy 32.783948 -37.869204) (xy 32.791574 -37.939187)
			(xy 32.791421 -38.009583) (xy 32.783489 -38.079532) (xy 32.767876 -38.148176) (xy 32.744773 -38.214674)
			(xy 32.714464 -38.278212) (xy 32.677319 -38.338012) (xy 32.633793 -38.39334) (xy 32.58442 -38.44352)
			(xy 32.529803 -38.487937) (xy 32.470614 -38.526046) (xy 32.407575 -38.557381) (xy 32.34146 -38.581558)
			(xy 32.273078 -38.598281) (xy 32.203267 -38.607345) (xy 32.168084 -38.608508) (xy 32.11703 -38.60927)
			(xy 31.4071 -39.3192) (xy 31.4071 -51.2953) (xy 31.7246 -51.6128)
		)
		(stroke
			(width 0)
			(type solid)
		)
		(fill yes)
		(layer "B.Cu")
		(net "GND")
	)
	(gr_line
		(start 0 -51.799998)
		(end 0 -1.999996)
		(stroke
			(width 1.016)
			(type default)
		)
		(layer "In1.Cu")
	)
	(gr_poly
		(pts
			(xy 94.713298 -51.81092) (xy 94.744102 -51.808459) (xy 94.804792 -51.796812) (xy 94.863545 -51.777656)
			(xy 94.919437 -51.751294) (xy 94.971588 -51.71814) (xy 95.019176 -51.678716) (xy 95.061453 -51.633644)
			(xy 95.097754 -51.583632) (xy 95.127505 -51.529468) (xy 95.15024 -51.472004) (xy 95.1656 -51.412147)
			(xy 95.173343 -51.350837) (xy 95.1738 -51.319938) (xy 95.1738 -50.8) (xy 95.174281 -50.746159) (xy 95.181963 -50.638751)
			(xy 95.197287 -50.532165) (xy 95.220177 -50.426943) (xy 95.250514 -50.323623) (xy 95.288146 -50.22273)
			(xy 95.332878 -50.124779) (xy 95.384485 -50.030268) (xy 95.442702 -49.93968) (xy 95.507234 -49.853476)
			(xy 95.577751 -49.772095) (xy 95.653894 -49.695952) (xy 95.735274 -49.625435) (xy 95.821478 -49.560903)
			(xy 95.912066 -49.502686) (xy 96.006577 -49.451079) (xy 96.104528 -49.406346) (xy 96.205421 -49.368715)
			(xy 96.308741 -49.338377) (xy 96.413963 -49.315488) (xy 96.520549 -49.300163) (xy 96.627957 -49.292481)
			(xy 96.681798 -49.292002) (xy 97.01911 -49.292002) (xy 97.06991 -49.290986) (xy 112.06988 -49.290986)
			(xy 112.123758 -49.291455) (xy 112.23124 -49.299141) (xy 112.3379 -49.314475) (xy 112.443194 -49.337379)
			(xy 112.546586 -49.367737) (xy 112.647549 -49.405393) (xy 112.745568 -49.450155) (xy 112.840144 -49.501797)
			(xy 112.930795 -49.560053) (xy 113.017059 -49.624629) (xy 113.098497 -49.695194) (xy 113.174693 -49.771389)
			(xy 113.245259 -49.852825) (xy 113.309835 -49.939088) (xy 113.368093 -50.029738) (xy 113.419736 -50.124314)
			(xy 113.4645 -50.222332) (xy 113.502157 -50.323295) (xy 113.532516 -50.426686) (xy 113.555421 -50.53198)
			(xy 113.570757 -50.63864) (xy 113.578444 -50.746122) (xy 113.578894 -50.8) (xy 113.578894 -51.319938)
			(xy 113.579422 -51.352083) (xy 113.587818 -51.415823) (xy 113.604461 -51.477922) (xy 113.629066 -51.537317)
			(xy 113.661213 -51.592993) (xy 113.700352 -51.643997) (xy 113.745813 -51.689457) (xy 113.796818 -51.728594)
			(xy 113.852495 -51.76074) (xy 113.911891 -51.785344) (xy 113.973991 -51.801985) (xy 114.037731 -51.810379)
			(xy 114.069876 -51.81092) (xy 132.990082 -51.81092) (xy 133.02223 -51.810396) (xy 133.085976 -51.802006)
			(xy 133.148082 -51.785368) (xy 133.207484 -51.760766) (xy 133.263168 -51.728621) (xy 133.314179 -51.689483)
			(xy 133.359646 -51.644021) (xy 133.398789 -51.593014) (xy 133.430941 -51.537335) (xy 133.45555 -51.477935)
			(xy 133.472195 -51.415831) (xy 133.480592 -51.352086) (xy 133.481064 -51.319938) (xy 133.481064 -50.8)
			(xy 133.481545 -50.746122) (xy 133.489232 -50.638641) (xy 133.504567 -50.531983) (xy 133.527472 -50.42669)
			(xy 133.55783 -50.323299) (xy 133.595486 -50.222338) (xy 133.640249 -50.12432) (xy 133.69189 -50.029745)
			(xy 133.750147 -49.939095) (xy 133.814721 -49.852832) (xy 133.885286 -49.771396) (xy 133.96148 -49.695201)
			(xy 134.042915 -49.624635) (xy 134.129177 -49.560059) (xy 134.219826 -49.501801) (xy 134.3144 -49.450159)
			(xy 134.412418 -49.405394) (xy 134.513379 -49.367737) (xy 134.616769 -49.337377) (xy 134.722061 -49.314471)
			(xy 134.82872 -49.299134) (xy 134.9362 -49.291446) (xy 134.990078 -49.290986) (xy 149.990048 -49.290986)
			(xy 150.043924 -49.291468) (xy 150.151402 -49.299159) (xy 150.258058 -49.314497) (xy 150.363347 -49.337404)
			(xy 150.466734 -49.367764) (xy 150.567692 -49.405422) (xy 150.665706 -49.450187) (xy 150.760277 -49.501829)
			(xy 150.850923 -49.560086) (xy 150.937183 -49.624662) (xy 151.018615 -49.695226) (xy 151.094807 -49.77142)
			(xy 151.165369 -49.852855) (xy 151.229941 -49.939116) (xy 151.288196 -50.029764) (xy 151.339835 -50.124337)
			(xy 151.384596 -50.222352) (xy 151.422251 -50.323311) (xy 151.452608 -50.426699) (xy 151.475512 -50.53199)
			(xy 151.490846 -50.638646) (xy 151.498533 -50.746124) (xy 151.499062 -50.8) (xy 151.499062 -51.319938)
			(xy 151.499567 -51.352083) (xy 151.507964 -51.415823) (xy 151.524608 -51.477921) (xy 151.549216 -51.537315)
			(xy 151.581365 -51.592989) (xy 151.620507 -51.643991) (xy 151.665971 -51.689447) (xy 151.716979 -51.72858)
			(xy 151.772659 -51.76072) (xy 151.832057 -51.785318) (xy 151.894158 -51.801952) (xy 151.957899 -51.810338)
			(xy 151.990044 -51.81092) (xy 158.939992 -51.81092) (xy 159.173926 -51.764438) (xy 159.330136 -51.660044)
			(xy 159.4358 -51.501802) (xy 159.485076 -51.26609) (xy 159.596582 -50.787554) (xy 159.92475 -50.30724)
			(xy 160.414462 -49.984152) (xy 160.940496 -49.881028) (xy 203.039472 -49.881028) (xy 203.565506 -49.984152)
			(xy 204.055218 -50.30724) (xy 204.383386 -50.787554) (xy 204.494892 -51.26609) (xy 204.544168 -51.501802)
			(xy 204.649832 -51.660044) (xy 204.806042 -51.764438) (xy 205.039976 -51.81092) (xy 316.06998 -51.81092)
			(xy 316.102128 -51.810396) (xy 316.165874 -51.802006) (xy 316.22798 -51.785368) (xy 316.287383 -51.760766)
			(xy 316.343067 -51.728621) (xy 316.394078 -51.689483) (xy 316.439545 -51.644022) (xy 316.478689 -51.593015)
			(xy 316.510841 -51.537335) (xy 316.53545 -51.477935) (xy 316.552095 -51.415831) (xy 316.560492 -51.352086)
			(xy 316.560962 -51.319938) (xy 316.560962 -50.8) (xy 316.561443 -50.746122) (xy 316.56913 -50.638641)
			(xy 316.584465 -50.531983) (xy 316.60737 -50.42669) (xy 316.637728 -50.323299) (xy 316.675384 -50.222338)
			(xy 316.720147 -50.12432) (xy 316.771788 -50.029745) (xy 316.830044 -49.939095) (xy 316.894619 -49.852832)
			(xy 316.965184 -49.771395) (xy 317.041377 -49.6952) (xy 317.122813 -49.624634) (xy 317.209075 -49.560058)
			(xy 317.299724 -49.5018) (xy 317.394298 -49.450158) (xy 317.492315 -49.405393) (xy 317.593276 -49.367735)
			(xy 317.696667 -49.337376) (xy 317.801959 -49.314469) (xy 317.908618 -49.299132) (xy 318.016098 -49.291444)
			(xy 318.069976 -49.290986) (xy 333.069946 -49.290986) (xy 333.123822 -49.291468) (xy 333.2313 -49.299159)
			(xy 333.337956 -49.314496) (xy 333.443245 -49.337404) (xy 333.546633 -49.367764) (xy 333.647591 -49.405422)
			(xy 333.745605 -49.450186) (xy 333.840176 -49.501828) (xy 333.930822 -49.560086) (xy 334.017082 -49.624661)
			(xy 334.098515 -49.695225) (xy 334.174706 -49.771419) (xy 334.245268 -49.852854) (xy 334.309841 -49.939115)
			(xy 334.368095 -50.029763) (xy 334.419735 -50.124336) (xy 334.464496 -50.222352) (xy 334.502151 -50.323311)
			(xy 334.532508 -50.426699) (xy 334.555412 -50.531989) (xy 334.570746 -50.638645) (xy 334.578433 -50.746124)
			(xy 334.57896 -50.8) (xy 334.57896 -51.319938) (xy 334.579465 -51.352083) (xy 334.587862 -51.415823)
			(xy 334.604506 -51.477921) (xy 334.629114 -51.537315) (xy 334.661263 -51.59299) (xy 334.700405 -51.643992)
			(xy 334.745869 -51.689448) (xy 334.796877 -51.728581) (xy 334.852556 -51.760722) (xy 334.911955 -51.785319)
			(xy 334.974056 -51.801954) (xy 335.037797 -51.81034) (xy 335.069942 -51.81092) (xy 353.989894 -51.81092)
			(xy 354.022041 -51.810395) (xy 354.085786 -51.802004) (xy 354.147891 -51.785365) (xy 354.207292 -51.760762)
			(xy 354.262974 -51.728616) (xy 354.313984 -51.689478) (xy 354.359449 -51.644017) (xy 354.398592 -51.593011)
			(xy 354.430742 -51.537331) (xy 354.455351 -51.477932) (xy 354.471995 -51.415829) (xy 354.480392 -51.352085)
			(xy 354.480876 -51.319938) (xy 354.480876 -50.8) (xy 354.481357 -50.746122) (xy 354.489044 -50.638642)
			(xy 354.504379 -50.531984) (xy 354.527284 -50.426691) (xy 354.557642 -50.323301) (xy 354.595298 -50.22234)
			(xy 354.640061 -50.124322) (xy 354.691702 -50.029748) (xy 354.749959 -49.939098) (xy 354.814534 -49.852836)
			(xy 354.885098 -49.7714) (xy 354.961292 -49.695205) (xy 355.042728 -49.62464) (xy 355.12899 -49.560065)
			(xy 355.219639 -49.501808) (xy 355.314213 -49.450166) (xy 355.412231 -49.405402) (xy 355.513191 -49.367745)
			(xy 355.616581 -49.337386) (xy 355.721874 -49.314481) (xy 355.828532 -49.299145) (xy 355.936012 -49.291457)
			(xy 355.98989 -49.290986) (xy 370.990114 -49.290986) (xy 371.043991 -49.291467) (xy 371.151471 -49.299155)
			(xy 371.258128 -49.314491) (xy 371.363419 -49.337397) (xy 371.466808 -49.367756) (xy 371.567768 -49.405412)
			(xy 371.665785 -49.450176) (xy 371.760358 -49.501818) (xy 371.851006 -49.560074) (xy 371.937268 -49.624649)
			(xy 372.018702 -49.695214) (xy 372.094896 -49.771408) (xy 372.165459 -49.852843) (xy 372.230034 -49.939105)
			(xy 372.28829 -50.029754) (xy 372.33993 -50.124328) (xy 372.384693 -50.222345) (xy 372.422349 -50.323305)
			(xy 372.452707 -50.426694) (xy 372.475611 -50.531986) (xy 372.490946 -50.638643) (xy 372.498633 -50.746123)
			(xy 372.499128 -50.8) (xy 372.499128 -51.319938) (xy 372.499656 -51.352082) (xy 372.508052 -51.41582)
			(xy 372.524696 -51.477918) (xy 372.549302 -51.537311) (xy 372.581449 -51.592985) (xy 372.620588 -51.643986)
			(xy 372.66605 -51.689443) (xy 372.717055 -51.728577) (xy 372.772732 -51.76072) (xy 372.832128 -51.78532)
			(xy 372.894227 -51.801957) (xy 372.957966 -51.810347) (xy 372.99011 -51.81092) (xy 379.940058 -51.81092)
			(xy 380.173992 -51.764438) (xy 380.330202 -51.660044) (xy 380.435866 -51.501802) (xy 380.485142 -51.26609)
			(xy 380.596648 -50.787554) (xy 380.924816 -50.30724) (xy 381.414528 -49.984152) (xy 381.940562 -49.881028)
			(xy 425.61002 -49.881028) (xy 425.665789 -49.880506) (xy 425.777016 -49.872169) (xy 425.887308 -49.855544)
			(xy 425.99605 -49.830724) (xy 426.102633 -49.797847) (xy 426.206461 -49.757097) (xy 426.306953 -49.708702)
			(xy 426.403549 -49.652933) (xy 426.495706 -49.590102) (xy 426.582911 -49.520559) (xy 426.664675 -49.444695)
			(xy 426.740541 -49.362932) (xy 426.810085 -49.275729) (xy 426.872918 -49.183572) (xy 426.928689 -49.086978)
			(xy 426.977086 -48.986486) (xy 427.017838 -48.882659) (xy 427.050717 -48.776077) (xy 427.075539 -48.667336)
			(xy 427.092166 -48.557043) (xy 427.100505 -48.445817) (xy 427.101 -48.390048) (xy 427.101 -42.13606)
			(xy 427.100452 -42.119415) (xy 427.091827 -42.087262) (xy 427.075176 -42.058435) (xy 427.051633 -42.034899)
			(xy 427.022801 -42.018257) (xy 426.990645 -42.009643) (xy 426.974 -42.00906) (xy 425.509944 -42.00906)
			(xy 425.465908 -42.008595) (xy 425.37817 -42.000921) (xy 425.291435 -41.985628) (xy 425.206363 -41.962832)
			(xy 425.123602 -41.932707) (xy 425.043783 -41.895482) (xy 424.967512 -41.851441) (xy 424.895371 -41.800918)
			(xy 424.827909 -41.7443) (xy 424.76564 -41.682015) (xy 424.709037 -41.61454) (xy 424.658531 -41.542387)
			(xy 424.614508 -41.466106) (xy 424.577302 -41.386278) (xy 424.547196 -41.30351) (xy 424.52442 -41.218433)
			(xy 424.509148 -41.131694) (xy 424.501495 -41.043955) (xy 424.501056 -40.999918) (xy 424.501056 -31.999936)
			(xy 424.501521 -31.955907) (xy 424.509193 -31.868184) (xy 424.524482 -31.781464) (xy 424.547271 -31.696406)
			(xy 424.577387 -31.613658) (xy 424.614601 -31.53385) (xy 424.658629 -31.457589) (xy 424.709137 -31.385456)
			(xy 424.765739 -31.318) (xy 424.828006 -31.255734) (xy 424.895462 -31.199132) (xy 424.967596 -31.148625)
			(xy 425.043857 -31.104597) (xy 425.123665 -31.067384) (xy 425.206413 -31.037269) (xy 425.291471 -31.01448)
			(xy 425.378192 -30.999192) (xy 425.465915 -30.991521) (xy 425.509944 -30.991048) (xy 426.974 -30.991048)
			(xy 426.990651 -30.990505) (xy 427.022818 -30.981888) (xy 427.05166 -30.965241) (xy 427.075212 -30.941698)
			(xy 427.091869 -30.912862) (xy 427.100499 -30.880698) (xy 427.101 -30.864048) (xy 427.101 -10.999978)
			(xy 427.101481 -10.95595) (xy 427.109157 -10.86823) (xy 427.12445 -10.781513) (xy 427.147241 -10.696459)
			(xy 427.177359 -10.613714) (xy 427.214574 -10.53391) (xy 427.258602 -10.457652) (xy 427.309109 -10.385522)
			(xy 427.365711 -10.318068) (xy 427.427975 -10.255804) (xy 427.49543 -10.199203) (xy 427.56756 -10.148697)
			(xy 427.643819 -10.104669) (xy 427.723624 -10.067455) (xy 427.806368 -10.037338) (xy 427.891423 -10.014547)
			(xy 427.97814 -9.999256) (xy 428.06586 -9.991581) (xy 428.109888 -9.99109) (xy 428.173896 -9.99109)
			(xy 428.190551 -9.990596) (xy 428.222725 -9.981975) (xy 428.251572 -9.96532) (xy 428.275124 -9.941767)
			(xy 428.291778 -9.912919) (xy 428.300397 -9.880745) (xy 428.300896 -9.86409) (xy 428.300896 -1.999996)
			(xy 428.300374 -1.944227) (xy 428.292039 -1.833) (xy 428.275415 -1.722708) (xy 428.250595 -1.613966)
			(xy 428.217719 -1.507383) (xy 428.176969 -1.403555) (xy 428.128575 -1.303063) (xy 428.072806 -1.206468)
			(xy 428.009974 -1.11431) (xy 427.940431 -1.027106) (xy 427.864566 -0.945342) (xy 427.782803 -0.869476)
			(xy 427.6956 -0.799933) (xy 427.603443 -0.737101) (xy 427.506848 -0.681331) (xy 427.406356 -0.632936)
			(xy 427.302528 -0.592185) (xy 427.195945 -0.559308) (xy 427.087204 -0.534487) (xy 426.976911 -0.517862)
			(xy 426.865685 -0.509526) (xy 426.809916 -0.509016) (xy 1.999996 -0.509016) (xy 1.944227 -0.509538)
			(xy 1.833001 -0.517873) (xy 1.722709 -0.534497) (xy 1.613967 -0.559317) (xy 1.507385 -0.592194) (xy 1.403557 -0.632943)
			(xy 1.303065 -0.681338) (xy 1.20647 -0.737107) (xy 1.114313 -0.799938) (xy 1.027109 -0.869481) (xy 0.945346 -0.945346)
			(xy 0.869481 -1.027109) (xy 0.799938 -1.114313) (xy 0.737107 -1.20647) (xy 0.681338 -1.303065) (xy 0.632943 -1.403557)
			(xy 0.592194 -1.507385) (xy 0.559317 -1.613967) (xy 0.534497 -1.722709) (xy 0.517873 -1.833001) (xy 0.509538 -1.944227)
			(xy 0.509016 -1.999996) (xy 0.509016 -4.700016) (xy 2.187458 -4.700016) (xy 2.191444 -4.564291) (xy 2.203388 -4.429035)
			(xy 2.22325 -4.294712) (xy 2.250961 -4.161787) (xy 2.286425 -4.030717) (xy 2.32952 -3.901954) (xy 2.380098 -3.775942)
			(xy 2.437983 -3.653116) (xy 2.502978 -3.533899) (xy 2.574857 -3.418701) (xy 2.653372 -3.307921) (xy 2.738254 -3.201939)
			(xy 2.829209 -3.101122) (xy 2.925925 -3.005816) (xy 3.028066 -2.91635) (xy 3.135283 -2.833034) (xy 3.247204 -2.756153)
			(xy 3.363444 -2.685972) (xy 3.483603 -2.622735) (xy 3.607266 -2.566659) (xy 3.734006 -2.517936) (xy 3.863388 -2.476736)
			(xy 3.994964 -2.4432) (xy 4.128282 -2.417444) (xy 4.262882 -2.399556) (xy 4.398299 -2.389598) (xy 4.534067 -2.387605)
			(xy 4.669719 -2.393583) (xy 4.804786 -2.407512) (xy 4.938802 -2.429343) (xy 5.071306 -2.459002) (xy 5.201842 -2.496387)
			(xy 5.329958 -2.541367) (xy 5.455213 -2.593789) (xy 5.577177 -2.653472) (xy 5.695427 -2.720209) (xy 5.809557 -2.793771)
			(xy 5.919173 -2.873905) (xy 6.023897 -2.960333) (xy 6.123369 -3.052759) (xy 6.217244 -3.150863) (xy 6.305201 -3.254307)
			(xy 6.386935 -3.362735) (xy 6.462165 -3.475773) (xy 6.530631 -3.59303) (xy 6.592097 -3.714104) (xy 6.646352 -3.838577)
			(xy 6.693209 -3.966019) (xy 6.732505 -4.095992) (xy 6.764106 -4.228046) (xy 6.787903 -4.361728) (xy 6.803813 -4.496575)
			(xy 6.811782 -4.632124) (xy 6.81228 -4.700016) (xy 6.811782 -4.767908) (xy 6.803813 -4.903457) (xy 6.787903 -5.038304)
			(xy 6.764106 -5.171986) (xy 6.732505 -5.30404) (xy 6.693209 -5.434013) (xy 6.646352 -5.561455) (xy 6.592097 -5.685928)
			(xy 6.540201 -5.788152) (xy 101.226874 -5.788152) (xy 101.226874 -5.367528) (xy 101.524562 -5.06984)
			(xy 103.215186 -5.06984) (xy 103.512874 -5.367528) (xy 103.512874 -5.437632) (xy 132.4102 -5.437632)
			(xy 132.4102 -3.747008) (xy 132.707888 -3.44932) (xy 133.128512 -3.44932) (xy 133.4262 -3.747008)
			(xy 133.4262 -5.437632) (xy 133.128512 -5.73532) (xy 132.707888 -5.73532) (xy 132.4102 -5.437632)
			(xy 103.512874 -5.437632) (xy 103.512874 -5.574538) (xy 127.80518 -5.574538) (xy 129.25298 -5.574538)
			(xy 129.25298 -5.925312) (xy 143.947134 -5.925312) (xy 143.947134 -5.504688) (xy 144.244822 -5.207)
			(xy 145.935446 -5.207) (xy 146.145758 -5.417312) (xy 164.2364 -5.417312) (xy 164.2364 -2.699512)
			(xy 165.5318 -2.699512) (xy 165.5318 -4.16306) (xy 166.236396 -4.16306) (xy 166.236396 -1.345184)
			(xy 167.531796 -1.345184) (xy 167.531796 -4.21386) (xy 166.261796 -4.21386) (xy 166.261796 -4.16306)
			(xy 166.236396 -4.16306) (xy 165.5318 -4.16306) (xy 165.5318 -5.417312) (xy 172.236384 -5.417312)
			(xy 172.236384 -2.699512) (xy 173.531784 -2.699512) (xy 173.531784 -4.16306) (xy 174.23638 -4.16306)
			(xy 174.23638 -1.345184) (xy 175.53178 -1.345184) (xy 175.53178 -4.21386) (xy 174.26178 -4.21386)
			(xy 174.26178 -4.16306) (xy 174.23638 -4.16306) (xy 173.531784 -4.16306) (xy 173.531784 -5.468112)
			(xy 172.261784 -5.468112) (xy 172.261784 -5.417312) (xy 172.236384 -5.417312) (xy 165.5318 -5.417312)
			(xy 165.5318 -5.468112) (xy 164.2618 -5.468112) (xy 164.2618 -5.417312) (xy 164.2364 -5.417312) (xy 146.145758 -5.417312)
			(xy 146.233134 -5.504688) (xy 146.233134 -5.925312) (xy 145.935446 -6.223) (xy 144.244822 -6.223)
			(xy 143.947134 -5.925312) (xy 129.25298 -5.925312) (xy 129.25298 -8.393938) (xy 127.80518 -8.393938)
			(xy 127.80518 -5.574538) (xy 103.512874 -5.574538) (xy 103.512874 -5.788152) (xy 103.215186 -6.08584)
			(xy 101.524562 -6.08584) (xy 101.226874 -5.788152) (xy 6.540201 -5.788152) (xy 6.530631 -5.807002)
			(xy 6.462165 -5.924259) (xy 6.386935 -6.037297) (xy 6.305201 -6.145725) (xy 6.217244 -6.249169) (xy 6.123369 -6.347273)
			(xy 6.023897 -6.439699) (xy 5.919173 -6.526127) (xy 5.809557 -6.606261) (xy 5.695427 -6.679823) (xy 5.577177 -6.74656)
			(xy 5.455213 -6.806243) (xy 5.329958 -6.858665) (xy 5.201842 -6.903645) (xy 5.071306 -6.94103) (xy 4.938802 -6.970689)
			(xy 4.804786 -6.99252) (xy 4.669719 -7.006449) (xy 4.534067 -7.012427) (xy 4.398299 -7.010434) (xy 4.262882 -7.000476)
			(xy 4.128282 -6.982588) (xy 3.994964 -6.956832) (xy 3.863388 -6.923296) (xy 3.734006 -6.882096) (xy 3.607266 -6.833373)
			(xy 3.483603 -6.777297) (xy 3.363444 -6.71406) (xy 3.247204 -6.643879) (xy 3.135283 -6.566998) (xy 3.028066 -6.483682)
			(xy 2.925925 -6.394216) (xy 2.829209 -6.29891) (xy 2.738254 -6.198093) (xy 2.653372 -6.092111) (xy 2.574857 -5.981331)
			(xy 2.502978 -5.866133) (xy 2.437983 -5.746916) (xy 2.380098 -5.62409) (xy 2.32952 -5.498078) (xy 2.286425 -5.369315)
			(xy 2.250961 -5.238245) (xy 2.22325 -5.10532) (xy 2.203388 -4.970997) (xy 2.191444 -4.835741) (xy 2.187458 -4.700016)
			(xy 0.509016 -4.700016) (xy 0.509016 -7.500112) (xy 9.403341 -7.500112) (xy 9.407346 -7.412204) (xy 9.419329 -7.325024)
			(xy 9.439189 -7.239295) (xy 9.466764 -7.155727) (xy 9.501823 -7.075013) (xy 9.544076 -6.997821) (xy 9.593174 -6.924792)
			(xy 9.64871 -6.85653) (xy 9.710222 -6.7936) (xy 9.777203 -6.736526) (xy 9.849096 -6.685778) (xy 9.925305 -6.641778)
			(xy 10.0052 -6.604891) (xy 10.088119 -6.575422) (xy 10.173374 -6.553615) (xy 10.260258 -6.539651)
			(xy 10.348052 -6.533645) (xy 10.436029 -6.535649) (xy 10.523459 -6.545644) (xy 10.609618 -6.563548)
			(xy 10.693792 -6.589212) (xy 10.775283 -6.622425) (xy 10.853417 -6.662911) (xy 10.927545 -6.710333)
			(xy 10.997053 -6.7643) (xy 11.061367 -6.824365) (xy 11.106105 -6.87451) (xy 117.8052 -6.87451) (xy 119.253 -6.87451)
			(xy 119.253 -9.0678) (xy 139.3698 -9.0678) (xy 141.1986 -9.0678) (xy 144.169892 -9.0678) (xy 145.998692 -9.0678)
			(xy 145.998692 -9.617456) (xy 164.2364 -9.617456) (xy 164.2364 -6.899656) (xy 165.5318 -6.899656)
			(xy 165.5318 -8.363204) (xy 166.236396 -8.363204) (xy 166.236396 -5.545328) (xy 167.531796 -5.545328)
			(xy 167.531796 -8.414004) (xy 166.261796 -8.414004) (xy 166.261796 -8.363204) (xy 166.236396 -8.363204)
			(xy 165.5318 -8.363204) (xy 165.5318 -9.617456) (xy 168.236392 -9.617456) (xy 168.236392 -6.899656)
			(xy 169.531792 -6.899656) (xy 169.531792 -8.363204) (xy 170.236388 -8.363204) (xy 170.236388 -5.545328)
			(xy 171.531788 -5.545328) (xy 171.531788 -8.414004) (xy 170.261788 -8.414004) (xy 170.261788 -8.363204)
			(xy 170.236388 -8.363204) (xy 169.531792 -8.363204) (xy 169.531792 -9.617456) (xy 172.236384 -9.617456)
			(xy 172.236384 -6.899656) (xy 173.531784 -6.899656) (xy 173.531784 -8.363204) (xy 174.23638 -8.363204)
			(xy 174.23638 -5.545328) (xy 175.53178 -5.545328) (xy 175.53178 -8.414004) (xy 174.26178 -8.414004)
			(xy 174.26178 -8.363204) (xy 174.23638 -8.363204) (xy 173.531784 -8.363204) (xy 173.531784 -9.668256)
			(xy 172.261784 -9.668256) (xy 172.261784 -9.617456) (xy 172.236384 -9.617456) (xy 169.531792 -9.617456)
			(xy 169.531792 -9.668256) (xy 168.261792 -9.668256) (xy 168.261792 -9.617456) (xy 168.236392 -9.617456)
			(xy 165.5318 -9.617456) (xy 165.5318 -9.668256) (xy 164.2618 -9.668256) (xy 164.2618 -9.617456) (xy 164.2364 -9.617456)
			(xy 145.998692 -9.617456) (xy 145.998692 -11.5062) (xy 144.169892 -11.5062) (xy 144.169892 -9.0678)
			(xy 141.1986 -9.0678) (xy 141.1986 -11.5062) (xy 139.3698 -11.5062) (xy 139.3698 -9.0678) (xy 119.253 -9.0678)
			(xy 119.253 -9.69391) (xy 117.8052 -9.69391) (xy 117.8052 -6.87451) (xy 11.106105 -6.87451) (xy 11.119951 -6.890029)
			(xy 11.172322 -6.960748) (xy 11.218045 -7.035936) (xy 11.256742 -7.114971) (xy 11.288091 -7.197197)
			(xy 11.311833 -7.281933) (xy 11.327771 -7.368477) (xy 11.335773 -7.456112) (xy 11.336274 -7.500112)
			(xy 11.335773 -7.544112) (xy 11.327771 -7.631747) (xy 11.311833 -7.718291) (xy 11.288091 -7.803027)
			(xy 11.256742 -7.885253) (xy 11.218045 -7.964288) (xy 11.172322 -8.039476) (xy 11.119951 -8.110195)
			(xy 11.061367 -8.175859) (xy 10.997053 -8.235924) (xy 10.927545 -8.289891) (xy 10.853417 -8.337313)
			(xy 10.775283 -8.377799) (xy 10.693792 -8.411012) (xy 10.609618 -8.436676) (xy 10.523459 -8.45458)
			(xy 10.436029 -8.464575) (xy 10.348052 -8.466579) (xy 10.260258 -8.460573) (xy 10.173374 -8.446609)
			(xy 10.088119 -8.424802) (xy 10.0052 -8.395333) (xy 9.925305 -8.358446) (xy 9.849096 -8.314446) (xy 9.777203 -8.263698)
			(xy 9.710222 -8.206624) (xy 9.64871 -8.143694) (xy 9.593174 -8.075432) (xy 9.544076 -8.002403) (xy 9.501823 -7.925211)
			(xy 9.466764 -7.844497) (xy 9.439189 -7.760929) (xy 9.419329 -7.6752) (xy 9.407346 -7.58802) (xy 9.403341 -7.500112)
			(xy 0.509016 -7.500112) (xy 0.509016 -9.554177) (xy 87.833696 -9.554177) (xy 87.833696 -9.445531)
			(xy 87.841627 -9.337174) (xy 87.857446 -9.229685) (xy 87.881069 -9.123638) (xy 87.91237 -9.019598)
			(xy 87.951182 -8.91812) (xy 87.997297 -8.819746) (xy 88.050471 -8.725001) (xy 88.110419 -8.63439)
			(xy 88.176821 -8.548396) (xy 88.249323 -8.467479) (xy 88.327538 -8.392071) (xy 88.411049 -8.322572)
			(xy 88.49941 -8.259355) (xy 88.59215 -8.202757) (xy 88.688774 -8.153079) (xy 88.788766 -8.110587)
			(xy 88.891594 -8.075507) (xy 88.996708 -8.048027) (xy 89.103547 -8.028292) (xy 89.211542 -8.016409)
			(xy 89.320116 -8.012442) (xy 89.42869 -8.016409) (xy 89.536685 -8.028292) (xy 89.643524 -8.048027)
			(xy 89.748638 -8.075507) (xy 89.851466 -8.110587) (xy 89.951458 -8.153079) (xy 90.048082 -8.202757)
			(xy 90.140822 -8.259355) (xy 90.229183 -8.322572) (xy 90.312694 -8.392071) (xy 90.390909 -8.467479)
			(xy 90.463411 -8.548396) (xy 90.529813 -8.63439) (xy 90.589761 -8.725001) (xy 90.642935 -8.819746)
			(xy 90.68905 -8.91812) (xy 90.727862 -9.019598) (xy 90.742287 -9.067546) (xy 101.449632 -9.067546)
			(xy 103.278432 -9.067546) (xy 106.249724 -9.067546) (xy 108.078524 -9.067546) (xy 108.078524 -9.405112)
			(xy 113.25352 -9.405112) (xy 113.25352 -8.984488) (xy 113.551208 -8.6868) (xy 115.394232 -8.6868)
			(xy 115.69192 -8.984488) (xy 115.69192 -9.405112) (xy 115.394232 -9.7028) (xy 113.551208 -9.7028)
			(xy 113.25352 -9.405112) (xy 108.078524 -9.405112) (xy 108.078524 -9.774428) (xy 127.80518 -9.774428)
			(xy 129.25298 -9.774428) (xy 129.25298 -12.593828) (xy 127.80518 -12.593828) (xy 127.80518 -9.774428)
			(xy 108.078524 -9.774428) (xy 108.078524 -11.0744) (xy 117.8052 -11.0744) (xy 119.253 -11.0744) (xy 119.253 -13.8938)
			(xy 117.8052 -13.8938) (xy 117.8052 -11.0744) (xy 108.078524 -11.0744) (xy 108.078524 -11.505946)
			(xy 106.249724 -11.505946) (xy 106.249724 -9.067546) (xy 103.278432 -9.067546) (xy 103.278432 -11.505946)
			(xy 101.449632 -11.505946) (xy 101.449632 -9.067546) (xy 90.742287 -9.067546) (xy 90.759163 -9.123638)
			(xy 90.782786 -9.229685) (xy 90.798605 -9.337174) (xy 90.806536 -9.445531) (xy 90.807032 -9.499854)
			(xy 90.806536 -9.554177) (xy 90.798605 -9.662534) (xy 90.782786 -9.770023) (xy 90.759163 -9.87607)
			(xy 90.727862 -9.98011) (xy 90.68905 -10.081588) (xy 90.642935 -10.179962) (xy 90.589761 -10.274707)
			(xy 90.529813 -10.365318) (xy 90.463411 -10.451312) (xy 90.390909 -10.532229) (xy 90.312694 -10.607637)
			(xy 90.229183 -10.677136) (xy 90.140822 -10.740353) (xy 90.048082 -10.796951) (xy 89.951458 -10.846629)
			(xy 89.851466 -10.889121) (xy 89.748638 -10.924201) (xy 89.643524 -10.951681) (xy 89.536685 -10.971416)
			(xy 89.42869 -10.983299) (xy 89.320116 -10.987267) (xy 89.211542 -10.983299) (xy 89.103547 -10.971416)
			(xy 88.996708 -10.951681) (xy 88.891594 -10.924201) (xy 88.788766 -10.889121) (xy 88.688774 -10.846629)
			(xy 88.59215 -10.796951) (xy 88.49941 -10.740353) (xy 88.411049 -10.677136) (xy 88.327538 -10.607637)
			(xy 88.249323 -10.532229) (xy 88.176821 -10.451312) (xy 88.110419 -10.365318) (xy 88.050471 -10.274707)
			(xy 87.997297 -10.179962) (xy 87.951182 -10.081588) (xy 87.91237 -9.98011) (xy 87.881069 -9.87607)
			(xy 87.857446 -9.770023) (xy 87.841627 -9.662534) (xy 87.833696 -9.554177) (xy 0.509016 -9.554177)
			(xy 0.509016 -14.439005) (xy 98.549955 -14.439005) (xy 98.549955 -14.340719) (xy 98.557864 -14.242752)
			(xy 98.57363 -14.145739) (xy 98.597151 -14.05031) (xy 98.628275 -13.957082) (xy 98.6668 -13.866661)
			(xy 98.712475 -13.779634) (xy 98.765006 -13.696563) (xy 98.82405 -13.61799) (xy 98.889225 -13.544422)
			(xy 98.960109 -13.476337) (xy 99.036242 -13.414176) (xy 99.117129 -13.358344) (xy 99.202247 -13.309201)
			(xy 99.291044 -13.267067) (xy 99.382942 -13.232214) (xy 99.477348 -13.204869) (xy 99.573647 -13.18521)
			(xy 99.671216 -13.173363) (xy 99.769422 -13.169405) (xy 99.867628 -13.173363) (xy 99.965197 -13.18521)
			(xy 100.061496 -13.204869) (xy 100.155902 -13.232214) (xy 100.2478 -13.267067) (xy 100.336597 -13.309201)
			(xy 100.421715 -13.358344) (xy 100.502602 -13.414176) (xy 100.578735 -13.476337) (xy 100.649619 -13.544422)
			(xy 100.714794 -13.61799) (xy 100.773838 -13.696563) (xy 100.826369 -13.779634) (xy 100.872044 -13.866661)
			(xy 100.910569 -13.957082) (xy 100.941693 -14.05031) (xy 100.965214 -14.145739) (xy 100.98098 -14.242752)
			(xy 100.988889 -14.340719) (xy 100.989384 -14.389862) (xy 100.988889 -14.439005) (xy 100.98098 -14.536972)
			(xy 100.965214 -14.633985) (xy 100.941693 -14.729414) (xy 100.936335 -14.745462) (xy 108.48086 -14.745462)
			(xy 108.48086 -14.059662) (xy 108.481364 -14.017301) (xy 108.489417 -13.932964) (xy 108.505451 -13.849774)
			(xy 108.529319 -13.768484) (xy 108.560807 -13.689832) (xy 108.599629 -13.614529) (xy 108.645432 -13.543257)
			(xy 108.697803 -13.476661) (xy 108.756268 -13.415346) (xy 108.820296 -13.359865) (xy 108.889308 -13.310722)
			(xy 108.962678 -13.268362) (xy 109.039743 -13.233167) (xy 109.119805 -13.205458) (xy 109.202138 -13.185484)
			(xy 109.285997 -13.173427) (xy 109.370622 -13.169396) (xy 109.455247 -13.173427) (xy 109.539106 -13.185484)
			(xy 109.621439 -13.205458) (xy 109.701501 -13.233167) (xy 109.778566 -13.268362) (xy 109.851936 -13.310722)
			(xy 109.920948 -13.359865) (xy 109.984976 -13.415346) (xy 110.043441 -13.476661) (xy 110.095812 -13.543257)
			(xy 110.141615 -13.614529) (xy 110.180437 -13.689832) (xy 110.211925 -13.768484) (xy 110.235793 -13.849774)
			(xy 110.251827 -13.932964) (xy 110.25988 -14.017301) (xy 110.260384 -14.059662) (xy 110.260384 -14.439259)
			(xy 136.470123 -14.439259) (xy 136.470123 -14.340973) (xy 136.478032 -14.243006) (xy 136.493798 -14.145993)
			(xy 136.517319 -14.050564) (xy 136.548443 -13.957336) (xy 136.586968 -13.866915) (xy 136.632643 -13.779888)
			(xy 136.685174 -13.696817) (xy 136.744218 -13.618244) (xy 136.809393 -13.544676) (xy 136.880277 -13.476591)
			(xy 136.95641 -13.41443) (xy 137.037297 -13.358598) (xy 137.122415 -13.309455) (xy 137.211212 -13.267321)
			(xy 137.30311 -13.232468) (xy 137.397516 -13.205123) (xy 137.493815 -13.185464) (xy 137.591384 -13.173617)
			(xy 137.68959 -13.169659) (xy 137.787796 -13.173617) (xy 137.885365 -13.185464) (xy 137.981664 -13.205123)
			(xy 138.07607 -13.232468) (xy 138.167968 -13.267321) (xy 138.256765 -13.309455) (xy 138.341883 -13.358598)
			(xy 138.42277 -13.41443) (xy 138.498903 -13.476591) (xy 138.569787 -13.544676) (xy 138.634962 -13.618244)
			(xy 138.694006 -13.696817) (xy 138.746537 -13.779888) (xy 138.792212 -13.866915) (xy 138.830737 -13.957336)
			(xy 138.861861 -14.050564) (xy 138.885382 -14.145993) (xy 138.901148 -14.243006) (xy 138.909057 -14.340973)
			(xy 138.909552 -14.390116) (xy 138.909057 -14.439259) (xy 138.901148 -14.537226) (xy 138.885382 -14.634239)
			(xy 138.861861 -14.729668) (xy 138.856503 -14.745716) (xy 146.401028 -14.745716) (xy 146.401028 -14.059916)
			(xy 146.401532 -14.017555) (xy 146.409585 -13.933218) (xy 146.425619 -13.850028) (xy 146.449487 -13.768738)
			(xy 146.480975 -13.690086) (xy 146.519797 -13.614783) (xy 146.5656 -13.543511) (xy 146.617971 -13.476915)
			(xy 146.676436 -13.4156) (xy 146.740464 -13.360119) (xy 146.809476 -13.310976) (xy 146.882846 -13.268616)
			(xy 146.959911 -13.233421) (xy 147.039973 -13.205712) (xy 147.122306 -13.185738) (xy 147.206165 -13.173681)
			(xy 147.29079 -13.16965) (xy 147.375415 -13.173681) (xy 147.459274 -13.185738) (xy 147.541607 -13.205712)
			(xy 147.621669 -13.233421) (xy 147.698734 -13.268616) (xy 147.772104 -13.310976) (xy 147.841116 -13.360119)
			(xy 147.905144 -13.4156) (xy 147.963609 -13.476915) (xy 148.01598 -13.543511) (xy 148.061783 -13.614783)
			(xy 148.100605 -13.690086) (xy 148.132093 -13.768738) (xy 148.14644 -13.8176) (xy 164.2364 -13.8176)
			(xy 164.2364 -11.0998) (xy 165.5318 -11.0998) (xy 165.5318 -12.563348) (xy 166.236396 -12.563348)
			(xy 166.236396 -9.745472) (xy 167.531796 -9.745472) (xy 167.531796 -12.614148) (xy 166.261796 -12.614148)
			(xy 166.261796 -12.563348) (xy 166.236396 -12.563348) (xy 165.5318 -12.563348) (xy 165.5318 -13.8176)
			(xy 168.236392 -13.8176) (xy 168.236392 -11.0998) (xy 169.531792 -11.0998) (xy 169.531792 -12.563348)
			(xy 170.236388 -12.563348) (xy 170.236388 -9.745472) (xy 171.531788 -9.745472) (xy 171.531788 -12.614148)
			(xy 170.261788 -12.614148) (xy 170.261788 -12.563348) (xy 170.236388 -12.563348) (xy 169.531792 -12.563348)
			(xy 169.531792 -13.8176) (xy 172.236384 -13.8176) (xy 172.236384 -11.0998) (xy 173.531784 -11.0998)
			(xy 173.531784 -12.563348) (xy 174.23638 -12.563348) (xy 174.23638 -9.745472) (xy 175.53178 -9.745472)
			(xy 175.53178 -10.61511) (xy 195.541919 -10.61511) (xy 195.550132 -10.44552) (xy 195.566539 -10.276526)
			(xy 195.591101 -10.108524) (xy 195.623761 -9.941907) (xy 195.664442 -9.777064) (xy 195.71305 -9.614382)
			(xy 195.740782 -9.534144) (xy 195.747894 -9.51357) (xy 195.747894 -9.332214) (xy 195.876164 -9.203944)
			(xy 195.885562 -9.184386) (xy 195.920655 -9.112187) (xy 195.996552 -8.970709) (xy 196.07884 -8.832851)
			(xy 196.167348 -8.698901) (xy 196.261889 -8.56914) (xy 196.362268 -8.443839) (xy 196.468272 -8.32326)
			(xy 196.57968 -8.207655) (xy 196.637656 -8.15213) (xy 196.661438 -8.128824) (xy 196.703154 -8.076926)
			(xy 196.737476 -8.019868) (xy 196.763776 -7.958696) (xy 196.781571 -7.894533) (xy 196.790534 -7.828553)
			(xy 196.791072 -7.79526) (xy 196.791072 -4.700016) (xy 196.791568 -4.633065) (xy 196.799501 -4.499398)
			(xy 196.815338 -4.366435) (xy 196.839024 -4.234645) (xy 196.870475 -4.104489) (xy 196.909583 -3.976425)
			(xy 196.956207 -3.850902) (xy 197.010187 -3.728362) (xy 197.07133 -3.609235) (xy 197.139424 -3.493939)
			(xy 197.214228 -3.38288) (xy 197.29548 -3.276447) (xy 197.382894 -3.175015) (xy 197.476164 -3.078939)
			(xy 197.574961 -2.988557) (xy 197.67894 -2.904187) (xy 197.787733 -2.826125) (xy 197.90096 -2.754645)
			(xy 198.018223 -2.689998) (xy 198.13911 -2.632411) (xy 198.263196 -2.582087) (xy 198.390045 -2.539202)
			(xy 198.519212 -2.503907) (xy 198.650243 -2.476326) (xy 198.782677 -2.456556) (xy 198.916051 -2.444666)
			(xy 199.049894 -2.440698) (xy 199.183737 -2.444666) (xy 199.317111 -2.456556) (xy 199.449545 -2.476326)
			(xy 199.580576 -2.503907) (xy 199.709743 -2.539202) (xy 199.836592 -2.582087) (xy 199.960678 -2.632411)
			(xy 200.081565 -2.689998) (xy 200.198828 -2.754645) (xy 200.312055 -2.826125) (xy 200.420848 -2.904187)
			(xy 200.524827 -2.988557) (xy 200.623624 -3.078939) (xy 200.716894 -3.175015) (xy 200.804308 -3.276447)
			(xy 200.88556 -3.38288) (xy 200.960364 -3.493939) (xy 201.028458 -3.609235) (xy 201.089601 -3.728362)
			(xy 201.143581 -3.850902) (xy 201.190205 -3.976425) (xy 201.229313 -4.104489) (xy 201.260764 -4.234645)
			(xy 201.28445 -4.366435) (xy 201.300287 -4.499398) (xy 201.30822 -4.633065) (xy 201.308716 -4.700016)
			(xy 201.308716 -7.79526) (xy 201.309274 -7.828552) (xy 201.318236 -7.894531) (xy 201.336026 -7.958695)
			(xy 201.362321 -8.019868) (xy 201.396636 -8.076928) (xy 201.438345 -8.128831) (xy 201.462132 -8.15213)
			(xy 201.520116 -8.207647) (xy 201.631527 -8.32325) (xy 201.737533 -8.443828) (xy 201.837913 -8.569129)
			(xy 201.932455 -8.698891) (xy 202.020962 -8.832842) (xy 202.103249 -8.970702) (xy 202.179143 -9.112182)
			(xy 202.214226 -9.184386) (xy 202.223624 -9.203944) (xy 202.351894 -9.332214) (xy 202.351894 -9.51357)
			(xy 202.359006 -9.534144) (xy 202.386741 -9.614382) (xy 202.435349 -9.777063) (xy 202.47603 -9.941906)
			(xy 202.50869 -10.108524) (xy 202.533252 -10.276526) (xy 202.549659 -10.44552) (xy 202.557872 -10.61511)
			(xy 202.557872 -10.615283) (xy 276.302174 -10.615283) (xy 276.310378 -10.445788) (xy 276.326768 -10.276889)
			(xy 276.351306 -10.108979) (xy 276.383934 -9.942453) (xy 276.424577 -9.777699) (xy 276.473138 -9.615103)
			(xy 276.500844 -9.534906) (xy 276.507956 -9.514332) (xy 276.507956 -9.33196) (xy 276.636988 -9.202928)
			(xy 276.646386 -9.18337) (xy 276.68148 -9.111251) (xy 276.757353 -8.969923) (xy 276.839603 -8.832209)
			(xy 276.928058 -8.698396) (xy 277.022534 -8.568764) (xy 277.122833 -8.443583) (xy 277.228746 -8.323114)
			(xy 277.340052 -8.20761) (xy 277.397972 -8.15213) (xy 277.421756 -8.128827) (xy 277.463472 -8.076928)
			(xy 277.497794 -8.019869) (xy 277.524093 -7.958697) (xy 277.541887 -7.894533) (xy 277.55085 -7.828553)
			(xy 277.551388 -7.79526) (xy 277.551388 -4.700016) (xy 277.551884 -4.633854) (xy 277.559647 -4.501758)
			(xy 277.57513 -4.370343) (xy 277.598279 -4.240059) (xy 277.629016 -4.111354) (xy 277.667234 -3.98467)
			(xy 277.712803 -3.86044) (xy 277.765567 -3.73909) (xy 277.825344 -3.621038) (xy 277.85822 -3.56362)
			(xy 277.8916 -3.507161) (xy 277.964053 -3.397811) (xy 278.042731 -3.292851) (xy 278.127369 -3.192636)
			(xy 278.217683 -3.097504) (xy 278.313367 -3.007774) (xy 278.414098 -2.923751) (xy 278.519537 -2.845717)
			(xy 278.629329 -2.773935) (xy 278.743102 -2.708649) (xy 278.801576 -2.678938) (xy 278.862284 -2.649288)
			(xy 278.986571 -2.596283) (xy 279.113804 -2.550803) (xy 279.243529 -2.51301) (xy 279.375281 -2.48304)
			(xy 279.508589 -2.460999) (xy 279.642977 -2.446967) (xy 279.777962 -2.440994) (xy 279.913064 -2.443101)
			(xy 280.047798 -2.45328) (xy 280.181682 -2.471496) (xy 280.314238 -2.497683) (xy 280.444991 -2.531747)
			(xy 280.573475 -2.573567) (xy 280.699228 -2.622992) (xy 280.821802 -2.679847) (xy 280.940758 -2.743928)
			(xy 281.05567 -2.815005) (xy 281.166128 -2.892824) (xy 281.271737 -2.977108) (xy 281.372118 -3.067554)
			(xy 281.466912 -3.163839) (xy 281.555781 -3.265619) (xy 281.638407 -3.372529) (xy 281.714494 -3.484188)
			(xy 281.78377 -3.600195) (xy 281.845987 -3.720136) (xy 281.900922 -3.843582) (xy 281.94838 -3.970091)
			(xy 281.98819 -4.099211) (xy 282.020211 -4.23048) (xy 282.044326 -4.363429) (xy 282.060451 -4.497581)
			(xy 282.068528 -4.632457) (xy 282.069032 -4.700016) (xy 282.069032 -5.788152) (xy 322.22694 -5.788152)
			(xy 322.22694 -5.367528) (xy 322.524628 -5.06984) (xy 324.215252 -5.06984) (xy 324.51294 -5.367528)
			(xy 324.51294 -5.437632) (xy 353.410266 -5.437632) (xy 353.410266 -3.747008) (xy 353.707954 -3.44932)
			(xy 354.128578 -3.44932) (xy 354.426266 -3.747008) (xy 354.426266 -5.437632) (xy 354.128578 -5.73532)
			(xy 353.707954 -5.73532) (xy 353.410266 -5.437632) (xy 324.51294 -5.437632) (xy 324.51294 -5.574538)
			(xy 348.805246 -5.574538) (xy 350.253046 -5.574538) (xy 350.253046 -5.925312) (xy 364.9472 -5.925312)
			(xy 364.9472 -5.504688) (xy 365.244888 -5.207) (xy 366.935512 -5.207) (xy 367.145824 -5.417312) (xy 385.236466 -5.417312)
			(xy 385.236466 -2.699512) (xy 386.531866 -2.699512) (xy 386.531866 -4.16306) (xy 387.236462 -4.16306)
			(xy 387.236462 -1.345184) (xy 388.531862 -1.345184) (xy 388.531862 -4.21386) (xy 387.261862 -4.21386)
			(xy 387.261862 -4.16306) (xy 387.236462 -4.16306) (xy 386.531866 -4.16306) (xy 386.531866 -5.417312)
			(xy 393.23645 -5.417312) (xy 393.23645 -2.699512) (xy 394.53185 -2.699512) (xy 394.53185 -4.16306)
			(xy 395.236446 -4.16306) (xy 395.236446 -1.345184) (xy 396.531846 -1.345184) (xy 396.531846 -4.21386)
			(xy 395.261846 -4.21386) (xy 395.261846 -4.16306) (xy 395.236446 -4.16306) (xy 394.53185 -4.16306)
			(xy 394.53185 -4.700016) (xy 421.997388 -4.700016) (xy 422.001374 -4.564291) (xy 422.013318 -4.429035)
			(xy 422.03318 -4.294712) (xy 422.060891 -4.161787) (xy 422.096355 -4.030717) (xy 422.13945 -3.901954)
			(xy 422.190028 -3.775942) (xy 422.247913 -3.653116) (xy 422.312908 -3.533899) (xy 422.384787 -3.418701)
			(xy 422.463302 -3.307921) (xy 422.548184 -3.201939) (xy 422.639139 -3.101122) (xy 422.735855 -3.005816)
			(xy 422.837996 -2.91635) (xy 422.945213 -2.833034) (xy 423.057134 -2.756153) (xy 423.173374 -2.685972)
			(xy 423.293533 -2.622735) (xy 423.417196 -2.566659) (xy 423.543936 -2.517936) (xy 423.673318 -2.476736)
			(xy 423.804894 -2.4432) (xy 423.938212 -2.417444) (xy 424.072812 -2.399556) (xy 424.208229 -2.389598)
			(xy 424.343997 -2.387605) (xy 424.479649 -2.393583) (xy 424.614716 -2.407512) (xy 424.748732 -2.429343)
			(xy 424.881236 -2.459002) (xy 425.011772 -2.496387) (xy 425.139888 -2.541367) (xy 425.265143 -2.593789)
			(xy 425.387107 -2.653472) (xy 425.505357 -2.720209) (xy 425.619487 -2.793771) (xy 425.729103 -2.873905)
			(xy 425.833827 -2.960333) (xy 425.933299 -3.052759) (xy 426.027174 -3.150863) (xy 426.115131 -3.254307)
			(xy 426.196865 -3.362735) (xy 426.272095 -3.475773) (xy 426.340561 -3.59303) (xy 426.402027 -3.714104)
			(xy 426.456282 -3.838577) (xy 426.503139 -3.966019) (xy 426.542435 -4.095992) (xy 426.574036 -4.228046)
			(xy 426.597833 -4.361728) (xy 426.613743 -4.496575) (xy 426.621712 -4.632124) (xy 426.62221 -4.700016)
			(xy 426.621712 -4.767908) (xy 426.613743 -4.903457) (xy 426.597833 -5.038304) (xy 426.574036 -5.171986)
			(xy 426.542435 -5.30404) (xy 426.503139 -5.434013) (xy 426.456282 -5.561455) (xy 426.402027 -5.685928)
			(xy 426.340561 -5.807002) (xy 426.272095 -5.924259) (xy 426.196865 -6.037297) (xy 426.115131 -6.145725)
			(xy 426.027174 -6.249169) (xy 425.933299 -6.347273) (xy 425.833827 -6.439699) (xy 425.729103 -6.526127)
			(xy 425.619487 -6.606261) (xy 425.505357 -6.679823) (xy 425.387107 -6.74656) (xy 425.265143 -6.806243)
			(xy 425.139888 -6.858665) (xy 425.011772 -6.903645) (xy 424.881236 -6.94103) (xy 424.748732 -6.970689)
			(xy 424.614716 -6.99252) (xy 424.479649 -7.006449) (xy 424.343997 -7.012427) (xy 424.208229 -7.010434)
			(xy 424.072812 -7.000476) (xy 423.938212 -6.982588) (xy 423.804894 -6.956832) (xy 423.673318 -6.923296)
			(xy 423.543936 -6.882096) (xy 423.417196 -6.833373) (xy 423.293533 -6.777297) (xy 423.173374 -6.71406)
			(xy 423.057134 -6.643879) (xy 422.945213 -6.566998) (xy 422.837996 -6.483682) (xy 422.735855 -6.394216)
			(xy 422.639139 -6.29891) (xy 422.548184 -6.198093) (xy 422.463302 -6.092111) (xy 422.384787 -5.981331)
			(xy 422.312908 -5.866133) (xy 422.247913 -5.746916) (xy 422.190028 -5.62409) (xy 422.13945 -5.498078)
			(xy 422.096355 -5.369315) (xy 422.060891 -5.238245) (xy 422.03318 -5.10532) (xy 422.013318 -4.970997)
			(xy 422.001374 -4.835741) (xy 421.997388 -4.700016) (xy 394.53185 -4.700016) (xy 394.53185 -5.468112)
			(xy 393.26185 -5.468112) (xy 393.26185 -5.417312) (xy 393.23645 -5.417312) (xy 386.531866 -5.417312)
			(xy 386.531866 -5.468112) (xy 385.261866 -5.468112) (xy 385.261866 -5.417312) (xy 385.236466 -5.417312)
			(xy 367.145824 -5.417312) (xy 367.2332 -5.504688) (xy 367.2332 -5.925312) (xy 366.935512 -6.223)
			(xy 365.244888 -6.223) (xy 364.9472 -5.925312) (xy 350.253046 -5.925312) (xy 350.253046 -8.393938)
			(xy 348.805246 -8.393938) (xy 348.805246 -5.574538) (xy 324.51294 -5.574538) (xy 324.51294 -5.788152)
			(xy 324.215252 -6.08584) (xy 322.524628 -6.08584) (xy 322.22694 -5.788152) (xy 282.069032 -5.788152)
			(xy 282.069032 -6.87451) (xy 338.805266 -6.87451) (xy 340.253066 -6.87451) (xy 340.253066 -9.067546)
			(xy 360.369866 -9.067546) (xy 362.198666 -9.067546) (xy 365.169958 -9.067546) (xy 366.998758 -9.067546)
			(xy 366.998758 -9.617456) (xy 385.236466 -9.617456) (xy 385.236466 -6.899656) (xy 386.531866 -6.899656)
			(xy 386.531866 -8.363204) (xy 387.236462 -8.363204) (xy 387.236462 -5.545328) (xy 388.531862 -5.545328)
			(xy 388.531862 -8.414004) (xy 387.261862 -8.414004) (xy 387.261862 -8.363204) (xy 387.236462 -8.363204)
			(xy 386.531866 -8.363204) (xy 386.531866 -9.617456) (xy 389.236458 -9.617456) (xy 389.236458 -6.899656)
			(xy 390.531858 -6.899656) (xy 390.531858 -8.363204) (xy 391.236454 -8.363204) (xy 391.236454 -5.545328)
			(xy 392.531854 -5.545328) (xy 392.531854 -8.414004) (xy 391.261854 -8.414004) (xy 391.261854 -8.363204)
			(xy 391.236454 -8.363204) (xy 390.531858 -8.363204) (xy 390.531858 -9.617456) (xy 393.23645 -9.617456)
			(xy 393.23645 -6.899656) (xy 394.53185 -6.899656) (xy 394.53185 -8.363204) (xy 395.236446 -8.363204)
			(xy 395.236446 -5.545328) (xy 396.531846 -5.545328) (xy 396.531846 -8.414004) (xy 395.261846 -8.414004)
			(xy 395.261846 -8.363204) (xy 395.236446 -8.363204) (xy 394.53185 -8.363204) (xy 394.53185 -9.668256)
			(xy 393.26185 -9.668256) (xy 393.26185 -9.617456) (xy 393.23645 -9.617456) (xy 390.531858 -9.617456)
			(xy 390.531858 -9.668256) (xy 389.261858 -9.668256) (xy 389.261858 -9.617456) (xy 389.236458 -9.617456)
			(xy 386.531866 -9.617456) (xy 386.531866 -9.668256) (xy 385.261866 -9.668256) (xy 385.261866 -9.617456)
			(xy 385.236466 -9.617456) (xy 366.998758 -9.617456) (xy 366.998758 -11.505946) (xy 365.169958 -11.505946)
			(xy 365.169958 -9.067546) (xy 362.198666 -9.067546) (xy 362.198666 -11.505946) (xy 360.369866 -11.505946)
			(xy 360.369866 -9.067546) (xy 340.253066 -9.067546) (xy 340.253066 -9.69391) (xy 338.805266 -9.69391)
			(xy 338.805266 -6.87451) (xy 282.069032 -6.87451) (xy 282.069032 -7.79526) (xy 282.069585 -7.828553)
			(xy 282.078547 -7.894532) (xy 282.096338 -7.958696) (xy 282.122633 -8.019869) (xy 282.15695 -8.076929)
			(xy 282.19866 -8.128831) (xy 282.222448 -8.15213) (xy 282.28042 -8.207659) (xy 282.391833 -8.32326)
			(xy 282.497841 -8.443836) (xy 282.598222 -8.569135) (xy 282.692766 -8.698896) (xy 282.781274 -8.832845)
			(xy 282.863563 -8.970704) (xy 282.939458 -9.112182) (xy 282.974542 -9.184386) (xy 282.98394 -9.203944)
			(xy 283.111956 -9.33196) (xy 283.111956 -9.513062) (xy 283.119068 -9.533382) (xy 283.12617 -9.553914)
			(xy 308.833762 -9.553914) (xy 308.833762 -9.445286) (xy 308.841691 -9.336948) (xy 308.857508 -9.229477)
			(xy 308.881127 -9.123448) (xy 308.912423 -9.019426) (xy 308.951228 -8.917965) (xy 308.997336 -8.819608)
			(xy 309.0505 -8.724879) (xy 309.110438 -8.634284) (xy 309.176828 -8.548305) (xy 309.249318 -8.467402)
			(xy 309.327519 -8.392006) (xy 309.411016 -8.32252) (xy 309.499362 -8.259313) (xy 309.592086 -8.202725)
			(xy 309.688694 -8.153055) (xy 309.788669 -8.11057) (xy 309.891479 -8.075497) (xy 309.996575 -8.048021)
			(xy 310.103396 -8.02829) (xy 310.211372 -8.016409) (xy 310.319928 -8.012442) (xy 310.428484 -8.016409)
			(xy 310.53646 -8.02829) (xy 310.643281 -8.048021) (xy 310.748377 -8.075497) (xy 310.851187 -8.11057)
			(xy 310.951162 -8.153055) (xy 311.04777 -8.202725) (xy 311.140494 -8.259313) (xy 311.22884 -8.32252)
			(xy 311.312337 -8.392006) (xy 311.390538 -8.467402) (xy 311.463028 -8.548305) (xy 311.529418 -8.634284)
			(xy 311.589356 -8.724879) (xy 311.64252 -8.819608) (xy 311.688628 -8.917965) (xy 311.727433 -9.019426)
			(xy 311.741987 -9.0678) (xy 322.449698 -9.0678) (xy 324.278498 -9.0678) (xy 327.24979 -9.0678) (xy 329.07859 -9.0678)
			(xy 329.07859 -9.405112) (xy 334.253586 -9.405112) (xy 334.253586 -8.984488) (xy 334.551274 -8.6868)
			(xy 336.394298 -8.6868) (xy 336.691986 -8.984488) (xy 336.691986 -9.405112) (xy 336.394298 -9.7028)
			(xy 334.551274 -9.7028) (xy 334.253586 -9.405112) (xy 329.07859 -9.405112) (xy 329.07859 -9.774428)
			(xy 348.805246 -9.774428) (xy 350.253046 -9.774428) (xy 350.253046 -12.593828) (xy 348.805246 -12.593828)
			(xy 348.805246 -9.774428) (xy 329.07859 -9.774428) (xy 329.07859 -11.0744) (xy 338.805266 -11.0744)
			(xy 340.253066 -11.0744) (xy 340.253066 -13.8938) (xy 338.805266 -13.8938) (xy 338.805266 -11.0744)
			(xy 329.07859 -11.0744) (xy 329.07859 -11.5062) (xy 327.24979 -11.5062) (xy 327.24979 -9.0678) (xy 324.278498 -9.0678)
			(xy 324.278498 -11.5062) (xy 322.449698 -11.5062) (xy 322.449698 -9.0678) (xy 311.741987 -9.0678)
			(xy 311.758729 -9.123448) (xy 311.782348 -9.229477) (xy 311.798165 -9.336948) (xy 311.806094 -9.445286)
			(xy 311.80659 -9.4996) (xy 311.806094 -9.553914) (xy 311.798165 -9.662252) (xy 311.782348 -9.769723)
			(xy 311.758729 -9.875752) (xy 311.727433 -9.979774) (xy 311.688628 -10.081235) (xy 311.64252 -10.179592)
			(xy 311.589356 -10.274321) (xy 311.529418 -10.364916) (xy 311.463028 -10.450895) (xy 311.390538 -10.531798)
			(xy 311.312337 -10.607194) (xy 311.22884 -10.67668) (xy 311.140494 -10.739887) (xy 311.04777 -10.796475)
			(xy 310.951162 -10.846145) (xy 310.851187 -10.88863) (xy 310.748377 -10.923703) (xy 310.643281 -10.951179)
			(xy 310.53646 -10.97091) (xy 310.428484 -10.982791) (xy 310.319928 -10.986758) (xy 310.211372 -10.982791)
			(xy 310.103396 -10.97091) (xy 309.996575 -10.951179) (xy 309.891479 -10.923703) (xy 309.788669 -10.88863)
			(xy 309.688694 -10.846145) (xy 309.592086 -10.796475) (xy 309.499362 -10.739887) (xy 309.411016 -10.67668)
			(xy 309.327519 -10.607194) (xy 309.249318 -10.531798) (xy 309.176828 -10.450895) (xy 309.110438 -10.364916)
			(xy 309.0505 -10.274321) (xy 308.997336 -10.179592) (xy 308.951228 -10.081235) (xy 308.912423 -9.979774)
			(xy 308.881127 -9.875752) (xy 308.857508 -9.769723) (xy 308.841691 -9.662252) (xy 308.833762 -9.553914)
			(xy 283.12617 -9.553914) (xy 283.146839 -9.613668) (xy 283.195511 -9.776451) (xy 283.236247 -9.941399)
			(xy 283.268951 -10.108126) (xy 283.293547 -10.27624) (xy 283.309975 -10.445347) (xy 283.318199 -10.615052)
			(xy 283.318199 -10.784956) (xy 283.309975 -10.95466) (xy 283.293546 -11.123768) (xy 283.26895 -11.291882)
			(xy 283.236246 -11.458608) (xy 283.195509 -11.623556) (xy 283.146837 -11.786339) (xy 283.119068 -11.866626)
			(xy 283.111956 -11.8872) (xy 283.111956 -12.067794) (xy 282.984194 -12.195556) (xy 282.974796 -12.215114)
			(xy 282.93766 -12.291498) (xy 282.85698 -12.440978) (xy 282.769161 -12.586378) (xy 282.674408 -12.727359)
			(xy 282.572944 -12.863588) (xy 282.465007 -12.994749) (xy 282.350849 -13.120532) (xy 282.230738 -13.240643)
			(xy 282.104955 -13.354802) (xy 281.973795 -13.462739) (xy 281.837565 -13.564204) (xy 281.696585 -13.658956)
			(xy 281.551185 -13.746776) (xy 281.401705 -13.827456) (xy 281.32532 -13.86459) (xy 281.305762 -13.873988)
			(xy 281.177746 -14.002004) (xy 280.996644 -14.002004) (xy 280.976324 -14.009116) (xy 280.896069 -14.03686)
			(xy 280.733354 -14.085488) (xy 280.568476 -14.126187) (xy 280.401822 -14.158861) (xy 280.233783 -14.183434)
			(xy 280.064751 -14.199847) (xy 279.895123 -14.208064) (xy 279.725297 -14.208064) (xy 279.555669 -14.199847)
			(xy 279.386637 -14.183434) (xy 279.218598 -14.158861) (xy 279.051944 -14.126187) (xy 278.887066 -14.085488)
			(xy 278.724351 -14.03686) (xy 278.644096 -14.009116) (xy 278.623776 -14.002004) (xy 278.442166 -14.002004)
			(xy 278.313642 -13.87348) (xy 278.294084 -13.864082) (xy 278.217786 -13.826955) (xy 278.068472 -13.746311)
			(xy 277.923232 -13.658543) (xy 277.782404 -13.563856) (xy 277.646319 -13.462471) (xy 277.515295 -13.354626)
			(xy 277.389637 -13.240572) (xy 277.269641 -13.120576) (xy 277.155586 -12.99492) (xy 277.04774 -12.863896)
			(xy 276.946355 -12.727811) (xy 276.851667 -12.586984) (xy 276.763898 -12.441744) (xy 276.683254 -12.29243)
			(xy 276.646132 -12.21613) (xy 276.636734 -12.196572) (xy 276.507956 -12.067794) (xy 276.507956 -11.885676)
			(xy 276.500844 -11.865356) (xy 276.473156 -11.785153) (xy 276.424592 -11.622557) (xy 276.383947 -11.457804)
			(xy 276.351316 -11.291278) (xy 276.326775 -11.123369) (xy 276.310382 -10.95447) (xy 276.302175 -10.784976)
			(xy 276.302174 -10.615283) (xy 202.557872 -10.615283) (xy 202.557872 -10.784898) (xy 202.549659 -10.954488)
			(xy 202.533251 -11.123481) (xy 202.508689 -11.291484) (xy 202.476028 -11.458101) (xy 202.435347 -11.622944)
			(xy 202.386738 -11.785626) (xy 202.359006 -11.865864) (xy 202.351894 -11.886438) (xy 202.351894 -12.068048)
			(xy 202.22337 -12.196572) (xy 202.213972 -12.21613) (xy 202.176855 -12.292433) (xy 202.09621 -12.441746)
			(xy 202.008442 -12.586987) (xy 201.913754 -12.727814) (xy 201.812368 -12.863899) (xy 201.704521 -12.994923)
			(xy 201.590467 -13.12058) (xy 201.47047 -13.240576) (xy 201.344813 -13.35463) (xy 201.213789 -13.462476)
			(xy 201.077703 -13.563861) (xy 200.936876 -13.658549) (xy 200.791635 -13.746317) (xy 200.642321 -13.826961)
			(xy 200.56602 -13.864082) (xy 200.546462 -13.87348) (xy 200.417684 -14.002258) (xy 200.235566 -14.002258)
			(xy 200.215246 -14.00937) (xy 200.13504 -14.037078) (xy 199.972425 -14.085641) (xy 199.807653 -14.126285)
			(xy 199.641108 -14.158916) (xy 199.47318 -14.183455) (xy 199.304262 -14.199847) (xy 199.13475 -14.208052)
			(xy 198.965038 -14.208052) (xy 198.795526 -14.199847) (xy 198.626608 -14.183455) (xy 198.45868 -14.158916)
			(xy 198.292135 -14.126285) (xy 198.127363 -14.085641) (xy 197.964748 -14.037078) (xy 197.884542 -14.00937)
			(xy 197.864222 -14.002258) (xy 197.682104 -14.002258) (xy 197.553326 -13.87348) (xy 197.533768 -13.864082)
			(xy 197.457467 -13.826961) (xy 197.308153 -13.746317) (xy 197.162913 -13.658549) (xy 197.022085 -13.563861)
			(xy 196.886001 -13.462475) (xy 196.754976 -13.354629) (xy 196.629319 -13.240575) (xy 196.509323 -13.120579)
			(xy 196.395269 -12.994922) (xy 196.287423 -12.863897) (xy 196.186038 -12.727812) (xy 196.09135 -12.586985)
			(xy 196.003581 -12.441745) (xy 195.922937 -12.292431) (xy 195.885816 -12.21613) (xy 195.876418 -12.196572)
			(xy 195.747894 -12.068048) (xy 195.747894 -11.886438) (xy 195.740782 -11.865864) (xy 195.713052 -11.785625)
			(xy 195.664444 -11.622943) (xy 195.623763 -11.458101) (xy 195.591102 -11.291483) (xy 195.56654 -11.123481)
			(xy 195.550133 -10.954487) (xy 195.54192 -10.784898) (xy 195.541919 -10.61511) (xy 175.53178 -10.61511)
			(xy 175.53178 -12.614148) (xy 174.26178 -12.614148) (xy 174.26178 -12.563348) (xy 174.23638 -12.563348)
			(xy 173.531784 -12.563348) (xy 173.531784 -13.8684) (xy 172.261784 -13.8684) (xy 172.261784 -13.8176)
			(xy 172.236384 -13.8176) (xy 169.531792 -13.8176) (xy 169.531792 -13.8684) (xy 168.261792 -13.8684)
			(xy 168.261792 -13.8176) (xy 168.236392 -13.8176) (xy 165.5318 -13.8176) (xy 165.5318 -13.8684) (xy 164.2618 -13.8684)
			(xy 164.2618 -13.8176) (xy 164.2364 -13.8176) (xy 148.14644 -13.8176) (xy 148.155961 -13.850028)
			(xy 148.171995 -13.933218) (xy 148.180048 -14.017555) (xy 148.180552 -14.059916) (xy 148.180552 -14.439259)
			(xy 319.550021 -14.439259) (xy 319.550021 -14.340973) (xy 319.55793 -14.243006) (xy 319.573696 -14.145993)
			(xy 319.597217 -14.050564) (xy 319.628341 -13.957336) (xy 319.666866 -13.866915) (xy 319.712541 -13.779888)
			(xy 319.765072 -13.696817) (xy 319.824116 -13.618244) (xy 319.889291 -13.544676) (xy 319.960175 -13.476591)
			(xy 320.036308 -13.41443) (xy 320.117195 -13.358598) (xy 320.202313 -13.309455) (xy 320.29111 -13.267321)
			(xy 320.383008 -13.232468) (xy 320.477414 -13.205123) (xy 320.573713 -13.185464) (xy 320.671282 -13.173617)
			(xy 320.769488 -13.169659) (xy 320.867694 -13.173617) (xy 320.965263 -13.185464) (xy 321.061562 -13.205123)
			(xy 321.155968 -13.232468) (xy 321.247866 -13.267321) (xy 321.336663 -13.309455) (xy 321.421781 -13.358598)
			(xy 321.502668 -13.41443) (xy 321.578801 -13.476591) (xy 321.649685 -13.544676) (xy 321.71486 -13.618244)
			(xy 321.773904 -13.696817) (xy 321.826435 -13.779888) (xy 321.87211 -13.866915) (xy 321.910635 -13.957336)
			(xy 321.941759 -14.050564) (xy 321.944064 -14.059916) (xy 329.480926 -14.059916) (xy 329.481436 -14.017565)
			(xy 329.489498 -13.933249) (xy 329.505539 -13.85008) (xy 329.529411 -13.768812) (xy 329.5609 -13.690182)
			(xy 329.59972 -13.6149) (xy 329.645519 -13.543649) (xy 329.697884 -13.477073) (xy 329.756339 -13.415776)
			(xy 329.820356 -13.360313) (xy 329.889354 -13.311185) (xy 329.96271 -13.268838) (xy 330.039758 -13.233655)
			(xy 330.119802 -13.205954) (xy 330.202116 -13.185987) (xy 330.285956 -13.173933) (xy 330.370561 -13.169903)
			(xy 330.455166 -13.173933) (xy 330.539006 -13.185987) (xy 330.62132 -13.205954) (xy 330.701364 -13.233655)
			(xy 330.778412 -13.268838) (xy 330.851768 -13.311185) (xy 330.920766 -13.360313) (xy 330.984783 -13.415776)
			(xy 331.043238 -13.477073) (xy 331.095603 -13.543649) (xy 331.141402 -13.6149) (xy 331.180222 -13.690182)
			(xy 331.211711 -13.768812) (xy 331.235583 -13.85008) (xy 331.251624 -13.933249) (xy 331.259686 -14.017565)
			(xy 331.260196 -14.059916) (xy 331.260196 -14.439005) (xy 357.470189 -14.439005) (xy 357.470189 -14.340719)
			(xy 357.478098 -14.242752) (xy 357.493864 -14.145739) (xy 357.517385 -14.05031) (xy 357.548509 -13.957082)
			(xy 357.587034 -13.866661) (xy 357.632709 -13.779634) (xy 357.68524 -13.696563) (xy 357.744284 -13.61799)
			(xy 357.809459 -13.544422) (xy 357.880343 -13.476337) (xy 357.956476 -13.414176) (xy 358.037363 -13.358344)
			(xy 358.122481 -13.309201) (xy 358.211278 -13.267067) (xy 358.303176 -13.232214) (xy 358.397582 -13.204869)
			(xy 358.493881 -13.18521) (xy 358.59145 -13.173363) (xy 358.689656 -13.169405) (xy 358.787862 -13.173363)
			(xy 358.885431 -13.18521) (xy 358.98173 -13.204869) (xy 359.076136 -13.232214) (xy 359.168034 -13.267067)
			(xy 359.256831 -13.309201) (xy 359.341949 -13.358344) (xy 359.422836 -13.414176) (xy 359.498969 -13.476337)
			(xy 359.569853 -13.544422) (xy 359.635028 -13.61799) (xy 359.694072 -13.696563) (xy 359.746603 -13.779634)
			(xy 359.792278 -13.866661) (xy 359.830803 -13.957082) (xy 359.861927 -14.05031) (xy 359.885448 -14.145739)
			(xy 359.901214 -14.242752) (xy 359.909123 -14.340719) (xy 359.909618 -14.389862) (xy 359.909123 -14.439005)
			(xy 359.901214 -14.536972) (xy 359.885448 -14.633985) (xy 359.861927 -14.729414) (xy 359.856569 -14.745462)
			(xy 367.401348 -14.745462) (xy 367.401348 -14.059662) (xy 367.401852 -14.017314) (xy 367.409903 -13.933)
			(xy 367.425932 -13.849834) (xy 367.449793 -13.768567) (xy 367.481272 -13.689937) (xy 367.520083 -13.614656)
			(xy 367.565873 -13.543404) (xy 367.618229 -13.476828) (xy 367.676677 -13.41553) (xy 367.740687 -13.360065)
			(xy 367.809679 -13.310936) (xy 367.883029 -13.268587) (xy 367.960072 -13.233403) (xy 368.040111 -13.205701)
			(xy 368.12242 -13.185733) (xy 368.206255 -13.17368) (xy 368.290856 -13.16965) (xy 368.375457 -13.17368)
			(xy 368.459292 -13.185733) (xy 368.541601 -13.205701) (xy 368.62164 -13.233403) (xy 368.698683 -13.268587)
			(xy 368.772033 -13.310936) (xy 368.841025 -13.360065) (xy 368.905035 -13.41553) (xy 368.963483 -13.476828)
			(xy 369.015839 -13.543404) (xy 369.061629 -13.614656) (xy 369.10044 -13.689937) (xy 369.131919 -13.768567)
			(xy 369.146316 -13.8176) (xy 385.236466 -13.8176) (xy 385.236466 -11.0998) (xy 386.531866 -11.0998)
			(xy 386.531866 -12.563348) (xy 387.236462 -12.563348) (xy 387.236462 -9.745472) (xy 388.531862 -9.745472)
			(xy 388.531862 -12.614148) (xy 387.261862 -12.614148) (xy 387.261862 -12.563348) (xy 387.236462 -12.563348)
			(xy 386.531866 -12.563348) (xy 386.531866 -13.8176) (xy 389.236458 -13.8176) (xy 389.236458 -11.0998)
			(xy 390.531858 -11.0998) (xy 390.531858 -12.563348) (xy 391.236454 -12.563348) (xy 391.236454 -9.745472)
			(xy 392.531854 -9.745472) (xy 392.531854 -12.614148) (xy 391.261854 -12.614148) (xy 391.261854 -12.563348)
			(xy 391.236454 -12.563348) (xy 390.531858 -12.563348) (xy 390.531858 -13.8176) (xy 393.23645 -13.8176)
			(xy 393.23645 -11.0998) (xy 394.53185 -11.0998) (xy 394.53185 -12.563348) (xy 395.236446 -12.563348)
			(xy 395.236446 -9.745472) (xy 396.531846 -9.745472) (xy 396.531846 -12.614148) (xy 395.261846 -12.614148)
			(xy 395.261846 -12.563348) (xy 395.236446 -12.563348) (xy 394.53185 -12.563348) (xy 394.53185 -13.8684)
			(xy 393.26185 -13.8684) (xy 393.26185 -13.8176) (xy 393.23645 -13.8176) (xy 390.531858 -13.8176)
			(xy 390.531858 -13.8684) (xy 389.261858 -13.8684) (xy 389.261858 -13.8176) (xy 389.236458 -13.8176)
			(xy 386.531866 -13.8176) (xy 386.531866 -13.8684) (xy 385.261866 -13.8684) (xy 385.261866 -13.8176)
			(xy 385.236466 -13.8176) (xy 369.146316 -13.8176) (xy 369.15578 -13.849834) (xy 369.171809 -13.933)
			(xy 369.17986 -14.017314) (xy 369.180364 -14.059662) (xy 369.180364 -14.694662) (xy 369.179898 -14.73694)
			(xy 369.1721 -14.821134) (xy 369.156565 -14.90425) (xy 369.133428 -14.985578) (xy 369.102885 -15.064424)
			(xy 369.065196 -15.140115) (xy 369.020685 -15.212005) (xy 368.969729 -15.279482) (xy 368.912765 -15.341969)
			(xy 368.850277 -15.398933) (xy 368.7828 -15.449888) (xy 368.71091 -15.494399) (xy 368.635218 -15.532087)
			(xy 368.556372 -15.56263) (xy 368.475044 -15.585767) (xy 368.391928 -15.601301) (xy 368.307734 -15.609099)
			(xy 368.265456 -15.60957) (xy 368.223029 -15.609129) (xy 368.138583 -15.600808) (xy 368.05536 -15.584249)
			(xy 367.97416 -15.559613) (xy 367.895766 -15.527137) (xy 367.820933 -15.487133) (xy 367.750381 -15.439987)
			(xy 367.684791 -15.386153) (xy 367.624792 -15.326149) (xy 367.570964 -15.260553) (xy 367.523825 -15.189996)
			(xy 367.483828 -15.115159) (xy 367.451359 -15.036763) (xy 367.426731 -14.955561) (xy 367.41018 -14.872336)
			(xy 367.401867 -14.787889) (xy 367.401348 -14.745462) (xy 359.856569 -14.745462) (xy 359.830803 -14.822642)
			(xy 359.792278 -14.913063) (xy 359.746603 -15.000091) (xy 359.694072 -15.083161) (xy 359.635028 -15.161734)
			(xy 359.569853 -15.235302) (xy 359.498969 -15.303387) (xy 359.422836 -15.365548) (xy 359.341949 -15.42138)
			(xy 359.256831 -15.470523) (xy 359.168034 -15.512657) (xy 359.076136 -15.54751) (xy 358.98173 -15.574855)
			(xy 358.885431 -15.594514) (xy 358.787862 -15.606361) (xy 358.689656 -15.610319) (xy 358.59145 -15.606361)
			(xy 358.493881 -15.594514) (xy 358.397582 -15.574855) (xy 358.303176 -15.54751) (xy 358.211278 -15.512657)
			(xy 358.122481 -15.470523) (xy 358.037363 -15.42138) (xy 357.956476 -15.365548) (xy 357.880343 -15.303387)
			(xy 357.809459 -15.235302) (xy 357.744284 -15.161734) (xy 357.68524 -15.083161) (xy 357.632709 -15.000091)
			(xy 357.587034 -14.913063) (xy 357.548509 -14.822642) (xy 357.517385 -14.729414) (xy 357.493864 -14.633985)
			(xy 357.478098 -14.536972) (xy 357.470189 -14.439005) (xy 331.260196 -14.439005) (xy 331.260196 -14.694916)
			(xy 331.259735 -14.737193) (xy 331.251932 -14.821386) (xy 331.236394 -14.904499) (xy 331.213253 -14.985825)
			(xy 331.182708 -15.064668) (xy 331.145018 -15.140357) (xy 331.100505 -15.212245) (xy 331.049549 -15.279719)
			(xy 330.992584 -15.342204) (xy 330.930098 -15.399167) (xy 330.862622 -15.450121) (xy 330.790732 -15.494631)
			(xy 330.715042 -15.532319) (xy 330.636198 -15.562862) (xy 330.554872 -15.586) (xy 330.471758 -15.601536)
			(xy 330.387565 -15.609336) (xy 330.345288 -15.609824) (xy 330.302863 -15.609299) (xy 330.218422 -15.600981)
			(xy 330.135202 -15.584427) (xy 330.054006 -15.559796) (xy 329.975615 -15.527324) (xy 329.900784 -15.487326)
			(xy 329.830233 -15.440186) (xy 329.764643 -15.386357) (xy 329.704645 -15.32636) (xy 329.650817 -15.26077)
			(xy 329.603676 -15.19022) (xy 329.563677 -15.115389) (xy 329.531206 -15.036998) (xy 329.506574 -14.955802)
			(xy 329.490019 -14.872582) (xy 329.481701 -14.788141) (xy 329.48118 -14.745716) (xy 329.480926 -14.059916)
			(xy 321.944064 -14.059916) (xy 321.96528 -14.145993) (xy 321.981046 -14.243006) (xy 321.988955 -14.340973)
			(xy 321.98945 -14.390116) (xy 321.988955 -14.439259) (xy 321.981046 -14.537226) (xy 321.96528 -14.634239)
			(xy 321.941759 -14.729668) (xy 321.910635 -14.822896) (xy 321.87211 -14.913317) (xy 321.826435 -15.000345)
			(xy 321.773904 -15.083415) (xy 321.71486 -15.161988) (xy 321.649685 -15.235556) (xy 321.578801 -15.303641)
			(xy 321.502668 -15.365802) (xy 321.421781 -15.421634) (xy 321.336663 -15.470777) (xy 321.247866 -15.512911)
			(xy 321.155968 -15.547764) (xy 321.061562 -15.575109) (xy 320.965263 -15.594768) (xy 320.867694 -15.606615)
			(xy 320.769488 -15.610573) (xy 320.671282 -15.606615) (xy 320.573713 -15.594768) (xy 320.477414 -15.575109)
			(xy 320.383008 -15.547764) (xy 320.29111 -15.512911) (xy 320.202313 -15.470777) (xy 320.117195 -15.421634)
			(xy 320.036308 -15.365802) (xy 319.960175 -15.303641) (xy 319.889291 -15.235556) (xy 319.824116 -15.161988)
			(xy 319.765072 -15.083415) (xy 319.712541 -15.000345) (xy 319.666866 -14.913317) (xy 319.628341 -14.822896)
			(xy 319.597217 -14.729668) (xy 319.573696 -14.634239) (xy 319.55793 -14.537226) (xy 319.550021 -14.439259)
			(xy 148.180552 -14.439259) (xy 148.180552 -14.694916) (xy 148.18005 -14.737199) (xy 148.172244 -14.821405)
			(xy 148.156702 -14.904531) (xy 148.133555 -14.985868) (xy 148.103 -15.064722) (xy 148.0653 -15.14042)
			(xy 148.020774 -15.212316) (xy 147.969805 -15.279796) (xy 147.912825 -15.342285) (xy 147.850322 -15.399249)
			(xy 147.782829 -15.450202) (xy 147.710922 -15.49471) (xy 147.635215 -15.532392) (xy 147.556354 -15.562926)
			(xy 147.475011 -15.586054) (xy 147.391881 -15.601576) (xy 147.307673 -15.60936) (xy 147.26539 -15.609824)
			(xy 147.265136 -15.609824) (xy 147.222711 -15.60927) (xy 147.138269 -15.600956) (xy 147.055049 -15.584406)
			(xy 146.973852 -15.559779) (xy 146.895459 -15.527311) (xy 146.820627 -15.487315) (xy 146.750075 -15.440177)
			(xy 146.684483 -15.386351) (xy 146.624484 -15.326355) (xy 146.570654 -15.260767) (xy 146.523511 -15.190218)
			(xy 146.483512 -15.115388) (xy 146.451039 -15.036997) (xy 146.426406 -14.955802) (xy 146.409851 -14.872582)
			(xy 146.401533 -14.788141) (xy 146.401028 -14.745716) (xy 138.856503 -14.745716) (xy 138.830737 -14.822896)
			(xy 138.792212 -14.913317) (xy 138.746537 -15.000345) (xy 138.694006 -15.083415) (xy 138.634962 -15.161988)
			(xy 138.569787 -15.235556) (xy 138.498903 -15.303641) (xy 138.42277 -15.365802) (xy 138.341883 -15.421634)
			(xy 138.256765 -15.470777) (xy 138.167968 -15.512911) (xy 138.07607 -15.547764) (xy 137.981664 -15.575109)
			(xy 137.885365 -15.594768) (xy 137.787796 -15.606615) (xy 137.68959 -15.610573) (xy 137.591384 -15.606615)
			(xy 137.493815 -15.594768) (xy 137.397516 -15.575109) (xy 137.30311 -15.547764) (xy 137.211212 -15.512911)
			(xy 137.122415 -15.470777) (xy 137.037297 -15.421634) (xy 136.95641 -15.365802) (xy 136.880277 -15.303641)
			(xy 136.809393 -15.235556) (xy 136.744218 -15.161988) (xy 136.685174 -15.083415) (xy 136.632643 -15.000345)
			(xy 136.586968 -14.913317) (xy 136.548443 -14.822896) (xy 136.517319 -14.729668) (xy 136.493798 -14.634239)
			(xy 136.478032 -14.537226) (xy 136.470123 -14.439259) (xy 110.260384 -14.439259) (xy 110.260384 -14.694662)
			(xy 110.259852 -14.736949) (xy 110.252052 -14.821164) (xy 110.236515 -14.904299) (xy 110.213373 -14.985646)
			(xy 110.182824 -15.06451) (xy 110.145129 -15.14022) (xy 110.100608 -15.212128) (xy 110.049643 -15.279622)
			(xy 109.992668 -15.342125) (xy 109.930168 -15.399105) (xy 109.862678 -15.450074) (xy 109.790772 -15.494599)
			(xy 109.715065 -15.5323) (xy 109.636203 -15.562854) (xy 109.554857 -15.586001) (xy 109.471723 -15.601544)
			(xy 109.387509 -15.609349) (xy 109.345222 -15.609824) (xy 109.302783 -15.609337) (xy 109.218312 -15.601019)
			(xy 109.135064 -15.584462) (xy 109.05384 -15.559824) (xy 108.975422 -15.527343) (xy 108.900565 -15.487331)
			(xy 108.829991 -15.440175) (xy 108.764379 -15.386328) (xy 108.704361 -15.326309) (xy 108.650515 -15.260696)
			(xy 108.60336 -15.190121) (xy 108.563351 -15.115264) (xy 108.530871 -15.036845) (xy 108.506234 -14.95562)
			(xy 108.489678 -14.872372) (xy 108.481362 -14.787901) (xy 108.48086 -14.745462) (xy 100.936335 -14.745462)
			(xy 100.910569 -14.822642) (xy 100.872044 -14.913063) (xy 100.826369 -15.000091) (xy 100.773838 -15.083161)
			(xy 100.714794 -15.161734) (xy 100.649619 -15.235302) (xy 100.578735 -15.303387) (xy 100.502602 -15.365548)
			(xy 100.421715 -15.42138) (xy 100.336597 -15.470523) (xy 100.2478 -15.512657) (xy 100.155902 -15.54751)
			(xy 100.061496 -15.574855) (xy 99.965197 -15.594514) (xy 99.867628 -15.606361) (xy 99.769422 -15.610319)
			(xy 99.671216 -15.606361) (xy 99.573647 -15.594514) (xy 99.477348 -15.574855) (xy 99.382942 -15.54751)
			(xy 99.291044 -15.512657) (xy 99.202247 -15.470523) (xy 99.117129 -15.42138) (xy 99.036242 -15.365548)
			(xy 98.960109 -15.303387) (xy 98.889225 -15.235302) (xy 98.82405 -15.161734) (xy 98.765006 -15.083161)
			(xy 98.712475 -15.000091) (xy 98.6668 -14.913063) (xy 98.628275 -14.822642) (xy 98.597151 -14.729414)
			(xy 98.57363 -14.633985) (xy 98.557864 -14.536972) (xy 98.549955 -14.439005) (xy 0.509016 -14.439005)
			(xy 0.509016 -18.545219) (xy 20.872007 -18.545219) (xy 20.87205 -18.453908) (xy 20.880966 -18.363033)
			(xy 20.898671 -18.273454) (xy 20.911312 -18.22958) (xy 21.129752 -18.22958) (xy 21.146337 -18.229101)
			(xy 21.178386 -18.220556) (xy 21.207146 -18.204033) (xy 21.23067 -18.180649) (xy 21.23948 -18.166588)
			(xy 21.257783 -18.136238) (xy 21.299908 -18.079238) (xy 21.347887 -18.02707) (xy 21.401171 -17.980332)
			(xy 21.459147 -17.939561) (xy 21.489924 -17.921986) (xy 21.504471 -17.913263) (xy 21.528754 -17.889601)
			(xy 21.545969 -17.860391) (xy 21.554909 -17.827686) (xy 21.555456 -17.810734) (xy 21.555456 -17.596866)
			(xy 21.596941 -17.585678) (xy 21.681432 -17.570032) (xy 21.767 -17.562177) (xy 21.852928 -17.562177)
			(xy 21.938496 -17.570032) (xy 22.022987 -17.585678) (xy 22.064472 -17.596866) (xy 22.064472 -17.810734)
			(xy 22.064965 -17.827699) (xy 22.073856 -17.860443) (xy 22.091078 -17.889676) (xy 22.115409 -17.913323)
			(xy 22.130004 -17.921986) (xy 22.160779 -17.939567) (xy 22.21877 -17.98032) (xy 22.272063 -18.02705)
			(xy 22.320044 -18.079219) (xy 22.362161 -18.136227) (xy 22.380448 -18.166588) (xy 22.389279 -18.180628)
			(xy 22.412809 -18.203988) (xy 22.441563 -18.220498) (xy 22.473598 -18.229044) (xy 22.490176 -18.22958)
			(xy 22.708616 -18.22958) (xy 22.72124 -18.273545) (xy 22.738897 -18.363302) (xy 22.747728 -18.454351)
			(xy 22.74824 -18.50009) (xy 22.747731 -18.545211) (xy 22.739127 -18.635041) (xy 22.730464 -18.679668)
			(xy 167.07104 -18.679668) (xy 167.07104 -18.353532) (xy 167.301672 -18.1229) (xy 168.897808 -18.1229)
			(xy 169.12844 -18.353532) (xy 169.12844 -18.679668) (xy 191.866266 -18.679668) (xy 191.866266 -18.353532)
			(xy 192.096898 -18.1229) (xy 193.693034 -18.1229) (xy 193.923666 -18.353532) (xy 193.923666 -18.679668)
			(xy 388.071106 -18.679668) (xy 388.071106 -18.353532) (xy 388.301738 -18.1229) (xy 389.897874 -18.1229)
			(xy 390.128506 -18.353532) (xy 390.128506 -18.679668) (xy 412.866332 -18.679668) (xy 412.866332 -18.353532)
			(xy 413.096964 -18.1229) (xy 414.6931 -18.1229) (xy 414.923732 -18.353532) (xy 414.923732 -18.679668)
			(xy 414.6931 -18.9103) (xy 413.096964 -18.9103) (xy 412.866332 -18.679668) (xy 390.128506 -18.679668)
			(xy 389.897874 -18.9103) (xy 388.301738 -18.9103) (xy 388.071106 -18.679668) (xy 193.923666 -18.679668)
			(xy 193.693034 -18.9103) (xy 192.096898 -18.9103) (xy 191.866266 -18.679668) (xy 169.12844 -18.679668)
			(xy 168.897808 -18.9103) (xy 167.301672 -18.9103) (xy 167.07104 -18.679668) (xy 22.730464 -18.679668)
			(xy 22.721931 -18.723629) (xy 22.709632 -18.767044) (xy 22.492208 -18.767044) (xy 22.475563 -18.767623)
			(xy 22.443406 -18.776234) (xy 22.414572 -18.792872) (xy 22.391024 -18.816404) (xy 22.382226 -18.830544)
			(xy 22.363929 -18.861244) (xy 22.321713 -18.918915) (xy 22.273522 -18.971695) (xy 22.219918 -19.018968)
			(xy 22.161527 -19.060183) (xy 22.130512 -19.07794) (xy 22.115939 -19.086623) (xy 22.091663 -19.110301)
			(xy 22.074455 -19.139522) (xy 22.065523 -19.172237) (xy 22.06498 -19.189192) (xy 22.06498 -19.40306)
			(xy 22.023416 -19.414293) (xy 21.938758 -19.430004) (xy 21.853016 -19.437893) (xy 21.766912 -19.437893)
			(xy 21.68117 -19.430004) (xy 21.596512 -19.414293) (xy 21.554948 -19.40306) (xy 21.554948 -19.189192)
			(xy 21.554425 -19.172229) (xy 21.545543 -19.139488) (xy 21.528329 -19.110255) (xy 21.504007 -19.086606)
			(xy 21.489416 -19.07794) (xy 21.458589 -19.060303) (xy 21.40052 -19.019407) (xy 21.347167 -18.972525)
			(xy 21.299145 -18.920195) (xy 21.257007 -18.863021) (xy 21.238718 -18.832576) (xy 21.229921 -18.818513)
			(xy 21.206378 -18.795158) (xy 21.177615 -18.778654) (xy 21.145571 -18.770116) (xy 21.12899 -18.769584)
			(xy 20.911058 -18.769584) (xy 20.89846 -18.725697) (xy 20.880839 -18.636102) (xy 20.872007 -18.545219)
			(xy 0.509016 -18.545219) (xy 0.509016 -24.826468) (xy 165.8239 -24.826468) (xy 165.8239 -23.230332)
			(xy 166.054532 -22.9997) (xy 166.380668 -22.9997) (xy 166.6113 -23.230332) (xy 166.6113 -23.858728)
			(xy 170.456352 -23.858728) (xy 170.456352 -23.532592) (xy 170.686984 -23.30196) (xy 172.28312 -23.30196)
			(xy 172.513752 -23.532592) (xy 172.513752 -23.858728) (xy 172.28312 -24.08936) (xy 170.686984 -24.08936)
			(xy 170.456352 -23.858728) (xy 166.6113 -23.858728) (xy 166.6113 -24.826468) (xy 177.83048 -24.826468)
			(xy 177.83048 -23.230332) (xy 178.061112 -22.9997) (xy 178.387248 -22.9997) (xy 178.61788 -23.230332)
			(xy 178.61788 -23.741888) (xy 189.46622 -23.741888) (xy 189.46622 -23.415752) (xy 189.696852 -23.18512)
			(xy 191.292988 -23.18512) (xy 191.52362 -23.415752) (xy 191.52362 -23.741888) (xy 191.292988 -23.97252)
			(xy 189.696852 -23.97252) (xy 189.46622 -23.741888) (xy 178.61788 -23.741888) (xy 178.61788 -24.826468)
			(xy 178.61026 -24.834088) (xy 197.2691 -24.834088) (xy 197.2691 -23.237952) (xy 197.499732 -23.00732)
			(xy 197.825868 -23.00732) (xy 198.0565 -23.237952) (xy 198.0565 -24.826468) (xy 386.823966 -24.826468)
			(xy 386.823966 -23.230332) (xy 387.054598 -22.9997) (xy 387.380734 -22.9997) (xy 387.611366 -23.230332)
			(xy 387.611366 -23.858728) (xy 391.456418 -23.858728) (xy 391.456418 -23.532592) (xy 391.68705 -23.30196)
			(xy 393.283186 -23.30196) (xy 393.513818 -23.532592) (xy 393.513818 -23.858728) (xy 393.283186 -24.08936)
			(xy 391.68705 -24.08936) (xy 391.456418 -23.858728) (xy 387.611366 -23.858728) (xy 387.611366 -24.826468)
			(xy 398.830546 -24.826468) (xy 398.830546 -23.230332) (xy 399.061178 -22.9997) (xy 399.387314 -22.9997)
			(xy 399.617946 -23.230332) (xy 399.617946 -23.741888) (xy 410.466286 -23.741888) (xy 410.466286 -23.415752)
			(xy 410.696918 -23.18512) (xy 412.293054 -23.18512) (xy 412.523686 -23.415752) (xy 412.523686 -23.741888)
			(xy 412.293054 -23.97252) (xy 410.696918 -23.97252) (xy 410.466286 -23.741888) (xy 399.617946 -23.741888)
			(xy 399.617946 -24.826468) (xy 399.610326 -24.834088) (xy 418.269166 -24.834088) (xy 418.269166 -23.237952)
			(xy 418.499798 -23.00732) (xy 418.825934 -23.00732) (xy 419.056566 -23.237952) (xy 419.056566 -24.834088)
			(xy 418.825934 -25.06472) (xy 418.499798 -25.06472) (xy 418.269166 -24.834088) (xy 399.610326 -24.834088)
			(xy 399.522442 -24.921972) (xy 408.456384 -24.921972) (xy 409.726384 -24.921972) (xy 410.85643 -24.921972)
			(xy 412.12643 -24.921972) (xy 413.256222 -24.921972) (xy 414.526222 -24.921972) (xy 415.656268 -24.921972)
			(xy 416.926268 -24.921972) (xy 416.926268 -26.877772) (xy 415.656268 -26.877772) (xy 415.656268 -24.921972)
			(xy 414.526222 -24.921972) (xy 414.526222 -26.877772) (xy 413.256222 -26.877772) (xy 413.256222 -24.921972)
			(xy 412.12643 -24.921972) (xy 412.12643 -26.877772) (xy 410.85643 -26.877772) (xy 410.85643 -24.921972)
			(xy 409.726384 -24.921972) (xy 409.726384 -26.877772) (xy 408.456384 -26.877772) (xy 408.456384 -24.921972)
			(xy 399.522442 -24.921972) (xy 399.387314 -25.0571) (xy 399.061178 -25.0571) (xy 398.830546 -24.826468)
			(xy 387.611366 -24.826468) (xy 387.515862 -24.921972) (xy 389.446262 -24.921972) (xy 390.716262 -24.921972)
			(xy 391.846308 -24.921972) (xy 393.116308 -24.921972) (xy 394.2461 -24.921972) (xy 395.5161 -24.921972)
			(xy 396.646146 -24.921972) (xy 397.916146 -24.921972) (xy 397.916146 -26.877772) (xy 396.646146 -26.877772)
			(xy 396.646146 -24.921972) (xy 395.5161 -24.921972) (xy 395.5161 -26.877772) (xy 394.2461 -26.877772)
			(xy 394.2461 -24.921972) (xy 393.116308 -24.921972) (xy 393.116308 -26.877772) (xy 391.846308 -26.877772)
			(xy 391.846308 -24.921972) (xy 390.716262 -24.921972) (xy 390.716262 -26.877772) (xy 389.446262 -26.877772)
			(xy 389.446262 -24.921972) (xy 387.515862 -24.921972) (xy 387.380734 -25.0571) (xy 387.054598 -25.0571)
			(xy 386.823966 -24.826468) (xy 198.0565 -24.826468) (xy 198.0565 -24.834088) (xy 197.825868 -25.06472)
			(xy 197.499732 -25.06472) (xy 197.2691 -24.834088) (xy 178.61026 -24.834088) (xy 178.522376 -24.921972)
			(xy 187.456318 -24.921972) (xy 188.726318 -24.921972) (xy 189.856364 -24.921972) (xy 191.126364 -24.921972)
			(xy 192.256156 -24.921972) (xy 193.526156 -24.921972) (xy 194.656202 -24.921972) (xy 195.926202 -24.921972)
			(xy 195.926202 -26.877772) (xy 194.656202 -26.877772) (xy 194.656202 -24.921972) (xy 193.526156 -24.921972)
			(xy 193.526156 -26.877772) (xy 192.256156 -26.877772) (xy 192.256156 -24.921972) (xy 191.126364 -24.921972)
			(xy 191.126364 -26.877772) (xy 189.856364 -26.877772) (xy 189.856364 -24.921972) (xy 188.726318 -24.921972)
			(xy 188.726318 -26.877772) (xy 187.456318 -26.877772) (xy 187.456318 -24.921972) (xy 178.522376 -24.921972)
			(xy 178.387248 -25.0571) (xy 178.061112 -25.0571) (xy 177.83048 -24.826468) (xy 166.6113 -24.826468)
			(xy 166.515796 -24.921972) (xy 168.44645 -24.921972) (xy 169.71645 -24.921972) (xy 170.846496 -24.921972)
			(xy 172.116496 -24.921972) (xy 173.246288 -24.921972) (xy 174.516288 -24.921972) (xy 175.646334 -24.921972)
			(xy 176.916334 -24.921972) (xy 176.916334 -26.877772) (xy 175.646334 -26.877772) (xy 175.646334 -24.921972)
			(xy 174.516288 -24.921972) (xy 174.516288 -26.877772) (xy 173.246288 -26.877772) (xy 173.246288 -24.921972)
			(xy 172.116496 -24.921972) (xy 172.116496 -26.877772) (xy 170.846496 -26.877772) (xy 170.846496 -24.921972)
			(xy 169.71645 -24.921972) (xy 169.71645 -26.877772) (xy 168.44645 -26.877772) (xy 168.44645 -24.921972)
			(xy 166.515796 -24.921972) (xy 166.380668 -25.0571) (xy 166.054532 -25.0571) (xy 165.8239 -24.826468)
			(xy 0.509016 -24.826468) (xy 0.509016 -26.545204) (xy 20.872002 -26.545204) (xy 20.872046 -26.453892)
			(xy 20.880963 -26.363017) (xy 20.89867 -26.273438) (xy 20.911312 -26.229564) (xy 21.129752 -26.229564)
			(xy 21.146337 -26.229093) (xy 21.178388 -26.220547) (xy 21.207148 -26.204021) (xy 21.230671 -26.180634)
			(xy 21.23948 -26.166572) (xy 21.257779 -26.13622) (xy 21.299905 -26.07922) (xy 21.347885 -26.027052)
			(xy 21.40117 -25.980315) (xy 21.459146 -25.939544) (xy 21.489924 -25.92197) (xy 21.504479 -25.913258)
			(xy 21.528761 -25.889592) (xy 21.545974 -25.86038) (xy 21.554911 -25.827671) (xy 21.555456 -25.810718)
			(xy 21.555456 -25.59685) (xy 21.596941 -25.585662) (xy 21.681432 -25.570016) (xy 21.767 -25.562161)
			(xy 21.852928 -25.562161) (xy 21.938496 -25.570016) (xy 22.022987 -25.585662) (xy 22.064472 -25.59685)
			(xy 22.064472 -25.810718) (xy 22.064977 -25.827683) (xy 22.073864 -25.860425) (xy 22.091083 -25.889658)
			(xy 22.11541 -25.913306) (xy 22.130004 -25.92197) (xy 22.160776 -25.939556) (xy 22.218768 -25.980308)
			(xy 22.272061 -26.027037) (xy 22.320043 -26.079205) (xy 22.362161 -26.136212) (xy 22.380448 -26.166572)
			(xy 22.389252 -26.18063) (xy 22.412795 -26.203982) (xy 22.441556 -26.220486) (xy 22.473596 -26.229029)
			(xy 22.490176 -26.229564) (xy 22.708616 -26.229564) (xy 22.721236 -26.27353) (xy 22.738894 -26.363286)
			(xy 22.747728 -26.454335) (xy 22.74824 -26.500074) (xy 22.747727 -26.545195) (xy 22.739125 -26.635025)
			(xy 22.72193 -26.723613) (xy 22.709632 -26.767028) (xy 22.492208 -26.767028) (xy 22.475553 -26.767518)
			(xy 22.443378 -26.776138) (xy 22.414531 -26.792795) (xy 22.39098 -26.816351) (xy 22.382226 -26.830528)
			(xy 22.363925 -26.861225) (xy 22.32171 -26.918897) (xy 22.27352 -26.971677) (xy 22.257883 -26.985468)
			(xy 183.6039 -26.985468) (xy 183.6039 -26.659332) (xy 183.834532 -26.4287) (xy 185.430668 -26.4287)
			(xy 185.6613 -26.659332) (xy 185.6613 -26.985468) (xy 404.603712 -26.985468) (xy 404.603712 -26.659332)
			(xy 404.834344 -26.4287) (xy 406.43048 -26.4287) (xy 406.661112 -26.659332) (xy 406.661112 -26.985468)
			(xy 406.43048 -27.2161) (xy 404.834344 -27.2161) (xy 404.603712 -26.985468) (xy 185.6613 -26.985468)
			(xy 185.430668 -27.2161) (xy 183.834532 -27.2161) (xy 183.6039 -26.985468) (xy 22.257883 -26.985468)
			(xy 22.219917 -27.018951) (xy 22.161527 -27.060166) (xy 22.130512 -27.077924) (xy 22.115946 -27.086618)
			(xy 22.091669 -27.110292) (xy 22.07446 -27.13951) (xy 22.065525 -27.172222) (xy 22.06498 -27.189176)
			(xy 22.06498 -27.403044) (xy 22.023416 -27.414277) (xy 21.938758 -27.429988) (xy 21.91689 -27.432)
			(xy 168.0464 -27.432) (xy 169.3164 -27.432) (xy 170.446446 -27.432) (xy 171.716446 -27.432) (xy 172.846238 -27.432)
			(xy 174.116238 -27.432) (xy 175.246284 -27.432) (xy 176.516284 -27.432) (xy 187.056268 -27.432) (xy 188.326268 -27.432)
			(xy 189.456314 -27.432) (xy 190.726314 -27.432) (xy 191.856106 -27.432) (xy 193.126106 -27.432) (xy 194.256152 -27.432)
			(xy 195.526152 -27.432) (xy 389.046212 -27.432) (xy 390.316212 -27.432) (xy 391.446258 -27.432) (xy 392.716258 -27.432)
			(xy 393.84605 -27.432) (xy 395.11605 -27.432) (xy 396.246096 -27.432) (xy 397.516096 -27.432) (xy 408.056334 -27.432)
			(xy 409.326334 -27.432) (xy 410.45638 -27.432) (xy 411.72638 -27.432) (xy 412.856172 -27.432) (xy 414.126172 -27.432)
			(xy 415.256218 -27.432) (xy 416.526218 -27.432) (xy 416.526218 -29.3878) (xy 415.256218 -29.3878)
			(xy 415.256218 -27.432) (xy 414.126172 -27.432) (xy 414.126172 -29.3878) (xy 412.856172 -29.3878)
			(xy 412.856172 -27.432) (xy 411.72638 -27.432) (xy 411.72638 -29.3878) (xy 410.45638 -29.3878) (xy 410.45638 -27.432)
			(xy 409.326334 -27.432) (xy 409.326334 -29.3878) (xy 408.056334 -29.3878) (xy 408.056334 -27.432)
			(xy 397.516096 -27.432) (xy 397.516096 -29.3878) (xy 396.246096 -29.3878) (xy 396.246096 -27.432)
			(xy 395.11605 -27.432) (xy 395.11605 -29.3878) (xy 393.84605 -29.3878) (xy 393.84605 -27.432) (xy 392.716258 -27.432)
			(xy 392.716258 -29.3878) (xy 391.446258 -29.3878) (xy 391.446258 -27.432) (xy 390.316212 -27.432)
			(xy 390.316212 -29.3878) (xy 389.046212 -29.3878) (xy 389.046212 -27.432) (xy 195.526152 -27.432)
			(xy 195.526152 -29.3878) (xy 194.256152 -29.3878) (xy 194.256152 -27.432) (xy 193.126106 -27.432)
			(xy 193.126106 -29.3878) (xy 191.856106 -29.3878) (xy 191.856106 -27.432) (xy 190.726314 -27.432)
			(xy 190.726314 -29.3878) (xy 189.456314 -29.3878) (xy 189.456314 -27.432) (xy 188.326268 -27.432)
			(xy 188.326268 -29.3878) (xy 187.056268 -29.3878) (xy 187.056268 -27.432) (xy 176.516284 -27.432)
			(xy 176.516284 -29.3878) (xy 175.246284 -29.3878) (xy 175.246284 -27.432) (xy 174.116238 -27.432)
			(xy 174.116238 -29.3878) (xy 172.846238 -29.3878) (xy 172.846238 -27.432) (xy 171.716446 -27.432)
			(xy 171.716446 -29.3878) (xy 170.446446 -29.3878) (xy 170.446446 -27.432) (xy 169.3164 -27.432) (xy 169.3164 -29.3878)
			(xy 168.0464 -29.3878) (xy 168.0464 -27.432) (xy 21.91689 -27.432) (xy 21.853016 -27.437877) (xy 21.766912 -27.437877)
			(xy 21.68117 -27.429988) (xy 21.596512 -27.414277) (xy 21.554948 -27.403044) (xy 21.554948 -27.189176)
			(xy 21.554438 -27.172212) (xy 21.545551 -27.139471) (xy 21.528334 -27.110238) (xy 21.504009 -27.086589)
			(xy 21.489416 -27.077924) (xy 21.458587 -27.060291) (xy 21.400517 -27.019395) (xy 21.347165 -26.972511)
			(xy 21.299143 -26.92018) (xy 21.257006 -26.863005) (xy 21.238718 -26.83256) (xy 21.229926 -26.818493)
			(xy 21.206381 -26.79514) (xy 21.177616 -26.778637) (xy 21.145571 -26.770099) (xy 21.12899 -26.769568)
			(xy 20.911058 -26.769568) (xy 20.898452 -26.725683) (xy 20.880832 -26.636088) (xy 20.872002 -26.545204)
			(xy 0.509016 -26.545204) (xy 0.509016 -35.084824) (xy 0.991888 -35.084824) (xy 0.991888 -34.915036)
			(xy 1.000101 -34.745446) (xy 1.016507 -34.576452) (xy 1.04107 -34.40845) (xy 1.07373 -34.241833)
			(xy 1.114412 -34.07699) (xy 1.16302 -33.914308) (xy 1.190752 -33.83407) (xy 1.197864 -33.813496)
			(xy 1.197864 -33.63214) (xy 1.326134 -33.50387) (xy 1.335532 -33.484312) (xy 1.370617 -33.412109)
			(xy 1.446515 -33.270632) (xy 1.528804 -33.132774) (xy 1.617313 -32.998825) (xy 1.711856 -32.869064)
			(xy 1.812235 -32.743763) (xy 1.91824 -32.623185) (xy 2.02965 -32.507581) (xy 2.087626 -32.452056)
			(xy 2.111452 -32.428781) (xy 2.153219 -32.376896) (xy 2.187589 -32.319842) (xy 2.21393 -32.258664)
			(xy 2.231759 -32.194487) (xy 2.240748 -32.12849) (xy 2.241296 -32.095186) (xy 2.241296 -28.999942)
			(xy 2.241792 -28.932998) (xy 2.249724 -28.799346) (xy 2.265559 -28.666399) (xy 2.289242 -28.534623)
			(xy 2.32069 -28.404482) (xy 2.359793 -28.276432) (xy 2.406413 -28.150923) (xy 2.460386 -28.028397)
			(xy 2.521523 -27.909284) (xy 2.589609 -27.794001) (xy 2.664404 -27.682954) (xy 2.745647 -27.576533)
			(xy 2.833051 -27.475112) (xy 2.926311 -27.379047) (xy 3.025097 -27.288676) (xy 3.129064 -27.204315)
			(xy 3.237845 -27.126261) (xy 3.35106 -27.054789) (xy 3.468309 -26.99015) (xy 3.589182 -26.932569)
			(xy 3.713254 -26.882251) (xy 3.840089 -26.839371) (xy 3.969241 -26.80408) (xy 4.100258 -26.776502)
			(xy 4.232677 -26.756734) (xy 4.366036 -26.744846) (xy 4.499864 -26.740878) (xy 4.633692 -26.744846)
			(xy 4.767051 -26.756734) (xy 4.89947 -26.776502) (xy 5.030487 -26.80408) (xy 5.159639 -26.839371)
			(xy 5.286474 -26.882251) (xy 5.410546 -26.932569) (xy 5.531419 -26.99015) (xy 5.648668 -27.054789)
			(xy 5.761883 -27.126261) (xy 5.870664 -27.204315) (xy 5.974631 -27.288676) (xy 6.073417 -27.379047)
			(xy 6.166677 -27.475112) (xy 6.254081 -27.576533) (xy 6.335324 -27.682954) (xy 6.410119 -27.794001)
			(xy 6.478205 -27.909284) (xy 6.539342 -28.028397) (xy 6.593315 -28.150923) (xy 6.639935 -28.276432)
			(xy 6.679038 -28.404482) (xy 6.710486 -28.534623) (xy 6.734169 -28.666399) (xy 6.750004 -28.799346)
			(xy 6.757936 -28.932998) (xy 6.758432 -28.999942) (xy 6.758432 -29.472128) (xy 183.83504 -29.472128)
			(xy 183.83504 -29.145992) (xy 184.065672 -28.91536) (xy 185.661808 -28.91536) (xy 185.89244 -29.145992)
			(xy 185.89244 -29.472128) (xy 404.834852 -29.472128) (xy 404.834852 -29.145992) (xy 405.065484 -28.91536)
			(xy 406.66162 -28.91536) (xy 406.892252 -29.145992) (xy 406.892252 -29.472128) (xy 406.66162 -29.70276)
			(xy 405.065484 -29.70276) (xy 404.834852 -29.472128) (xy 185.89244 -29.472128) (xy 185.661808 -29.70276)
			(xy 184.065672 -29.70276) (xy 183.83504 -29.472128) (xy 6.758432 -29.472128) (xy 6.758432 -30.897068)
			(xy 167.656256 -30.897068) (xy 167.656256 -30.570932) (xy 167.886888 -30.3403) (xy 169.483024 -30.3403)
			(xy 169.713656 -30.570932) (xy 169.713656 -30.897068) (xy 169.483024 -31.1277) (xy 167.886888 -31.1277)
			(xy 167.656256 -30.897068) (xy 6.758432 -30.897068) (xy 6.758432 -31.158688) (xy 174.856394 -31.158688)
			(xy 174.856394 -30.832552) (xy 175.087026 -30.60192) (xy 176.683162 -30.60192) (xy 176.839118 -30.757876)
			(xy 189.06617 -30.757876) (xy 189.06617 -30.43174) (xy 189.296802 -30.201108) (xy 190.892938 -30.201108)
			(xy 191.12357 -30.43174) (xy 191.12357 -30.726888) (xy 193.866262 -30.726888) (xy 193.866262 -30.400752)
			(xy 194.096894 -30.17012) (xy 195.69303 -30.17012) (xy 195.923662 -30.400752) (xy 195.923662 -30.726888)
			(xy 195.753482 -30.897068) (xy 388.656068 -30.897068) (xy 388.656068 -30.570932) (xy 388.8867 -30.3403)
			(xy 390.482836 -30.3403) (xy 390.713468 -30.570932) (xy 390.713468 -30.897068) (xy 390.482836 -31.1277)
			(xy 388.8867 -31.1277) (xy 388.656068 -30.897068) (xy 195.753482 -30.897068) (xy 195.69303 -30.95752)
			(xy 194.096894 -30.95752) (xy 193.866262 -30.726888) (xy 191.12357 -30.726888) (xy 191.12357 -30.757876)
			(xy 190.892938 -30.988508) (xy 189.296802 -30.988508) (xy 189.06617 -30.757876) (xy 176.839118 -30.757876)
			(xy 176.913794 -30.832552) (xy 176.913794 -31.158688) (xy 395.856206 -31.158688) (xy 395.856206 -30.832552)
			(xy 396.086838 -30.60192) (xy 397.682974 -30.60192) (xy 397.83893 -30.757876) (xy 410.065982 -30.757876)
			(xy 410.065982 -30.43174) (xy 410.296614 -30.201108) (xy 411.89275 -30.201108) (xy 412.123382 -30.43174)
			(xy 412.123382 -30.726888) (xy 414.866074 -30.726888) (xy 414.866074 -30.400752) (xy 415.096706 -30.17012)
			(xy 416.692842 -30.17012) (xy 416.923474 -30.400752) (xy 416.923474 -30.726888) (xy 416.692842 -30.95752)
			(xy 415.096706 -30.95752) (xy 414.866074 -30.726888) (xy 412.123382 -30.726888) (xy 412.123382 -30.757876)
			(xy 411.89275 -30.988508) (xy 410.296614 -30.988508) (xy 410.065982 -30.757876) (xy 397.83893 -30.757876)
			(xy 397.913606 -30.832552) (xy 397.913606 -31.158688) (xy 397.682974 -31.38932) (xy 396.086838 -31.38932)
			(xy 395.856206 -31.158688) (xy 176.913794 -31.158688) (xy 176.683162 -31.38932) (xy 175.087026 -31.38932)
			(xy 174.856394 -31.158688) (xy 6.758432 -31.158688) (xy 6.758432 -32.095186) (xy 6.75903 -32.128484)
			(xy 6.761875 -32.149288) (xy 170.056302 -32.149288) (xy 170.056302 -31.823152) (xy 170.286934 -31.59252)
			(xy 171.88307 -31.59252) (xy 172.113702 -31.823152) (xy 172.113702 -31.844488) (xy 191.48044 -31.844488)
			(xy 191.48044 -31.518352) (xy 191.711072 -31.28772) (xy 193.307208 -31.28772) (xy 193.53784 -31.518352)
			(xy 193.53784 -31.844488) (xy 193.307208 -32.07512) (xy 191.711072 -32.07512) (xy 191.48044 -31.844488)
			(xy 172.113702 -31.844488) (xy 172.113702 -32.149288) (xy 391.056114 -32.149288) (xy 391.056114 -31.823152)
			(xy 391.286746 -31.59252) (xy 392.882882 -31.59252) (xy 393.113514 -31.823152) (xy 393.113514 -31.844488)
			(xy 412.480252 -31.844488) (xy 412.480252 -31.518352) (xy 412.710884 -31.28772) (xy 414.30702 -31.28772)
			(xy 414.537652 -31.518352) (xy 414.537652 -31.844488) (xy 414.30702 -32.07512) (xy 412.710884 -32.07512)
			(xy 412.480252 -31.844488) (xy 393.113514 -31.844488) (xy 393.113514 -32.149288) (xy 392.882882 -32.37992)
			(xy 391.286746 -32.37992) (xy 391.056114 -32.149288) (xy 172.113702 -32.149288) (xy 171.88307 -32.37992)
			(xy 170.286934 -32.37992) (xy 170.056302 -32.149288) (xy 6.761875 -32.149288) (xy 6.768053 -32.194467)
			(xy 6.785895 -32.258629) (xy 6.81223 -32.319798) (xy 6.846577 -32.376855) (xy 6.888306 -32.428757)
			(xy 6.912102 -32.452056) (xy 6.970087 -32.507573) (xy 7.081498 -32.623175) (xy 7.187504 -32.743753)
			(xy 7.287884 -32.869054) (xy 7.382426 -32.998816) (xy 7.470933 -33.132768) (xy 7.553219 -33.270628)
			(xy 7.629113 -33.412108) (xy 7.664196 -33.484312) (xy 7.673594 -33.50387) (xy 7.801864 -33.63214)
			(xy 7.801864 -33.639119) (xy 165.265595 -33.639119) (xy 165.265595 -33.540833) (xy 165.273504 -33.442866)
			(xy 165.28927 -33.345853) (xy 165.312791 -33.250424) (xy 165.343915 -33.157196) (xy 165.38244 -33.066775)
			(xy 165.428115 -32.979748) (xy 165.480646 -32.896677) (xy 165.53969 -32.818104) (xy 165.604865 -32.744536)
			(xy 165.675749 -32.676451) (xy 165.751882 -32.61429) (xy 165.832769 -32.558458) (xy 165.917887 -32.509315)
			(xy 166.006684 -32.467181) (xy 166.098582 -32.432328) (xy 166.192988 -32.404983) (xy 166.289287 -32.385324)
			(xy 166.386856 -32.373477) (xy 166.485062 -32.369519) (xy 166.583268 -32.373477) (xy 166.680837 -32.385324)
			(xy 166.777136 -32.404983) (xy 166.871542 -32.432328) (xy 166.96344 -32.467181) (xy 167.052237 -32.509315)
			(xy 167.137355 -32.558458) (xy 167.218242 -32.61429) (xy 167.294375 -32.676451) (xy 167.365259 -32.744536)
			(xy 167.430434 -32.818104) (xy 167.489478 -32.896677) (xy 167.542009 -32.979748) (xy 167.587684 -33.066775)
			(xy 167.593944 -33.081468) (xy 172.481748 -33.081468) (xy 172.481748 -32.755332) (xy 172.71238 -32.5247)
			(xy 174.308516 -32.5247) (xy 174.539148 -32.755332) (xy 174.539148 -33.081468) (xy 174.308516 -33.3121)
			(xy 172.71238 -33.3121) (xy 172.481748 -33.081468) (xy 167.593944 -33.081468) (xy 167.626209 -33.157196)
			(xy 167.657333 -33.250424) (xy 167.680854 -33.345853) (xy 167.69662 -33.442866) (xy 167.704529 -33.540833)
			(xy 167.705024 -33.589976) (xy 167.704529 -33.639119) (xy 167.704526 -33.63915) (xy 177.264809 -33.63915)
			(xy 177.264809 -33.540802) (xy 177.272723 -33.442774) (xy 177.288499 -33.345701) (xy 177.312035 -33.250211)
			(xy 177.343178 -33.156926) (xy 177.381727 -33.066448) (xy 177.427431 -32.979366) (xy 177.479994 -32.896244)
			(xy 177.539075 -32.817621) (xy 177.604292 -32.744008) (xy 177.67522 -32.67588) (xy 177.7514 -32.613681)
			(xy 177.832338 -32.557813) (xy 177.917509 -32.50864) (xy 178.006361 -32.466479) (xy 178.098317 -32.431605)
			(xy 178.192781 -32.404243) (xy 178.289141 -32.384571) (xy 178.386771 -32.372717) (xy 178.485038 -32.368757)
			(xy 178.583305 -32.372717) (xy 178.680935 -32.384571) (xy 178.777295 -32.404243) (xy 178.871759 -32.431605)
			(xy 178.963715 -32.466479) (xy 179.052567 -32.50864) (xy 179.137738 -32.557813) (xy 179.218676 -32.613681)
			(xy 179.294856 -32.67588) (xy 179.365784 -32.744008) (xy 179.431001 -32.817621) (xy 179.490082 -32.896244)
			(xy 179.542645 -32.979366) (xy 179.588349 -33.066448) (xy 179.626898 -33.156926) (xy 179.658041 -33.250211)
			(xy 179.681577 -33.345701) (xy 179.697353 -33.442774) (xy 179.705267 -33.540802) (xy 179.705762 -33.589976)
			(xy 179.705267 -33.639119) (xy 184.275463 -33.639119) (xy 184.275463 -33.540833) (xy 184.283372 -33.442866)
			(xy 184.299138 -33.345853) (xy 184.322659 -33.250424) (xy 184.353783 -33.157196) (xy 184.392308 -33.066775)
			(xy 184.437983 -32.979748) (xy 184.490514 -32.896677) (xy 184.549558 -32.818104) (xy 184.614733 -32.744536)
			(xy 184.685617 -32.676451) (xy 184.76175 -32.61429) (xy 184.842637 -32.558458) (xy 184.927755 -32.509315)
			(xy 185.016552 -32.467181) (xy 185.10845 -32.432328) (xy 185.202856 -32.404983) (xy 185.299155 -32.385324)
			(xy 185.396724 -32.373477) (xy 185.49493 -32.369519) (xy 185.593136 -32.373477) (xy 185.690705 -32.385324)
			(xy 185.787004 -32.404983) (xy 185.88141 -32.432328) (xy 185.973308 -32.467181) (xy 186.062105 -32.509315)
			(xy 186.147223 -32.558458) (xy 186.22811 -32.61429) (xy 186.304243 -32.676451) (xy 186.375127 -32.744536)
			(xy 186.440302 -32.818104) (xy 186.499346 -32.896677) (xy 186.551877 -32.979748) (xy 186.597552 -33.066775)
			(xy 186.636077 -33.157196) (xy 186.667201 -33.250424) (xy 186.690722 -33.345853) (xy 186.706488 -33.442866)
			(xy 186.714397 -33.540833) (xy 186.714892 -33.589976) (xy 186.714397 -33.639119) (xy 186.714394 -33.63915)
			(xy 196.274677 -33.63915) (xy 196.274677 -33.540802) (xy 196.282591 -33.442774) (xy 196.298367 -33.345701)
			(xy 196.321903 -33.250211) (xy 196.353046 -33.156926) (xy 196.391595 -33.066448) (xy 196.437299 -32.979366)
			(xy 196.489862 -32.896244) (xy 196.548943 -32.817621) (xy 196.61416 -32.744008) (xy 196.685088 -32.67588)
			(xy 196.761268 -32.613681) (xy 196.842206 -32.557813) (xy 196.927377 -32.50864) (xy 197.016229 -32.466479)
			(xy 197.108185 -32.431605) (xy 197.202649 -32.404243) (xy 197.299009 -32.384571) (xy 197.396639 -32.372717)
			(xy 197.494906 -32.368757) (xy 197.593173 -32.372717) (xy 197.690803 -32.384571) (xy 197.787163 -32.404243)
			(xy 197.881627 -32.431605) (xy 197.973583 -32.466479) (xy 198.062435 -32.50864) (xy 198.147606 -32.557813)
			(xy 198.228544 -32.613681) (xy 198.304724 -32.67588) (xy 198.375652 -32.744008) (xy 198.440869 -32.817621)
			(xy 198.49995 -32.896244) (xy 198.552513 -32.979366) (xy 198.598217 -33.066448) (xy 198.636766 -33.156926)
			(xy 198.667909 -33.250211) (xy 198.691445 -33.345701) (xy 198.707221 -33.442774) (xy 198.715135 -33.540802)
			(xy 198.71563 -33.589976) (xy 198.715135 -33.639119) (xy 386.265407 -33.639119) (xy 386.265407 -33.540833)
			(xy 386.273316 -33.442866) (xy 386.289082 -33.345853) (xy 386.312603 -33.250424) (xy 386.343727 -33.157196)
			(xy 386.382252 -33.066775) (xy 386.427927 -32.979748) (xy 386.480458 -32.896677) (xy 386.539502 -32.818104)
			(xy 386.604677 -32.744536) (xy 386.675561 -32.676451) (xy 386.751694 -32.61429) (xy 386.832581 -32.558458)
			(xy 386.917699 -32.509315) (xy 387.006496 -32.467181) (xy 387.098394 -32.432328) (xy 387.1928 -32.404983)
			(xy 387.289099 -32.385324) (xy 387.386668 -32.373477) (xy 387.484874 -32.369519) (xy 387.58308 -32.373477)
			(xy 387.680649 -32.385324) (xy 387.776948 -32.404983) (xy 387.871354 -32.432328) (xy 387.963252 -32.467181)
			(xy 388.052049 -32.509315) (xy 388.137167 -32.558458) (xy 388.218054 -32.61429) (xy 388.294187 -32.676451)
			(xy 388.365071 -32.744536) (xy 388.430246 -32.818104) (xy 388.48929 -32.896677) (xy 388.541821 -32.979748)
			(xy 388.587496 -33.066775) (xy 388.593756 -33.081468) (xy 393.48156 -33.081468) (xy 393.48156 -32.755332)
			(xy 393.712192 -32.5247) (xy 395.308328 -32.5247) (xy 395.53896 -32.755332) (xy 395.53896 -33.081468)
			(xy 395.308328 -33.3121) (xy 393.712192 -33.3121) (xy 393.48156 -33.081468) (xy 388.593756 -33.081468)
			(xy 388.626021 -33.157196) (xy 388.657145 -33.250424) (xy 388.680666 -33.345853) (xy 388.696432 -33.442866)
			(xy 388.704341 -33.540833) (xy 388.704836 -33.589976) (xy 388.704341 -33.639119) (xy 388.704338 -33.63915)
			(xy 398.264621 -33.63915) (xy 398.264621 -33.540802) (xy 398.272535 -33.442774) (xy 398.288311 -33.345701)
			(xy 398.311847 -33.250211) (xy 398.34299 -33.156926) (xy 398.381539 -33.066448) (xy 398.427243 -32.979366)
			(xy 398.479806 -32.896244) (xy 398.538887 -32.817621) (xy 398.604104 -32.744008) (xy 398.675032 -32.67588)
			(xy 398.751212 -32.613681) (xy 398.83215 -32.557813) (xy 398.917321 -32.50864) (xy 399.006173 -32.466479)
			(xy 399.098129 -32.431605) (xy 399.192593 -32.404243) (xy 399.288953 -32.384571) (xy 399.386583 -32.372717)
			(xy 399.48485 -32.368757) (xy 399.583117 -32.372717) (xy 399.680747 -32.384571) (xy 399.777107 -32.404243)
			(xy 399.871571 -32.431605) (xy 399.963527 -32.466479) (xy 400.052379 -32.50864) (xy 400.13755 -32.557813)
			(xy 400.218488 -32.613681) (xy 400.294668 -32.67588) (xy 400.365596 -32.744008) (xy 400.430813 -32.817621)
			(xy 400.489894 -32.896244) (xy 400.542457 -32.979366) (xy 400.588161 -33.066448) (xy 400.62671 -33.156926)
			(xy 400.657853 -33.250211) (xy 400.681389 -33.345701) (xy 400.697165 -33.442774) (xy 400.705079 -33.540802)
			(xy 400.705574 -33.589976) (xy 400.705079 -33.639119) (xy 405.275529 -33.639119) (xy 405.275529 -33.540833)
			(xy 405.283438 -33.442866) (xy 405.299204 -33.345853) (xy 405.322725 -33.250424) (xy 405.353849 -33.157196)
			(xy 405.392374 -33.066775) (xy 405.438049 -32.979748) (xy 405.49058 -32.896677) (xy 405.549624 -32.818104)
			(xy 405.614799 -32.744536) (xy 405.685683 -32.676451) (xy 405.761816 -32.61429) (xy 405.842703 -32.558458)
			(xy 405.927821 -32.509315) (xy 406.016618 -32.467181) (xy 406.108516 -32.432328) (xy 406.202922 -32.404983)
			(xy 406.299221 -32.385324) (xy 406.39679 -32.373477) (xy 406.494996 -32.369519) (xy 406.593202 -32.373477)
			(xy 406.690771 -32.385324) (xy 406.78707 -32.404983) (xy 406.881476 -32.432328) (xy 406.973374 -32.467181)
			(xy 407.062171 -32.509315) (xy 407.147289 -32.558458) (xy 407.228176 -32.61429) (xy 407.304309 -32.676451)
			(xy 407.375193 -32.744536) (xy 407.440368 -32.818104) (xy 407.499412 -32.896677) (xy 407.551943 -32.979748)
			(xy 407.597618 -33.066775) (xy 407.636143 -33.157196) (xy 407.667267 -33.250424) (xy 407.690788 -33.345853)
			(xy 407.706554 -33.442866) (xy 407.714463 -33.540833) (xy 407.714958 -33.589976) (xy 407.714463 -33.639119)
			(xy 407.71446 -33.63915) (xy 417.274743 -33.63915) (xy 417.274743 -33.540802) (xy 417.282657 -33.442774)
			(xy 417.298433 -33.345701) (xy 417.321969 -33.250211) (xy 417.353112 -33.156926) (xy 417.391661 -33.066448)
			(xy 417.437365 -32.979366) (xy 417.489928 -32.896244) (xy 417.549009 -32.817621) (xy 417.614226 -32.744008)
			(xy 417.685154 -32.67588) (xy 417.761334 -32.613681) (xy 417.842272 -32.557813) (xy 417.927443 -32.50864)
			(xy 418.016295 -32.466479) (xy 418.108251 -32.431605) (xy 418.202715 -32.404243) (xy 418.299075 -32.384571)
			(xy 418.396705 -32.372717) (xy 418.494972 -32.368757) (xy 418.593239 -32.372717) (xy 418.690869 -32.384571)
			(xy 418.787229 -32.404243) (xy 418.881693 -32.431605) (xy 418.973649 -32.466479) (xy 419.062501 -32.50864)
			(xy 419.147672 -32.557813) (xy 419.22861 -32.613681) (xy 419.30479 -32.67588) (xy 419.375718 -32.744008)
			(xy 419.440935 -32.817621) (xy 419.500016 -32.896244) (xy 419.552579 -32.979366) (xy 419.598283 -33.066448)
			(xy 419.636832 -33.156926) (xy 419.667975 -33.250211) (xy 419.691511 -33.345701) (xy 419.707287 -33.442774)
			(xy 419.715201 -33.540802) (xy 419.715696 -33.589976) (xy 419.715201 -33.63915) (xy 419.707287 -33.737178)
			(xy 419.691511 -33.834251) (xy 419.667975 -33.929741) (xy 419.636832 -34.023026) (xy 419.598283 -34.113504)
			(xy 419.552579 -34.200586) (xy 419.500016 -34.283708) (xy 419.440935 -34.362331) (xy 419.375718 -34.435944)
			(xy 419.30479 -34.504072) (xy 419.22861 -34.566271) (xy 419.147672 -34.622139) (xy 419.062501 -34.671312)
			(xy 418.973649 -34.713473) (xy 418.881693 -34.748347) (xy 418.787229 -34.775709) (xy 418.690869 -34.795381)
			(xy 418.593239 -34.807235) (xy 418.494972 -34.811196) (xy 418.396705 -34.807235) (xy 418.299075 -34.795381)
			(xy 418.202715 -34.775709) (xy 418.108251 -34.748347) (xy 418.016295 -34.713473) (xy 417.927443 -34.671312)
			(xy 417.842272 -34.622139) (xy 417.761334 -34.566271) (xy 417.685154 -34.504072) (xy 417.614226 -34.435944)
			(xy 417.549009 -34.362331) (xy 417.489928 -34.283708) (xy 417.437365 -34.200586) (xy 417.391661 -34.113504)
			(xy 417.353112 -34.023026) (xy 417.321969 -33.929741) (xy 417.298433 -33.834251) (xy 417.282657 -33.737178)
			(xy 417.274743 -33.63915) (xy 407.71446 -33.63915) (xy 407.706554 -33.737086) (xy 407.690788 -33.834099)
			(xy 407.667267 -33.929528) (xy 407.636143 -34.022756) (xy 407.597618 -34.113177) (xy 407.551943 -34.200205)
			(xy 407.499412 -34.283275) (xy 407.440368 -34.361848) (xy 407.375193 -34.435416) (xy 407.304309 -34.503501)
			(xy 407.228176 -34.565662) (xy 407.147289 -34.621494) (xy 407.062171 -34.670637) (xy 406.973374 -34.712771)
			(xy 406.881476 -34.747624) (xy 406.78707 -34.774969) (xy 406.690771 -34.794628) (xy 406.593202 -34.806475)
			(xy 406.494996 -34.810433) (xy 406.39679 -34.806475) (xy 406.299221 -34.794628) (xy 406.202922 -34.774969)
			(xy 406.108516 -34.747624) (xy 406.016618 -34.712771) (xy 405.927821 -34.670637) (xy 405.842703 -34.621494)
			(xy 405.761816 -34.565662) (xy 405.685683 -34.503501) (xy 405.614799 -34.435416) (xy 405.549624 -34.361848)
			(xy 405.49058 -34.283275) (xy 405.438049 -34.200205) (xy 405.392374 -34.113177) (xy 405.353849 -34.022756)
			(xy 405.322725 -33.929528) (xy 405.299204 -33.834099) (xy 405.283438 -33.737086) (xy 405.275529 -33.639119)
			(xy 400.705079 -33.639119) (xy 400.705079 -33.63915) (xy 400.697165 -33.737178) (xy 400.681389 -33.834251)
			(xy 400.657853 -33.929741) (xy 400.62671 -34.023026) (xy 400.588161 -34.113504) (xy 400.542457 -34.200586)
			(xy 400.489894 -34.283708) (xy 400.430813 -34.362331) (xy 400.365596 -34.435944) (xy 400.294668 -34.504072)
			(xy 400.218488 -34.566271) (xy 400.13755 -34.622139) (xy 400.052379 -34.671312) (xy 399.963527 -34.713473)
			(xy 399.871571 -34.748347) (xy 399.777107 -34.775709) (xy 399.680747 -34.795381) (xy 399.583117 -34.807235)
			(xy 399.48485 -34.811196) (xy 399.386583 -34.807235) (xy 399.288953 -34.795381) (xy 399.192593 -34.775709)
			(xy 399.098129 -34.748347) (xy 399.006173 -34.713473) (xy 398.917321 -34.671312) (xy 398.83215 -34.622139)
			(xy 398.751212 -34.566271) (xy 398.675032 -34.504072) (xy 398.604104 -34.435944) (xy 398.538887 -34.362331)
			(xy 398.479806 -34.283708) (xy 398.427243 -34.200586) (xy 398.381539 -34.113504) (xy 398.34299 -34.023026)
			(xy 398.311847 -33.929741) (xy 398.288311 -33.834251) (xy 398.272535 -33.737178) (xy 398.264621 -33.63915)
			(xy 388.704338 -33.63915) (xy 388.696432 -33.737086) (xy 388.680666 -33.834099) (xy 388.657145 -33.929528)
			(xy 388.626021 -34.022756) (xy 388.587496 -34.113177) (xy 388.541821 -34.200205) (xy 388.48929 -34.283275)
			(xy 388.430246 -34.361848) (xy 388.365071 -34.435416) (xy 388.294187 -34.503501) (xy 388.218054 -34.565662)
			(xy 388.137167 -34.621494) (xy 388.052049 -34.670637) (xy 387.963252 -34.712771) (xy 387.871354 -34.747624)
			(xy 387.776948 -34.774969) (xy 387.680649 -34.794628) (xy 387.58308 -34.806475) (xy 387.484874 -34.810433)
			(xy 387.386668 -34.806475) (xy 387.289099 -34.794628) (xy 387.1928 -34.774969) (xy 387.098394 -34.747624)
			(xy 387.006496 -34.712771) (xy 386.917699 -34.670637) (xy 386.832581 -34.621494) (xy 386.751694 -34.565662)
			(xy 386.675561 -34.503501) (xy 386.604677 -34.435416) (xy 386.539502 -34.361848) (xy 386.480458 -34.283275)
			(xy 386.427927 -34.200205) (xy 386.382252 -34.113177) (xy 386.343727 -34.022756) (xy 386.312603 -33.929528)
			(xy 386.289082 -33.834099) (xy 386.273316 -33.737086) (xy 386.265407 -33.639119) (xy 198.715135 -33.639119)
			(xy 198.715135 -33.63915) (xy 198.707221 -33.737178) (xy 198.691445 -33.834251) (xy 198.667909 -33.929741)
			(xy 198.636766 -34.023026) (xy 198.598217 -34.113504) (xy 198.552513 -34.200586) (xy 198.49995 -34.283708)
			(xy 198.440869 -34.362331) (xy 198.375652 -34.435944) (xy 198.304724 -34.504072) (xy 198.228544 -34.566271)
			(xy 198.147606 -34.622139) (xy 198.062435 -34.671312) (xy 197.973583 -34.713473) (xy 197.881627 -34.748347)
			(xy 197.787163 -34.775709) (xy 197.690803 -34.795381) (xy 197.593173 -34.807235) (xy 197.494906 -34.811196)
			(xy 197.396639 -34.807235) (xy 197.299009 -34.795381) (xy 197.202649 -34.775709) (xy 197.108185 -34.748347)
			(xy 197.016229 -34.713473) (xy 196.927377 -34.671312) (xy 196.842206 -34.622139) (xy 196.761268 -34.566271)
			(xy 196.685088 -34.504072) (xy 196.61416 -34.435944) (xy 196.548943 -34.362331) (xy 196.489862 -34.283708)
			(xy 196.437299 -34.200586) (xy 196.391595 -34.113504) (xy 196.353046 -34.023026) (xy 196.321903 -33.929741)
			(xy 196.298367 -33.834251) (xy 196.282591 -33.737178) (xy 196.274677 -33.63915) (xy 186.714394 -33.63915)
			(xy 186.706488 -33.737086) (xy 186.690722 -33.834099) (xy 186.667201 -33.929528) (xy 186.636077 -34.022756)
			(xy 186.597552 -34.113177) (xy 186.551877 -34.200205) (xy 186.499346 -34.283275) (xy 186.440302 -34.361848)
			(xy 186.375127 -34.435416) (xy 186.304243 -34.503501) (xy 186.22811 -34.565662) (xy 186.147223 -34.621494)
			(xy 186.062105 -34.670637) (xy 185.973308 -34.712771) (xy 185.88141 -34.747624) (xy 185.787004 -34.774969)
			(xy 185.690705 -34.794628) (xy 185.593136 -34.806475) (xy 185.49493 -34.810433) (xy 185.396724 -34.806475)
			(xy 185.299155 -34.794628) (xy 185.202856 -34.774969) (xy 185.10845 -34.747624) (xy 185.016552 -34.712771)
			(xy 184.927755 -34.670637) (xy 184.842637 -34.621494) (xy 184.76175 -34.565662) (xy 184.685617 -34.503501)
			(xy 184.614733 -34.435416) (xy 184.549558 -34.361848) (xy 184.490514 -34.283275) (xy 184.437983 -34.200205)
			(xy 184.392308 -34.113177) (xy 184.353783 -34.022756) (xy 184.322659 -33.929528) (xy 184.299138 -33.834099)
			(xy 184.283372 -33.737086) (xy 184.275463 -33.639119) (xy 179.705267 -33.639119) (xy 179.705267 -33.63915)
			(xy 179.697353 -33.737178) (xy 179.681577 -33.834251) (xy 179.658041 -33.929741) (xy 179.626898 -34.023026)
			(xy 179.588349 -34.113504) (xy 179.542645 -34.200586) (xy 179.490082 -34.283708) (xy 179.431001 -34.362331)
			(xy 179.365784 -34.435944) (xy 179.294856 -34.504072) (xy 179.218676 -34.566271) (xy 179.137738 -34.622139)
			(xy 179.052567 -34.671312) (xy 178.963715 -34.713473) (xy 178.871759 -34.748347) (xy 178.777295 -34.775709)
			(xy 178.680935 -34.795381) (xy 178.583305 -34.807235) (xy 178.485038 -34.811196) (xy 178.386771 -34.807235)
			(xy 178.289141 -34.795381) (xy 178.192781 -34.775709) (xy 178.098317 -34.748347) (xy 178.006361 -34.713473)
			(xy 177.917509 -34.671312) (xy 177.832338 -34.622139) (xy 177.7514 -34.566271) (xy 177.67522 -34.504072)
			(xy 177.604292 -34.435944) (xy 177.539075 -34.362331) (xy 177.479994 -34.283708) (xy 177.427431 -34.200586)
			(xy 177.381727 -34.113504) (xy 177.343178 -34.023026) (xy 177.312035 -33.929741) (xy 177.288499 -33.834251)
			(xy 177.272723 -33.737178) (xy 177.264809 -33.63915) (xy 167.704526 -33.63915) (xy 167.69662 -33.737086)
			(xy 167.680854 -33.834099) (xy 167.657333 -33.929528) (xy 167.626209 -34.022756) (xy 167.587684 -34.113177)
			(xy 167.542009 -34.200205) (xy 167.489478 -34.283275) (xy 167.430434 -34.361848) (xy 167.365259 -34.435416)
			(xy 167.294375 -34.503501) (xy 167.218242 -34.565662) (xy 167.137355 -34.621494) (xy 167.052237 -34.670637)
			(xy 166.96344 -34.712771) (xy 166.871542 -34.747624) (xy 166.777136 -34.774969) (xy 166.680837 -34.794628)
			(xy 166.583268 -34.806475) (xy 166.485062 -34.810433) (xy 166.386856 -34.806475) (xy 166.289287 -34.794628)
			(xy 166.192988 -34.774969) (xy 166.098582 -34.747624) (xy 166.006684 -34.712771) (xy 165.917887 -34.670637)
			(xy 165.832769 -34.621494) (xy 165.751882 -34.565662) (xy 165.675749 -34.503501) (xy 165.604865 -34.435416)
			(xy 165.53969 -34.361848) (xy 165.480646 -34.283275) (xy 165.428115 -34.200205) (xy 165.38244 -34.113177)
			(xy 165.343915 -34.022756) (xy 165.312791 -33.929528) (xy 165.28927 -33.834099) (xy 165.273504 -33.737086)
			(xy 165.265595 -33.639119) (xy 7.801864 -33.639119) (xy 7.801864 -33.813496) (xy 7.808976 -33.83407)
			(xy 7.836708 -33.914308) (xy 7.885316 -34.07699) (xy 7.925998 -34.241833) (xy 7.958658 -34.40845)
			(xy 7.983221 -34.576452) (xy 7.999628 -34.745446) (xy 8.007841 -34.915036) (xy 8.007841 -35.084824)
			(xy 7.999628 -35.254414) (xy 7.983221 -35.423408) (xy 7.958658 -35.59141) (xy 7.925998 -35.758027)
			(xy 7.885316 -35.92287) (xy 7.836708 -36.085552) (xy 7.808976 -36.16579) (xy 7.801864 -36.186364)
			(xy 7.801864 -36.367974) (xy 7.67334 -36.496498) (xy 7.663942 -36.516056) (xy 7.626819 -36.592356)
			(xy 7.546175 -36.74167) (xy 7.458407 -36.88691) (xy 7.363719 -37.027738) (xy 7.262334 -37.163823)
			(xy 7.154488 -37.294847) (xy 7.040434 -37.420504) (xy 6.960886 -37.500052) (xy 9.403341 -37.500052)
			(xy 9.407346 -37.412144) (xy 9.419329 -37.324964) (xy 9.439189 -37.239235) (xy 9.466764 -37.155667)
			(xy 9.501823 -37.074953) (xy 9.544076 -36.997761) (xy 9.593174 -36.924732) (xy 9.64871 -36.85647)
			(xy 9.710222 -36.79354) (xy 9.777203 -36.736466) (xy 9.849096 -36.685718) (xy 9.925305 -36.641718)
			(xy 10.0052 -36.604831) (xy 10.088119 -36.575362) (xy 10.173374 -36.553555) (xy 10.260258 -36.539591)
			(xy 10.348052 -36.533585) (xy 10.436029 -36.535589) (xy 10.523459 -36.545584) (xy 10.609618 -36.563488)
			(xy 10.693792 -36.589152) (xy 10.775283 -36.622365) (xy 10.853417 -36.662851) (xy 10.927545 -36.710273)
			(xy 10.997053 -36.76424) (xy 11.061367 -36.824305) (xy 11.119951 -36.889969) (xy 11.172322 -36.960688)
			(xy 11.218045 -37.035876) (xy 11.256742 -37.114911) (xy 11.288091 -37.197137) (xy 11.311833 -37.281873)
			(xy 11.327771 -37.368417) (xy 11.335773 -37.456052) (xy 11.336274 -37.500052) (xy 11.335773 -37.544052)
			(xy 11.327771 -37.631687) (xy 11.311833 -37.718231) (xy 11.288091 -37.802967) (xy 11.256742 -37.885193)
			(xy 11.218045 -37.964228) (xy 11.172322 -38.039416) (xy 11.119951 -38.110135) (xy 11.061367 -38.175799)
			(xy 10.997053 -38.235864) (xy 10.927545 -38.289831) (xy 10.853417 -38.337253) (xy 10.775283 -38.377739)
			(xy 10.693792 -38.410952) (xy 10.609618 -38.436616) (xy 10.523459 -38.45452) (xy 10.436029 -38.464515)
			(xy 10.348052 -38.466519) (xy 10.260258 -38.460513) (xy 10.173374 -38.446549) (xy 10.088119 -38.424742)
			(xy 10.0052 -38.395273) (xy 9.925305 -38.358386) (xy 9.849096 -38.314386) (xy 9.777203 -38.263638)
			(xy 9.710222 -38.206564) (xy 9.64871 -38.143634) (xy 9.593174 -38.075372) (xy 9.544076 -38.002343)
			(xy 9.501823 -37.925151) (xy 9.466764 -37.844437) (xy 9.439189 -37.760869) (xy 9.419329 -37.67514)
			(xy 9.407346 -37.58796) (xy 9.403341 -37.500052) (xy 6.960886 -37.500052) (xy 6.920438 -37.5405)
			(xy 6.794781 -37.654554) (xy 6.663757 -37.762401) (xy 6.527672 -37.863786) (xy 6.386845 -37.958474)
			(xy 6.241604 -38.046242) (xy 6.092291 -38.126887) (xy 6.01599 -38.164008) (xy 5.996432 -38.173406)
			(xy 5.867654 -38.302184) (xy 5.685536 -38.302184) (xy 5.665216 -38.309296) (xy 5.58501 -38.337004)
			(xy 5.422395 -38.385567) (xy 5.257623 -38.426211) (xy 5.091078 -38.458842) (xy 4.92315 -38.483381)
			(xy 4.754232 -38.499773) (xy 4.58472 -38.507978) (xy 4.415008 -38.507978) (xy 4.245496 -38.499773)
			(xy 4.076578 -38.483381) (xy 3.90865 -38.458842) (xy 3.742105 -38.426211) (xy 3.577333 -38.385567)
			(xy 3.414718 -38.337004) (xy 3.334512 -38.309296) (xy 3.314192 -38.302184) (xy 3.132074 -38.302184)
			(xy 3.003296 -38.173406) (xy 2.983738 -38.164008) (xy 2.907438 -38.126885) (xy 2.758124 -38.046241)
			(xy 2.612884 -37.958473) (xy 2.472056 -37.863785) (xy 2.335971 -37.7624) (xy 2.204947 -37.654554)
			(xy 2.07929 -37.5405) (xy 1.959294 -37.420504) (xy 1.845239 -37.294847) (xy 1.737393 -37.163823)
			(xy 1.636008 -37.027738) (xy 1.54132 -36.886911) (xy 1.453552 -36.74167) (xy 1.372907 -36.592357)
			(xy 1.335786 -36.516056) (xy 1.326388 -36.496498) (xy 1.197864 -36.367974) (xy 1.197864 -36.186364)
			(xy 1.190752 -36.16579) (xy 1.16302 -36.085552) (xy 1.114412 -35.92287) (xy 1.07373 -35.758027) (xy 1.04107 -35.59141)
			(xy 1.016507 -35.423408) (xy 1.000101 -35.254414) (xy 0.991888 -35.084824) (xy 0.509016 -35.084824)
			(xy 0.509016 -46.4566) (xy 0.509511 -46.473254) (xy 0.518132 -46.505427) (xy 0.534787 -46.534272)
			(xy 0.558341 -46.557823) (xy 0.587188 -46.574474) (xy 0.619362 -46.583091) (xy 0.636016 -46.5836)
			(xy 9.814052 -46.5836) (xy 9.830711 -46.583111) (xy 9.862896 -46.574498) (xy 9.891754 -46.557847)
			(xy 9.915317 -46.534292) (xy 9.93198 -46.50544) (xy 9.940605 -46.473259) (xy 9.941052 -46.4566) (xy 9.941052 -42.649902)
			(xy 9.941539 -42.609005) (xy 9.949314 -42.52758) (xy 9.964793 -42.447264) (xy 9.987838 -42.368782)
			(xy 10.018238 -42.292847) (xy 10.055718 -42.220145) (xy 10.09994 -42.151334) (xy 10.150502 -42.087039)
			(xy 10.206947 -42.027842) (xy 10.268763 -41.974278) (xy 10.335391 -41.926832) (xy 10.406227 -41.885935)
			(xy 10.480631 -41.851956) (xy 10.557927 -41.825203) (xy 10.637416 -41.80592) (xy 10.718378 -41.794279)
			(xy 10.80008 -41.790387) (xy 10.881782 -41.794279) (xy 10.962744 -41.80592) (xy 11.042233 -41.825203)
			(xy 11.119529 -41.851956) (xy 11.193933 -41.885935) (xy 11.264769 -41.926832) (xy 11.331397 -41.974278)
			(xy 11.393213 -42.027842) (xy 11.449658 -42.087039) (xy 11.50022 -42.151334) (xy 11.544442 -42.220145)
			(xy 11.581922 -42.292847) (xy 11.612322 -42.368782) (xy 11.635367 -42.447264) (xy 11.650846 -42.52758)
			(xy 11.658621 -42.609005) (xy 11.659108 -42.649902) (xy 11.659108 -45.085) (xy 11.659603 -45.101654)
			(xy 11.668224 -45.133828) (xy 11.684879 -45.162674) (xy 11.708432 -45.186226) (xy 11.737279 -45.202879)
			(xy 11.769454 -45.211498) (xy 11.786108 -45.212) (xy 12.032234 -45.212) (xy 12.057634 -45.2374) (xy 18.284698 -45.2374)
			(xy 18.310098 -45.212) (xy 50.320702 -45.212) (xy 50.346102 -45.2374) (xy 51.44389 -45.2374) (xy 51.460546 -45.236907)
			(xy 51.492722 -45.228287) (xy 51.521571 -45.211633) (xy 51.545127 -45.188079) (xy 51.561783 -45.159232)
			(xy 51.570405 -45.127056) (xy 51.57089 -45.1104) (xy 51.57089 -43.319954) (xy 51.571372 -43.266078)
			(xy 51.579063 -43.1586) (xy 51.5944 -43.051944) (xy 51.617308 -42.946655) (xy 51.647668 -42.843268)
			(xy 51.685326 -42.74231) (xy 51.73009 -42.644296) (xy 51.781732 -42.549725) (xy 51.83999 -42.459079)
			(xy 51.904565 -42.372819) (xy 51.975129 -42.291387) (xy 52.051323 -42.215195) (xy 52.132758 -42.144634)
			(xy 52.21902 -42.080061) (xy 52.309668 -42.021807) (xy 52.404241 -41.970168) (xy 52.502256 -41.925407)
			(xy 52.603215 -41.887752) (xy 52.706603 -41.857395) (xy 52.811894 -41.834491) (xy 52.91855 -41.819157)
			(xy 53.026028 -41.811471) (xy 53.079904 -41.81094) (xy 55.0799 -41.81094) (xy 55.133778 -41.811421)
			(xy 55.241259 -41.819108) (xy 55.347919 -41.834443) (xy 55.453212 -41.857348) (xy 55.556603 -41.887705)
			(xy 55.657566 -41.925362) (xy 55.755584 -41.970124) (xy 55.85016 -42.021765) (xy 55.940811 -42.080022)
			(xy 56.027075 -42.144596) (xy 56.108512 -42.21516) (xy 56.184708 -42.291354) (xy 56.255275 -42.372789)
			(xy 56.319852 -42.459051) (xy 56.378111 -42.5497) (xy 56.429755 -42.644274) (xy 56.474521 -42.742292)
			(xy 56.51218 -42.843253) (xy 56.542541 -42.946643) (xy 56.565449 -43.051936) (xy 56.580787 -43.158595)
			(xy 56.588478 -43.266076) (xy 56.588914 -43.319954) (xy 56.588914 -47.585006) (xy 76.302054 -47.585006)
			(xy 76.302054 -47.415312) (xy 76.310259 -47.245817) (xy 76.326651 -47.076917) (xy 76.351191 -46.909008)
			(xy 76.383821 -46.742481) (xy 76.424465 -46.577727) (xy 76.473029 -46.415131) (xy 76.500736 -46.334934)
			(xy 76.507848 -46.31436) (xy 76.507848 -46.132496) (xy 76.636372 -46.003972) (xy 76.64577 -45.984414)
			(xy 76.680844 -45.912205) (xy 76.756744 -45.770729) (xy 76.839035 -45.632872) (xy 76.927545 -45.498923)
			(xy 77.022089 -45.369163) (xy 77.12247 -45.243863) (xy 77.228476 -45.123285) (xy 77.339887 -45.007683)
			(xy 77.397864 -44.952158) (xy 77.421682 -44.928888) (xy 77.463394 -44.876982) (xy 77.497712 -44.819916)
			(xy 77.524005 -44.758738) (xy 77.541792 -44.694568) (xy 77.550747 -44.628583) (xy 77.55128 -44.595288)
			(xy 77.55128 -41.500044) (xy 77.551776 -41.433093) (xy 77.559709 -41.299426) (xy 77.575546 -41.166463)
			(xy 77.599232 -41.034673) (xy 77.630683 -40.904517) (xy 77.669791 -40.776453) (xy 77.716415 -40.65093)
			(xy 77.770395 -40.52839) (xy 77.831538 -40.409263) (xy 77.899632 -40.293967) (xy 77.974436 -40.182908)
			(xy 78.055688 -40.076475) (xy 78.143102 -39.975043) (xy 78.236372 -39.878967) (xy 78.335169 -39.788585)
			(xy 78.439148 -39.704215) (xy 78.547941 -39.626153) (xy 78.661168 -39.554673) (xy 78.778431 -39.490026)
			(xy 78.899318 -39.432439) (xy 79.023404 -39.382115) (xy 79.150253 -39.33923) (xy 79.27942 -39.303935)
			(xy 79.410451 -39.276354) (xy 79.542885 -39.256584) (xy 79.676259 -39.244694) (xy 79.810102 -39.240726)
			(xy 79.943945 -39.244694) (xy 80.077319 -39.256584) (xy 80.209753 -39.276354) (xy 80.340784 -39.303935)
			(xy 80.469951 -39.33923) (xy 80.5968 -39.382115) (xy 80.720886 -39.432439) (xy 80.841773 -39.490026)
			(xy 80.959036 -39.554673) (xy 81.072263 -39.626153) (xy 81.181056 -39.704215) (xy 81.285035 -39.788585)
			(xy 81.383832 -39.878967) (xy 81.477102 -39.975043) (xy 81.564516 -40.076475) (xy 81.645768 -40.182908)
			(xy 81.720572 -40.293967) (xy 81.788666 -40.409263) (xy 81.849809 -40.52839) (xy 81.903789 -40.65093)
			(xy 81.950413 -40.776453) (xy 81.989521 -40.904517) (xy 82.020972 -41.034673) (xy 82.044658 -41.166463)
			(xy 82.060495 -41.299426) (xy 82.068428 -41.433093) (xy 82.068924 -41.500044) (xy 82.068924 -44.595288)
			(xy 82.069462 -44.628581) (xy 82.078427 -44.694561) (xy 82.096221 -44.758725) (xy 82.122519 -44.819898)
			(xy 82.156839 -44.876958) (xy 82.198551 -44.92886) (xy 82.202817 -44.933038) (xy 115.78564 -44.933038)
			(xy 115.78564 -44.805162) (xy 115.793669 -44.677538) (xy 115.809697 -44.55067) (xy 115.833658 -44.425058)
			(xy 115.86546 -44.3012) (xy 115.904976 -44.179582) (xy 115.95205 -44.060685) (xy 116.006497 -43.944979)
			(xy 116.068102 -43.83292) (xy 116.136622 -43.724951) (xy 116.211786 -43.621497) (xy 116.293297 -43.522966)
			(xy 116.380834 -43.429748) (xy 116.474052 -43.342211) (xy 116.572583 -43.2607) (xy 116.676037 -43.185536)
			(xy 116.784006 -43.117016) (xy 116.896065 -43.055411) (xy 117.011771 -43.000964) (xy 117.130668 -42.95389)
			(xy 117.252286 -42.914374) (xy 117.376144 -42.882572) (xy 117.501756 -42.858611) (xy 117.628624 -42.842583)
			(xy 117.756248 -42.834554) (xy 117.884124 -42.834554) (xy 118.011748 -42.842583) (xy 118.138616 -42.858611)
			(xy 118.264228 -42.882572) (xy 118.388086 -42.914374) (xy 118.509704 -42.95389) (xy 118.628601 -43.000964)
			(xy 118.744307 -43.055411) (xy 118.856366 -43.117016) (xy 118.964335 -43.185536) (xy 119.067789 -43.2607)
			(xy 119.16632 -43.342211) (xy 119.259538 -43.429748) (xy 119.347075 -43.522966) (xy 119.428586 -43.621497)
			(xy 119.50375 -43.724951) (xy 119.57227 -43.83292) (xy 119.633875 -43.944979) (xy 119.688322 -44.060685)
			(xy 119.735396 -44.179582) (xy 119.774912 -44.3012) (xy 119.806714 -44.425058) (xy 119.830675 -44.55067)
			(xy 119.846703 -44.677538) (xy 119.854732 -44.805162) (xy 119.855234 -44.8691) (xy 119.854732 -44.932982)
			(xy 127.217418 -44.932982) (xy 127.217418 -44.805218) (xy 127.22544 -44.677705) (xy 127.241453 -44.550948)
			(xy 127.265394 -44.425446) (xy 127.297168 -44.301696) (xy 127.336649 -44.180184) (xy 127.383682 -44.061392)
			(xy 127.438082 -43.945787) (xy 127.499633 -43.833826) (xy 127.568093 -43.725951) (xy 127.643191 -43.622587)
			(xy 127.724631 -43.524142) (xy 127.812092 -43.431006) (xy 127.905228 -43.343545) (xy 128.003673 -43.262105)
			(xy 128.107037 -43.187007) (xy 128.214912 -43.118547) (xy 128.326873 -43.056996) (xy 128.442478 -43.002596)
			(xy 128.56127 -42.955563) (xy 128.682782 -42.916082) (xy 128.806532 -42.884308) (xy 128.932034 -42.860367)
			(xy 129.058791 -42.844354) (xy 129.186304 -42.836332) (xy 129.314068 -42.836332) (xy 129.441581 -42.844354)
			(xy 129.568338 -42.860367) (xy 129.69384 -42.884308) (xy 129.81759 -42.916082) (xy 129.939102 -42.955563)
			(xy 130.057894 -43.002596) (xy 130.173499 -43.056996) (xy 130.28546 -43.118547) (xy 130.393335 -43.187007)
			(xy 130.496699 -43.262105) (xy 130.595144 -43.343545) (xy 130.68828 -43.431006) (xy 130.775741 -43.524142)
			(xy 130.857181 -43.622587) (xy 130.932279 -43.725951) (xy 131.000739 -43.833826) (xy 131.06229 -43.945787)
			(xy 131.11669 -44.061392) (xy 131.163723 -44.180184) (xy 131.203204 -44.301696) (xy 131.234978 -44.425446)
			(xy 131.258919 -44.550948) (xy 131.274932 -44.677705) (xy 131.282954 -44.805218) (xy 131.283456 -44.8691)
			(xy 131.282954 -44.932982) (xy 131.274932 -45.060495) (xy 131.258919 -45.187252) (xy 131.234978 -45.312754)
			(xy 131.203204 -45.436504) (xy 131.163723 -45.558016) (xy 131.11669 -45.676808) (xy 131.06229 -45.792413)
			(xy 131.000739 -45.904374) (xy 130.932279 -46.012249) (xy 130.857181 -46.115613) (xy 130.775741 -46.214058)
			(xy 130.68828 -46.307194) (xy 130.595144 -46.394655) (xy 130.496699 -46.476095) (xy 130.393335 -46.551193)
			(xy 130.28546 -46.619653) (xy 130.173499 -46.681204) (xy 130.057894 -46.735604) (xy 129.939102 -46.782637)
			(xy 129.81759 -46.822118) (xy 129.69384 -46.853892) (xy 129.568338 -46.877833) (xy 129.441581 -46.893846)
			(xy 129.314068 -46.901868) (xy 129.186304 -46.901868) (xy 129.058791 -46.893846) (xy 128.932034 -46.877833)
			(xy 128.806532 -46.853892) (xy 128.682782 -46.822118) (xy 128.56127 -46.782637) (xy 128.442478 -46.735604)
			(xy 128.326873 -46.681204) (xy 128.214912 -46.619653) (xy 128.107037 -46.551193) (xy 128.003673 -46.476095)
			(xy 127.905228 -46.394655) (xy 127.812092 -46.307194) (xy 127.724631 -46.214058) (xy 127.643191 -46.115613)
			(xy 127.568093 -46.012249) (xy 127.499633 -45.904374) (xy 127.438082 -45.792413) (xy 127.383682 -45.676808)
			(xy 127.336649 -45.558016) (xy 127.297168 -45.436504) (xy 127.265394 -45.312754) (xy 127.241453 -45.187252)
			(xy 127.22544 -45.060495) (xy 127.217418 -44.932982) (xy 119.854732 -44.932982) (xy 119.854732 -44.933038)
			(xy 119.846703 -45.060662) (xy 119.830675 -45.18753) (xy 119.806714 -45.313142) (xy 119.774912 -45.437)
			(xy 119.735396 -45.558618) (xy 119.688322 -45.677515) (xy 119.633875 -45.793221) (xy 119.57227 -45.90528)
			(xy 119.50375 -46.013249) (xy 119.428586 -46.116703) (xy 119.347075 -46.215234) (xy 119.259538 -46.308452)
			(xy 119.16632 -46.395989) (xy 119.067789 -46.4775) (xy 118.964335 -46.552664) (xy 118.856366 -46.621184)
			(xy 118.744307 -46.682789) (xy 118.628601 -46.737236) (xy 118.509704 -46.78431) (xy 118.388086 -46.823826)
			(xy 118.264228 -46.855628) (xy 118.138616 -46.879589) (xy 118.011748 -46.895617) (xy 117.884124 -46.903646)
			(xy 117.756248 -46.903646) (xy 117.628624 -46.895617) (xy 117.501756 -46.879589) (xy 117.376144 -46.855628)
			(xy 117.252286 -46.823826) (xy 117.130668 -46.78431) (xy 117.011771 -46.737236) (xy 116.896065 -46.682789)
			(xy 116.784006 -46.621184) (xy 116.676037 -46.552664) (xy 116.572583 -46.4775) (xy 116.474052 -46.395989)
			(xy 116.380834 -46.308452) (xy 116.293297 -46.215234) (xy 116.211786 -46.116703) (xy 116.136622 -46.013249)
			(xy 116.068102 -45.90528) (xy 116.006497 -45.793221) (xy 115.95205 -45.677515) (xy 115.904976 -45.558618)
			(xy 115.86546 -45.437) (xy 115.833658 -45.313142) (xy 115.809697 -45.18753) (xy 115.793669 -45.060662)
			(xy 115.78564 -44.933038) (xy 82.202817 -44.933038) (xy 82.22234 -44.952158) (xy 82.280356 -45.007726)
			(xy 82.391852 -45.123406) (xy 82.497938 -45.244068) (xy 82.59839 -45.369459) (xy 82.692998 -45.499316)
			(xy 82.781564 -45.633366) (xy 82.863902 -45.77133) (xy 82.93984 -45.912917) (xy 82.974942 -45.985176)
			(xy 82.98434 -46.004988) (xy 83.111848 -46.132496) (xy 83.111848 -46.31309) (xy 83.11896 -46.33341)
			(xy 83.146748 -46.41369) (xy 83.19542 -46.576474) (xy 83.236154 -46.741423) (xy 83.268857 -46.90815)
			(xy 83.293451 -47.076265) (xy 83.309879 -47.245373) (xy 83.318102 -47.415078) (xy 83.3181 -47.584982)
			(xy 83.318099 -47.585008) (xy 206.302031 -47.585008) (xy 206.302033 -47.415314) (xy 206.31024 -47.245819)
			(xy 206.326634 -47.076918) (xy 206.351176 -46.909008) (xy 206.383809 -46.742481) (xy 206.424456 -46.577727)
			(xy 206.473022 -46.415131) (xy 206.50073 -46.334934) (xy 206.507842 -46.31436) (xy 206.507842 -46.132242)
			(xy 206.63662 -46.003464) (xy 206.646018 -45.983906) (xy 206.681097 -45.91174) (xy 206.75699 -45.770341)
			(xy 206.839265 -45.632559) (xy 206.92775 -45.49868) (xy 207.022261 -45.368985) (xy 207.1226 -45.243744)
			(xy 207.228557 -45.123219) (xy 207.339912 -45.007662) (xy 207.397858 -44.952158) (xy 207.421671 -44.928869)
			(xy 207.463442 -44.876989) (xy 207.497815 -44.819938) (xy 207.524158 -44.758763) (xy 207.541989 -44.694588)
			(xy 207.55098 -44.628591) (xy 207.551528 -44.595288) (xy 207.551274 -41.500044) (xy 207.551774 -41.433099)
			(xy 207.559713 -41.299445) (xy 207.575555 -41.166495) (xy 207.599246 -41.034718) (xy 207.630701 -40.904576)
			(xy 207.66981 -40.776525) (xy 207.716436 -40.651016) (xy 207.770415 -40.528489) (xy 207.831558 -40.409376)
			(xy 207.89965 -40.294093) (xy 207.974451 -40.183047) (xy 208.055699 -40.076626) (xy 208.143108 -39.975206)
			(xy 208.236372 -39.879142) (xy 208.335163 -39.788771) (xy 208.439133 -39.704411) (xy 208.547919 -39.626358)
			(xy 208.661137 -39.554887) (xy 208.77839 -39.490248) (xy 208.899267 -39.432669) (xy 209.023342 -39.382351)
			(xy 209.15018 -39.339472) (xy 209.279335 -39.304181) (xy 209.410354 -39.276604) (xy 209.542777 -39.256836)
			(xy 209.676138 -39.244947) (xy 209.809969 -39.24098) (xy 209.9438 -39.244947) (xy 210.077161 -39.256836)
			(xy 210.209584 -39.276604) (xy 210.340603 -39.304181) (xy 210.469758 -39.339472) (xy 210.596596 -39.382351)
			(xy 210.720671 -39.432669) (xy 210.841548 -39.490248) (xy 210.958801 -39.554887) (xy 211.072019 -39.626358)
			(xy 211.180805 -39.704411) (xy 211.284775 -39.788771) (xy 211.383566 -39.879142) (xy 211.47683 -39.975206)
			(xy 211.564239 -40.076626) (xy 211.645487 -40.183047) (xy 211.720288 -40.294093) (xy 211.78838 -40.409376)
			(xy 211.849523 -40.528489) (xy 211.903502 -40.651016) (xy 211.950128 -40.776525) (xy 211.989237 -40.904576)
			(xy 212.020692 -41.034718) (xy 212.044383 -41.166495) (xy 212.060225 -41.299445) (xy 212.068164 -41.433099)
			(xy 212.068664 -41.500044) (xy 212.068664 -44.595288) (xy 212.069252 -44.628587) (xy 212.078275 -44.69457)
			(xy 212.096119 -44.758733) (xy 212.122456 -44.819902) (xy 212.156805 -44.876959) (xy 212.198537 -44.928859)
			(xy 212.222334 -44.952158) (xy 212.280334 -45.007691) (xy 212.391793 -45.123311) (xy 212.497842 -45.243912)
			(xy 212.59826 -45.36924) (xy 212.692836 -45.499034) (xy 212.781371 -45.633021) (xy 212.863681 -45.77092)
			(xy 212.939592 -45.912442) (xy 212.974682 -45.984668) (xy 212.98408 -46.00448) (xy 213.111842 -46.132242)
			(xy 213.111842 -46.31309) (xy 213.118954 -46.33341) (xy 213.146742 -46.41369) (xy 213.195414 -46.576474)
			(xy 213.236149 -46.741423) (xy 213.268852 -46.90815) (xy 213.293446 -47.076265) (xy 213.309873 -47.245373)
			(xy 213.318096 -47.415078) (xy 213.318095 -47.584982) (xy 213.318094 -47.585008) (xy 297.302105 -47.585008)
			(xy 297.302106 -47.415314) (xy 297.310314 -47.245819) (xy 297.326708 -47.076918) (xy 297.351249 -46.909008)
			(xy 297.383882 -46.742481) (xy 297.424528 -46.577727) (xy 297.473094 -46.415131) (xy 297.500802 -46.334934)
			(xy 297.507914 -46.31436) (xy 297.507914 -46.132242) (xy 297.636692 -46.003464) (xy 297.64609 -45.983906)
			(xy 297.681156 -45.911733) (xy 297.75705 -45.770335) (xy 297.839327 -45.632553) (xy 297.927814 -45.498675)
			(xy 298.022326 -45.368981) (xy 298.122667 -45.243741) (xy 298.228626 -45.123217) (xy 298.339983 -45.007662)
			(xy 298.39793 -44.952158) (xy 298.421756 -44.928883) (xy 298.463523 -44.876998) (xy 298.497893 -44.819943)
			(xy 298.524234 -44.758766) (xy 298.542062 -44.694589) (xy 298.551052 -44.628592) (xy 298.5516 -44.595288)
			(xy 298.5516 -41.500044) (xy 298.552096 -41.4331) (xy 298.560028 -41.299448) (xy 298.575863 -41.166501)
			(xy 298.599546 -41.034725) (xy 298.630994 -40.904584) (xy 298.670097 -40.776534) (xy 298.716717 -40.651025)
			(xy 298.77069 -40.528499) (xy 298.831827 -40.409386) (xy 298.899913 -40.294103) (xy 298.974708 -40.183056)
			(xy 299.055951 -40.076635) (xy 299.143355 -39.975214) (xy 299.236615 -39.879149) (xy 299.335401 -39.788778)
			(xy 299.439368 -39.704417) (xy 299.548149 -39.626363) (xy 299.661364 -39.554891) (xy 299.778613 -39.490252)
			(xy 299.899486 -39.432671) (xy 300.023558 -39.382353) (xy 300.150393 -39.339473) (xy 300.279545 -39.304182)
			(xy 300.410562 -39.276604) (xy 300.542981 -39.256836) (xy 300.67634 -39.244948) (xy 300.810168 -39.24098)
			(xy 300.943996 -39.244948) (xy 301.077355 -39.256836) (xy 301.209774 -39.276604) (xy 301.340791 -39.304182)
			(xy 301.469943 -39.339473) (xy 301.596778 -39.382353) (xy 301.72085 -39.432671) (xy 301.841723 -39.490252)
			(xy 301.958972 -39.554891) (xy 302.072187 -39.626363) (xy 302.180968 -39.704417) (xy 302.284935 -39.788778)
			(xy 302.383721 -39.879149) (xy 302.476981 -39.975214) (xy 302.564385 -40.076635) (xy 302.645628 -40.183056)
			(xy 302.720423 -40.294103) (xy 302.788509 -40.409386) (xy 302.849646 -40.528499) (xy 302.903619 -40.651025)
			(xy 302.950239 -40.776534) (xy 302.989342 -40.904584) (xy 303.02079 -41.034725) (xy 303.044473 -41.166501)
			(xy 303.060308 -41.299448) (xy 303.06824 -41.4331) (xy 303.068736 -41.500044) (xy 303.068736 -44.595288)
			(xy 303.069332 -44.628586) (xy 303.078355 -44.694569) (xy 303.096197 -44.758732) (xy 303.122533 -44.819901)
			(xy 303.15688 -44.876957) (xy 303.19861 -44.928859) (xy 303.202878 -44.933038) (xy 336.785706 -44.933038)
			(xy 336.785706 -44.805162) (xy 336.793735 -44.677538) (xy 336.809763 -44.55067) (xy 336.833724 -44.425058)
			(xy 336.865526 -44.3012) (xy 336.905042 -44.179582) (xy 336.952116 -44.060685) (xy 337.006563 -43.944979)
			(xy 337.068168 -43.83292) (xy 337.136688 -43.724951) (xy 337.211852 -43.621497) (xy 337.293363 -43.522966)
			(xy 337.3809 -43.429748) (xy 337.474118 -43.342211) (xy 337.572649 -43.2607) (xy 337.676103 -43.185536)
			(xy 337.784072 -43.117016) (xy 337.896131 -43.055411) (xy 338.011837 -43.000964) (xy 338.130734 -42.95389)
			(xy 338.252352 -42.914374) (xy 338.37621 -42.882572) (xy 338.501822 -42.858611) (xy 338.62869 -42.842583)
			(xy 338.756314 -42.834554) (xy 338.88419 -42.834554) (xy 339.011814 -42.842583) (xy 339.138682 -42.858611)
			(xy 339.264294 -42.882572) (xy 339.388152 -42.914374) (xy 339.50977 -42.95389) (xy 339.628667 -43.000964)
			(xy 339.744373 -43.055411) (xy 339.856432 -43.117016) (xy 339.964401 -43.185536) (xy 340.067855 -43.2607)
			(xy 340.166386 -43.342211) (xy 340.259604 -43.429748) (xy 340.347141 -43.522966) (xy 340.428652 -43.621497)
			(xy 340.503816 -43.724951) (xy 340.572336 -43.83292) (xy 340.633941 -43.944979) (xy 340.688388 -44.060685)
			(xy 340.735462 -44.179582) (xy 340.774978 -44.3012) (xy 340.80678 -44.425058) (xy 340.830741 -44.55067)
			(xy 340.846769 -44.677538) (xy 340.854798 -44.805162) (xy 340.8553 -44.8691) (xy 340.854798 -44.932982)
			(xy 348.217484 -44.932982) (xy 348.217484 -44.805218) (xy 348.225506 -44.677705) (xy 348.241519 -44.550948)
			(xy 348.26546 -44.425446) (xy 348.297234 -44.301696) (xy 348.336715 -44.180184) (xy 348.383748 -44.061392)
			(xy 348.438148 -43.945787) (xy 348.499699 -43.833826) (xy 348.568159 -43.725951) (xy 348.643257 -43.622587)
			(xy 348.724697 -43.524142) (xy 348.812158 -43.431006) (xy 348.905294 -43.343545) (xy 349.003739 -43.262105)
			(xy 349.107103 -43.187007) (xy 349.214978 -43.118547) (xy 349.326939 -43.056996) (xy 349.442544 -43.002596)
			(xy 349.561336 -42.955563) (xy 349.682848 -42.916082) (xy 349.806598 -42.884308) (xy 349.9321 -42.860367)
			(xy 350.058857 -42.844354) (xy 350.18637 -42.836332) (xy 350.314134 -42.836332) (xy 350.441647 -42.844354)
			(xy 350.568404 -42.860367) (xy 350.693906 -42.884308) (xy 350.817656 -42.916082) (xy 350.939168 -42.955563)
			(xy 351.05796 -43.002596) (xy 351.173565 -43.056996) (xy 351.285526 -43.118547) (xy 351.393401 -43.187007)
			(xy 351.496765 -43.262105) (xy 351.59521 -43.343545) (xy 351.688346 -43.431006) (xy 351.775807 -43.524142)
			(xy 351.857247 -43.622587) (xy 351.932345 -43.725951) (xy 352.000805 -43.833826) (xy 352.062356 -43.945787)
			(xy 352.116756 -44.061392) (xy 352.163789 -44.180184) (xy 352.20327 -44.301696) (xy 352.235044 -44.425446)
			(xy 352.258985 -44.550948) (xy 352.274998 -44.677705) (xy 352.28302 -44.805218) (xy 352.283522 -44.8691)
			(xy 352.28302 -44.932982) (xy 352.274998 -45.060495) (xy 352.258985 -45.187252) (xy 352.235044 -45.312754)
			(xy 352.20327 -45.436504) (xy 352.163789 -45.558016) (xy 352.116756 -45.676808) (xy 352.062356 -45.792413)
			(xy 352.000805 -45.904374) (xy 351.932345 -46.012249) (xy 351.857247 -46.115613) (xy 351.775807 -46.214058)
			(xy 351.688346 -46.307194) (xy 351.59521 -46.394655) (xy 351.496765 -46.476095) (xy 351.393401 -46.551193)
			(xy 351.285526 -46.619653) (xy 351.173565 -46.681204) (xy 351.05796 -46.735604) (xy 350.939168 -46.782637)
			(xy 350.817656 -46.822118) (xy 350.693906 -46.853892) (xy 350.568404 -46.877833) (xy 350.441647 -46.893846)
			(xy 350.314134 -46.901868) (xy 350.18637 -46.901868) (xy 350.058857 -46.893846) (xy 349.9321 -46.877833)
			(xy 349.806598 -46.853892) (xy 349.682848 -46.822118) (xy 349.561336 -46.782637) (xy 349.442544 -46.735604)
			(xy 349.326939 -46.681204) (xy 349.214978 -46.619653) (xy 349.107103 -46.551193) (xy 349.003739 -46.476095)
			(xy 348.905294 -46.394655) (xy 348.812158 -46.307194) (xy 348.724697 -46.214058) (xy 348.643257 -46.115613)
			(xy 348.568159 -46.012249) (xy 348.499699 -45.904374) (xy 348.438148 -45.792413) (xy 348.383748 -45.676808)
			(xy 348.336715 -45.558016) (xy 348.297234 -45.436504) (xy 348.26546 -45.312754) (xy 348.241519 -45.187252)
			(xy 348.225506 -45.060495) (xy 348.217484 -44.932982) (xy 340.854798 -44.932982) (xy 340.854798 -44.933038)
			(xy 340.846769 -45.060662) (xy 340.830741 -45.18753) (xy 340.80678 -45.313142) (xy 340.774978 -45.437)
			(xy 340.735462 -45.558618) (xy 340.688388 -45.677515) (xy 340.633941 -45.793221) (xy 340.572336 -45.90528)
			(xy 340.503816 -46.013249) (xy 340.428652 -46.116703) (xy 340.347141 -46.215234) (xy 340.259604 -46.308452)
			(xy 340.166386 -46.395989) (xy 340.067855 -46.4775) (xy 339.964401 -46.552664) (xy 339.856432 -46.621184)
			(xy 339.744373 -46.682789) (xy 339.628667 -46.737236) (xy 339.50977 -46.78431) (xy 339.388152 -46.823826)
			(xy 339.264294 -46.855628) (xy 339.138682 -46.879589) (xy 339.011814 -46.895617) (xy 338.88419 -46.903646)
			(xy 338.756314 -46.903646) (xy 338.62869 -46.895617) (xy 338.501822 -46.879589) (xy 338.37621 -46.855628)
			(xy 338.252352 -46.823826) (xy 338.130734 -46.78431) (xy 338.011837 -46.737236) (xy 337.896131 -46.682789)
			(xy 337.784072 -46.621184) (xy 337.676103 -46.552664) (xy 337.572649 -46.4775) (xy 337.474118 -46.395989)
			(xy 337.3809 -46.308452) (xy 337.293363 -46.215234) (xy 337.211852 -46.116703) (xy 337.136688 -46.013249)
			(xy 337.068168 -45.90528) (xy 337.006563 -45.793221) (xy 336.952116 -45.677515) (xy 336.905042 -45.558618)
			(xy 336.865526 -45.437) (xy 336.833724 -45.313142) (xy 336.809763 -45.18753) (xy 336.793735 -45.060662)
			(xy 336.785706 -44.933038) (xy 303.202878 -44.933038) (xy 303.222406 -44.952158) (xy 303.280403 -45.007695)
			(xy 303.391862 -45.123314) (xy 303.497912 -45.243914) (xy 303.59833 -45.369242) (xy 303.692906 -45.499035)
			(xy 303.781442 -45.633022) (xy 303.863752 -45.77092) (xy 303.939664 -45.912442) (xy 303.974754 -45.984668)
			(xy 303.984152 -46.00448) (xy 304.111914 -46.132242) (xy 304.111914 -46.31309) (xy 304.119026 -46.33341)
			(xy 304.146814 -46.41369) (xy 304.195486 -46.576474) (xy 304.236222 -46.741423) (xy 304.268925 -46.90815)
			(xy 304.293519 -47.076265) (xy 304.309947 -47.245373) (xy 304.31817 -47.415078) (xy 304.318168 -47.584982)
			(xy 304.309943 -47.754687) (xy 304.293512 -47.923795) (xy 304.268915 -48.09191) (xy 304.236209 -48.258636)
			(xy 304.19547 -48.423584) (xy 304.146796 -48.586367) (xy 304.119026 -48.666654) (xy 304.111914 -48.687228)
			(xy 304.111914 -48.868076) (xy 303.983898 -48.996092) (xy 303.9745 -49.01565) (xy 303.937399 -49.092006)
			(xy 303.856734 -49.241402) (xy 303.768938 -49.386722) (xy 303.674216 -49.527626) (xy 303.572789 -49.663782)
			(xy 303.464895 -49.794874) (xy 303.350787 -49.920593) (xy 303.230731 -50.040646) (xy 303.105009 -50.154751)
			(xy 302.973915 -50.262642) (xy 302.837756 -50.364065) (xy 302.69685 -50.458784) (xy 302.551528 -50.546577)
			(xy 302.40213 -50.627237) (xy 302.325786 -50.664364) (xy 302.306228 -50.673762) (xy 302.177704 -50.802286)
			(xy 301.99584 -50.802286) (xy 301.97552 -50.809398) (xy 301.895314 -50.837106) (xy 301.732699 -50.885669)
			(xy 301.567927 -50.926313) (xy 301.401382 -50.958944) (xy 301.233454 -50.983483) (xy 301.064536 -50.999875)
			(xy 300.895024 -51.00808) (xy 300.725312 -51.00808) (xy 300.5558 -50.999875) (xy 300.386882 -50.983483)
			(xy 300.218954 -50.958944) (xy 300.052409 -50.926313) (xy 299.887637 -50.885669) (xy 299.725022 -50.837106)
			(xy 299.644816 -50.809398) (xy 299.624496 -50.802286) (xy 299.442124 -50.802286) (xy 299.313092 -50.673254)
			(xy 299.293534 -50.663856) (xy 299.217276 -50.626741) (xy 299.068045 -50.546114) (xy 298.922885 -50.458371)
			(xy 298.782135 -50.363715) (xy 298.646122 -50.262369) (xy 298.515166 -50.154568) (xy 298.389572 -50.040566)
			(xy 298.269634 -49.920628) (xy 298.155632 -49.795034) (xy 298.047831 -49.664078) (xy 297.946485 -49.528065)
			(xy 297.851829 -49.387315) (xy 297.764086 -49.242155) (xy 297.683459 -49.092924) (xy 297.646344 -49.016666)
			(xy 297.636946 -48.997108) (xy 297.507914 -48.868076) (xy 297.507914 -48.685704) (xy 297.500802 -48.665384)
			(xy 297.47307 -48.585196) (xy 297.424508 -48.422598) (xy 297.383865 -48.257843) (xy 297.351236 -48.091316)
			(xy 297.326698 -47.923405) (xy 297.310308 -47.754504) (xy 297.302105 -47.585008) (xy 213.318094 -47.585008)
			(xy 213.309869 -47.754687) (xy 213.293438 -47.923795) (xy 213.268841 -48.09191) (xy 213.236136 -48.258636)
			(xy 213.195398 -48.423584) (xy 213.146723 -48.586367) (xy 213.118954 -48.666654) (xy 213.111842 -48.687228)
			(xy 213.111842 -48.868076) (xy 212.983826 -48.996092) (xy 212.974428 -49.01565) (xy 212.937315 -49.092)
			(xy 212.856651 -49.241397) (xy 212.768856 -49.386717) (xy 212.674135 -49.52762) (xy 212.572709 -49.663777)
			(xy 212.464816 -49.794869) (xy 212.350708 -49.920588) (xy 212.230653 -50.040641) (xy 212.104932 -50.154747)
			(xy 211.973839 -50.262638) (xy 211.837681 -50.364062) (xy 211.696776 -50.458782) (xy 211.551455 -50.546575)
			(xy 211.402057 -50.627237) (xy 211.325714 -50.664364) (xy 211.306156 -50.673762) (xy 211.177632 -50.802286)
			(xy 210.995768 -50.802286) (xy 210.975448 -50.809398) (xy 210.895242 -50.837106) (xy 210.732627 -50.885669)
			(xy 210.567855 -50.926313) (xy 210.40131 -50.958944) (xy 210.233382 -50.983483) (xy 210.064464 -50.999875)
			(xy 209.894952 -51.00808) (xy 209.72524 -51.00808) (xy 209.555728 -50.999875) (xy 209.38681 -50.983483)
			(xy 209.218882 -50.958944) (xy 209.052337 -50.926313) (xy 208.887565 -50.885669) (xy 208.72495 -50.837106)
			(xy 208.644744 -50.809398) (xy 208.624424 -50.802286) (xy 208.442052 -50.802286) (xy 208.31302 -50.673254)
			(xy 208.293462 -50.663856) (xy 208.217209 -50.626729) (xy 208.067979 -50.546104) (xy 207.922818 -50.458362)
			(xy 207.782067 -50.363707) (xy 207.646054 -50.262362) (xy 207.515098 -50.154562) (xy 207.389504 -50.040561)
			(xy 207.269565 -49.920623) (xy 207.155562 -49.79503) (xy 207.047761 -49.664075) (xy 206.946414 -49.528063)
			(xy 206.851759 -49.387313) (xy 206.764015 -49.242154) (xy 206.683388 -49.092924) (xy 206.646272 -49.016666)
			(xy 206.636874 -48.997108) (xy 206.507842 -48.868076) (xy 206.507842 -48.685704) (xy 206.50073 -48.665384)
			(xy 206.472998 -48.585196) (xy 206.424435 -48.422599) (xy 206.383792 -48.257843) (xy 206.351163 -48.091316)
			(xy 206.326625 -47.923405) (xy 206.310235 -47.754504) (xy 206.302031 -47.585008) (xy 83.318099 -47.585008)
			(xy 83.309875 -47.754687) (xy 83.293444 -47.923795) (xy 83.268847 -48.09191) (xy 83.236141 -48.258636)
			(xy 83.195404 -48.423584) (xy 83.146729 -48.586367) (xy 83.11896 -48.666654) (xy 83.111848 -48.687228)
			(xy 83.111848 -48.86833) (xy 82.983578 -48.9966) (xy 82.97418 -49.016158) (xy 82.937071 -49.092465)
			(xy 82.856425 -49.241778) (xy 82.768656 -49.387018) (xy 82.673967 -49.527845) (xy 82.57258 -49.66393)
			(xy 82.464733 -49.794953) (xy 82.350678 -49.92061) (xy 82.230681 -50.040606) (xy 82.105023 -50.154659)
			(xy 81.973998 -50.262505) (xy 81.837912 -50.36389) (xy 81.697084 -50.458577) (xy 81.551843 -50.546345)
			(xy 81.402529 -50.626989) (xy 81.326228 -50.66411) (xy 81.30667 -50.673508) (xy 81.177638 -50.80254)
			(xy 80.995266 -50.80254) (xy 80.974692 -50.809652) (xy 80.894534 -50.837323) (xy 80.732021 -50.885822)
			(xy 80.567354 -50.926411) (xy 80.400918 -50.958998) (xy 80.233102 -50.983504) (xy 80.064298 -50.999873)
			(xy 79.8949 -51.008068) (xy 79.725304 -51.008068) (xy 79.555906 -50.999873) (xy 79.387102 -50.983504)
			(xy 79.219286 -50.958998) (xy 79.05285 -50.926411) (xy 78.888183 -50.885822) (xy 78.72567 -50.837323)
			(xy 78.645512 -50.809652) (xy 78.624938 -50.80254) (xy 78.442058 -50.80254) (xy 78.312772 -50.673254)
			(xy 78.293214 -50.663856) (xy 78.216985 -50.626744) (xy 78.067808 -50.546131) (xy 77.922701 -50.458406)
			(xy 77.782 -50.363773) (xy 77.646036 -50.262453) (xy 77.515125 -50.154684) (xy 77.389573 -50.040716)
			(xy 77.269673 -49.920816) (xy 77.155706 -49.795263) (xy 77.047937 -49.664352) (xy 76.946618 -49.528387)
			(xy 76.851986 -49.387686) (xy 76.764261 -49.242578) (xy 76.683649 -49.093401) (xy 76.646532 -49.017174)
			(xy 76.637134 -48.997616) (xy 76.507848 -48.86833) (xy 76.507848 -48.685704) (xy 76.500736 -48.665384)
			(xy 76.473028 -48.585187) (xy 76.424465 -48.422591) (xy 76.383821 -48.257837) (xy 76.35119 -48.09131)
			(xy 76.326651 -47.923401) (xy 76.310259 -47.754501) (xy 76.302054 -47.585006) (xy 56.588914 -47.585006)
			(xy 56.588914 -50.31994) (xy 56.589437 -50.375708) (xy 56.597775 -50.486932) (xy 56.614401 -50.597222)
			(xy 56.639223 -50.705962) (xy 56.672101 -50.812542) (xy 56.712852 -50.916368) (xy 56.761247 -51.016857)
			(xy 56.817017 -51.11345) (xy 56.879849 -51.205604) (xy 56.949392 -51.292806) (xy 57.025257 -51.374567)
			(xy 57.10702 -51.45043) (xy 57.194223 -51.519971) (xy 57.286379 -51.582801) (xy 57.382973 -51.638569)
			(xy 57.483464 -51.686962) (xy 57.58729 -51.72771) (xy 57.693871 -51.760586) (xy 57.802611 -51.785405)
			(xy 57.912901 -51.802029) (xy 58.024126 -51.810364) (xy 58.079894 -51.81092)
		)
		(stroke
			(width 0)
			(type solid)
		)
		(fill yes)
		(layer "In1.Cu")
		(net "GND")
	)
	(gr_line
		(start 0.1778 -46.8376)
		(end 10.541 -46.8376)
		(stroke
			(width 0.508)
			(type default)
		)
		(layer "In1.Cu")
	)
	(gr_line
		(start 0.7366 -49.1744)
		(end 9.271 -49.1744)
		(stroke
			(width 2.54)
			(type default)
		)
		(layer "In1.Cu")
	)
	(gr_line
		(start 0.762 -51.3334)
		(end 9.2964 -51.3334)
		(stroke
			(width 2.54)
			(type default)
		)
		(layer "In1.Cu")
	)
	(gr_line
		(start 0.762 -50.3174)
		(end 9.2964 -50.3174)
		(stroke
			(width 2.54)
			(type default)
		)
		(layer "In1.Cu")
	)
	(gr_line
		(start 0.762 -49.911)
		(end 9.2964 -49.911)
		(stroke
			(width 2.54)
			(type default)
		)
		(layer "In1.Cu")
	)
	(gr_line
		(start 0.7874 -50.8508)
		(end 9.3218 -50.8508)
		(stroke
			(width 2.54)
			(type default)
		)
		(layer "In1.Cu")
	)
	(gr_line
		(start 0.7874 -50.3682)
		(end 9.3218 -50.3682)
		(stroke
			(width 2.54)
			(type default)
		)
		(layer "In1.Cu")
	)
	(gr_line
		(start 0.7874 -49.5046)
		(end 9.3218 -49.5046)
		(stroke
			(width 2.54)
			(type default)
		)
		(layer "In1.Cu")
	)
	(gr_line
		(start 0.7874 -48.6156)
		(end 9.3218 -48.6156)
		(stroke
			(width 2.54)
			(type default)
		)
		(layer "In1.Cu")
	)
	(gr_line
		(start 0.7874 -48.0822)
		(end 9.3218 -48.0822)
		(stroke
			(width 2.54)
			(type default)
		)
		(layer "In1.Cu")
	)
	(gr_line
		(start 0.8128 -48.3108)
		(end 9.3472 -48.3108)
		(stroke
			(width 2.54)
			(type default)
		)
		(layer "In1.Cu")
	)
	(gr_line
		(start 0.8128 -48.26)
		(end 9.3472 -48.26)
		(stroke
			(width 2.54)
			(type default)
		)
		(layer "In1.Cu")
	)
	(gr_line
		(start 0.8128 -47.9044)
		(end 9.3472 -47.9044)
		(stroke
			(width 2.54)
			(type default)
		)
		(layer "In1.Cu")
	)
	(gr_line
		(start 0.8382 -48.8442)
		(end 9.3726 -48.8442)
		(stroke
			(width 2.54)
			(type default)
		)
		(layer "In1.Cu")
	)
	(gr_line
		(start 0.8382 -48.5394)
		(end 9.3726 -48.5394)
		(stroke
			(width 2.54)
			(type default)
		)
		(layer "In1.Cu")
	)
	(gr_line
		(start 0.8382 -48.4378)
		(end 9.3726 -48.4378)
		(stroke
			(width 2.54)
			(type default)
		)
		(layer "In1.Cu")
	)
	(gr_line
		(start 0.8382 -48.0822)
		(end 9.3726 -48.0822)
		(stroke
			(width 2.54)
			(type default)
		)
		(layer "In1.Cu")
	)
	(gr_line
		(start 0.8636 -49.0982)
		(end 9.398 -49.0982)
		(stroke
			(width 2.54)
			(type default)
		)
		(layer "In1.Cu")
	)
	(gr_line
		(start 0.8636 -48.9204)
		(end 9.398 -48.9204)
		(stroke
			(width 2.54)
			(type default)
		)
		(layer "In1.Cu")
	)
	(gr_line
		(start 0.8636 -48.7172)
		(end 9.398 -48.7172)
		(stroke
			(width 2.54)
			(type default)
		)
		(layer "In1.Cu")
	)
	(gr_line
		(start 0.8636 -48.641)
		(end 9.398 -48.641)
		(stroke
			(width 2.54)
			(type default)
		)
		(layer "In1.Cu")
	)
	(gr_line
		(start 0.889 -51.5366)
		(end 9.4234 -51.5366)
		(stroke
			(width 2.54)
			(type default)
		)
		(layer "In1.Cu")
	)
	(gr_line
		(start 0.9144 -49.8856)
		(end 9.4488 -49.8856)
		(stroke
			(width 2.54)
			(type default)
		)
		(layer "In1.Cu")
	)
	(gr_line
		(start 0.9144 -49.2506)
		(end 9.4488 -49.2506)
		(stroke
			(width 2.54)
			(type default)
		)
		(layer "In1.Cu")
	)
	(gr_line
		(start 0.9398 -51.2572)
		(end 9.4742 -51.2572)
		(stroke
			(width 2.54)
			(type default)
		)
		(layer "In1.Cu")
	)
	(gr_line
		(start 0.9398 -49.7332)
		(end 9.4742 -49.7332)
		(stroke
			(width 2.54)
			(type default)
		)
		(layer "In1.Cu")
	)
	(gr_line
		(start 0.9398 -49.5808)
		(end 9.4742 -49.5808)
		(stroke
			(width 2.54)
			(type default)
		)
		(layer "In1.Cu")
	)
	(gr_line
		(start 0.9398 -49.3522)
		(end 9.4742 -49.3522)
		(stroke
			(width 2.54)
			(type default)
		)
		(layer "In1.Cu")
	)
	(gr_line
		(start 0.9652 -51.3588)
		(end 9.4996 -51.3588)
		(stroke
			(width 2.54)
			(type default)
		)
		(layer "In1.Cu")
	)
	(gr_line
		(start 0.9652 -50.4698)
		(end 9.4996 -50.4698)
		(stroke
			(width 2.54)
			(type default)
		)
		(layer "In1.Cu")
	)
	(gr_line
		(start 0.9652 -50.3682)
		(end 9.4996 -50.3682)
		(stroke
			(width 2.54)
			(type default)
		)
		(layer "In1.Cu")
	)
	(gr_line
		(start 0.9652 -50.1142)
		(end 9.4996 -50.1142)
		(stroke
			(width 2.54)
			(type default)
		)
		(layer "In1.Cu")
	)
	(gr_line
		(start 0.9906 -51.435)
		(end 5.8674 -51.435)
		(stroke
			(width 2.54)
			(type default)
		)
		(layer "In1.Cu")
	)
	(gr_line
		(start 0.9906 -51.1048)
		(end 9.525 -51.1048)
		(stroke
			(width 2.54)
			(type default)
		)
		(layer "In1.Cu")
	)
	(gr_line
		(start 0.9906 -50.8)
		(end 9.525 -50.8)
		(stroke
			(width 2.54)
			(type default)
		)
		(layer "In1.Cu")
	)
	(gr_line
		(start 0.9906 -50.6476)
		(end 9.525 -50.6476)
		(stroke
			(width 2.54)
			(type default)
		)
		(layer "In1.Cu")
	)
	(gr_line
		(start 1.016 -50.9524)
		(end 9.5504 -50.9524)
		(stroke
			(width 2.54)
			(type default)
		)
		(layer "In1.Cu")
	)
	(gr_line
		(start 1.0414 -51.1556)
		(end 9.5758 -51.1556)
		(stroke
			(width 2.54)
			(type default)
		)
		(layer "In1.Cu")
	)
	(gr_line
		(start 1.0414 -50.9016)
		(end 9.5758 -50.9016)
		(stroke
			(width 2.54)
			(type default)
		)
		(layer "In1.Cu")
	)
	(gr_line
		(start 1.0414 -50.0888)
		(end 9.5758 -50.0888)
		(stroke
			(width 2.54)
			(type default)
		)
		(layer "In1.Cu")
	)
	(gr_line
		(start 1.0668 -50.6984)
		(end 9.6012 -50.6984)
		(stroke
			(width 2.54)
			(type default)
		)
		(layer "In1.Cu")
	)
	(gr_line
		(start 1.0668 -50.4952)
		(end 9.6012 -50.4952)
		(stroke
			(width 2.54)
			(type default)
		)
		(layer "In1.Cu")
	)
	(gr_line
		(start 1.0668 -50.2412)
		(end 9.6012 -50.2412)
		(stroke
			(width 2.54)
			(type default)
		)
		(layer "In1.Cu")
	)
	(gr_line
		(start 1.1938 -50.3682)
		(end 9.7282 -50.3682)
		(stroke
			(width 2.54)
			(type default)
		)
		(layer "In1.Cu")
	)
	(gr_line
		(start 1.2192 -50.3428)
		(end 9.7536 -50.3428)
		(stroke
			(width 2.54)
			(type default)
		)
		(layer "In1.Cu")
	)
	(gr_line
		(start 1.2192 -49.8602)
		(end 9.7536 -49.8602)
		(stroke
			(width 2.54)
			(type default)
		)
		(layer "In1.Cu")
	)
	(gr_line
		(start 1.2446 -48.7934)
		(end 9.779 -48.7934)
		(stroke
			(width 2.54)
			(type default)
		)
		(layer "In1.Cu")
	)
	(gr_line
		(start 1.4732 -52.1462)
		(end 6.35 -52.1462)
		(stroke
			(width 2.54)
			(type default)
		)
		(layer "In1.Cu")
	)
	(gr_line
		(start 1.49987 -53.299868)
		(end 0 -51.799998)
		(stroke
			(width 1.016)
			(type default)
		)
		(layer "In1.Cu")
	)
	(gr_line
		(start 1.8542 -52.5272)
		(end 6.731 -52.5272)
		(stroke
			(width 2.54)
			(type default)
		)
		(layer "In1.Cu")
	)
	(gr_arc
		(start 1.999996 0)
		(mid 0.585785 -0.585785)
		(end 0 -1.999996)
		(stroke
			(width 1.016)
			(type default)
		)
		(layer "In1.Cu")
	)
	(gr_line
		(start 1.999996 0)
		(end 426.809916 0)
		(stroke
			(width 1.016)
			(type default)
		)
		(layer "In1.Cu")
	)
	(gr_line
		(start 2.5654 -52.2478)
		(end 7.4422 -52.2478)
		(stroke
			(width 2.54)
			(type default)
		)
		(layer "In1.Cu")
	)
	(gr_arc
		(start 2.750058 -32.563308)
		(mid 4.372855 -37.997202)
		(end 6.45033 -32.720534)
		(stroke
			(width 1.016)
			(type default)
		)
		(layer "In1.Cu")
	)
	(gr_line
		(start 2.750058 -29.207714)
		(end 2.750058 -32.563308)
		(stroke
			(width 1.016)
			(type default)
		)
		(layer "In1.Cu")
	)
	(gr_line
		(start 2.760726 -29.197046)
		(end 2.750058 -29.207714)
		(stroke
			(width 1.016)
			(type default)
		)
		(layer "In1.Cu")
	)
	(gr_line
		(start 3.6576 -52.5018)
		(end 8.5344 -52.5018)
		(stroke
			(width 2.54)
			(type default)
		)
		(layer "In1.Cu")
	)
	(gr_line
		(start 4.2418 -49.5554)
		(end 12.7762 -49.5554)
		(stroke
			(width 2.54)
			(type default)
		)
		(layer "In1.Cu")
	)
	(gr_line
		(start 4.2672 -49.7586)
		(end 12.8016 -49.7586)
		(stroke
			(width 2.54)
			(type default)
		)
		(layer "In1.Cu")
	)
	(gr_line
		(start 4.2926 -49.2506)
		(end 12.827 -49.2506)
		(stroke
			(width 2.54)
			(type default)
		)
		(layer "In1.Cu")
	)
	(gr_line
		(start 4.318 -48.8188)
		(end 12.8524 -48.8188)
		(stroke
			(width 2.54)
			(type default)
		)
		(layer "In1.Cu")
	)
	(gr_line
		(start 4.3434 -50.8254)
		(end 12.8778 -50.8254)
		(stroke
			(width 2.54)
			(type default)
		)
		(layer "In1.Cu")
	)
	(gr_line
		(start 4.3434 -48.895)
		(end 12.8778 -48.895)
		(stroke
			(width 2.54)
			(type default)
		)
		(layer "In1.Cu")
	)
	(gr_line
		(start 4.3688 -50.6222)
		(end 12.9032 -50.6222)
		(stroke
			(width 2.54)
			(type default)
		)
		(layer "In1.Cu")
	)
	(gr_line
		(start 4.3688 -50.4444)
		(end 12.9032 -50.4444)
		(stroke
			(width 2.54)
			(type default)
		)
		(layer "In1.Cu")
	)
	(gr_line
		(start 4.3688 -50.1142)
		(end 12.9032 -50.1142)
		(stroke
			(width 2.54)
			(type default)
		)
		(layer "In1.Cu")
	)
	(gr_line
		(start 4.3942 -51.8668)
		(end 9.271 -51.8668)
		(stroke
			(width 2.54)
			(type default)
		)
		(layer "In1.Cu")
	)
	(gr_line
		(start 4.3942 -49.9364)
		(end 12.9286 -49.9364)
		(stroke
			(width 2.54)
			(type default)
		)
		(layer "In1.Cu")
	)
	(gr_line
		(start 4.3942 -48.4632)
		(end 12.9286 -48.4632)
		(stroke
			(width 2.54)
			(type default)
		)
		(layer "In1.Cu")
	)
	(gr_line
		(start 4.4196 -48.2092)
		(end 12.954 -48.2092)
		(stroke
			(width 2.54)
			(type default)
		)
		(layer "In1.Cu")
	)
	(gr_line
		(start 4.445 -48.5394)
		(end 12.9794 -48.5394)
		(stroke
			(width 2.54)
			(type default)
		)
		(layer "In1.Cu")
	)
	(gr_line
		(start 4.445 -48.4378)
		(end 12.9794 -48.4378)
		(stroke
			(width 2.54)
			(type default)
		)
		(layer "In1.Cu")
	)
	(gr_line
		(start 4.445 -48.0314)
		(end 12.9794 -48.0314)
		(stroke
			(width 2.54)
			(type default)
		)
		(layer "In1.Cu")
	)
	(gr_line
		(start 4.445 -47.9044)
		(end 12.9794 -47.9044)
		(stroke
			(width 2.54)
			(type default)
		)
		(layer "In1.Cu")
	)
	(gr_line
		(start 4.4704 -48.8442)
		(end 13.0048 -48.8442)
		(stroke
			(width 2.54)
			(type default)
		)
		(layer "In1.Cu")
	)
	(gr_line
		(start 4.49961 -34.99993)
		(end 4.499864 -35.000184)
		(stroke
			(width 4.064)
			(type default)
		)
		(layer "In1.Cu")
	)
	(gr_line
		(start 4.49961 -28.999688)
		(end 4.49961 -34.99993)
		(stroke
			(width 4.064)
			(type default)
		)
		(layer "In1.Cu")
	)
	(gr_line
		(start 4.499864 -35.000184)
		(end 4.499864 -34.99993)
		(stroke
			(width 6.604)
			(type default)
		)
		(layer "In1.Cu")
	)
	(gr_line
		(start 4.6736 -49.0728)
		(end 13.208 -49.0728)
		(stroke
			(width 2.54)
			(type default)
		)
		(layer "In1.Cu")
	)
	(gr_line
		(start 4.826 -49.4284)
		(end 13.3604 -49.4284)
		(stroke
			(width 2.54)
			(type default)
		)
		(layer "In1.Cu")
	)
	(gr_line
		(start 4.8514 -49.5808)
		(end 13.3858 -49.5808)
		(stroke
			(width 2.54)
			(type default)
		)
		(layer "In1.Cu")
	)
	(gr_line
		(start 4.8514 -48.7934)
		(end 13.3858 -48.7934)
		(stroke
			(width 2.54)
			(type default)
		)
		(layer "In1.Cu")
	)
	(gr_line
		(start 4.9022 -49.8856)
		(end 13.4366 -49.8856)
		(stroke
			(width 2.54)
			(type default)
		)
		(layer "In1.Cu")
	)
	(gr_line
		(start 4.9276 -50.2666)
		(end 13.462 -50.2666)
		(stroke
			(width 2.54)
			(type default)
		)
		(layer "In1.Cu")
	)
	(gr_line
		(start 4.953 -50.419)
		(end 13.4874 -50.419)
		(stroke
			(width 2.54)
			(type default)
		)
		(layer "In1.Cu")
	)
	(gr_line
		(start 4.953 -50.0634)
		(end 13.4874 -50.0634)
		(stroke
			(width 2.54)
			(type default)
		)
		(layer "In1.Cu")
	)
	(gr_line
		(start 5.0038 -50.7238)
		(end 13.5382 -50.7238)
		(stroke
			(width 2.54)
			(type default)
		)
		(layer "In1.Cu")
	)
	(gr_line
		(start 5.0546 -51.181)
		(end 9.9314 -51.181)
		(stroke
			(width 2.54)
			(type default)
		)
		(layer "In1.Cu")
	)
	(gr_line
		(start 6.249924 -32.520128)
		(end 6.249924 -28.999942)
		(stroke
			(width 1.016)
			(type default)
		)
		(layer "In1.Cu")
	)
	(gr_arc
		(start 6.249924 -28.999942)
		(mid 4.401168 -27.252413)
		(end 2.760726 -29.197046)
		(stroke
			(width 1.016)
			(type default)
		)
		(layer "In1.Cu")
	)
	(gr_line
		(start 6.45033 -32.720534)
		(end 6.249924 -32.520128)
		(stroke
			(width 1.016)
			(type default)
		)
		(layer "In1.Cu")
	)
	(gr_line
		(start 8.950198 -53.299868)
		(end 1.49987 -53.299868)
		(stroke
			(width 1.016)
			(type default)
		)
		(layer "In1.Cu")
	)
	(gr_line
		(start 10.450068 -51.799998)
		(end 8.950198 -53.299868)
		(stroke
			(width 1.016)
			(type default)
		)
		(layer "In1.Cu")
	)
	(gr_line
		(start 10.450068 -42.650664)
		(end 10.450068 -51.799998)
		(stroke
			(width 1.016)
			(type default)
		)
		(layer "In1.Cu")
	)
	(gr_arc
		(start 10.450068 -42.650664)
		(mid 11.047577 -42.898154)
		(end 10.80008 -42.300652)
		(stroke
			(width 1.016)
			(type default)
		)
		(layer "In1.Cu")
	)
	(gr_line
		(start 10.541 -46.8376)
		(end 10.9982 -46.3804)
		(stroke
			(width 0.508)
			(type default)
		)
		(layer "In1.Cu")
	)
	(gr_line
		(start 10.7188 -45.6692)
		(end 10.7696 -45.6184)
		(stroke
			(width 0.762)
			(type default)
		)
		(layer "In1.Cu")
	)
	(gr_line
		(start 10.7696 -45.72)
		(end 10.7188 -45.6692)
		(stroke
			(width 0.762)
			(type default)
		)
		(layer "In1.Cu")
	)
	(gr_line
		(start 10.7696 -45.6184)
		(end 51.9176 -45.6184)
		(stroke
			(width 0.762)
			(type default)
		)
		(layer "In1.Cu")
	)
	(gr_line
		(start 10.9982 -46.3804)
		(end 11.4554 -45.9232)
		(stroke
			(width 1.27)
			(type default)
		)
		(layer "In1.Cu")
	)
	(gr_line
		(start 11.150092 -51.799998)
		(end 12.649962 -53.299868)
		(stroke
			(width 1.016)
			(type default)
		)
		(layer "In1.Cu")
	)
	(gr_arc
		(start 11.150092 -42.650664)
		(mid 11.047562 -42.403198)
		(end 10.80008 -42.300652)
		(stroke
			(width 1.016)
			(type default)
		)
		(layer "In1.Cu")
	)
	(gr_line
		(start 11.150092 -42.650664)
		(end 11.150092 -51.799998)
		(stroke
			(width 1.016)
			(type default)
		)
		(layer "In1.Cu")
	)
	(gr_line
		(start 11.1506 -45.7962)
		(end 11.3284 -45.6184)
		(stroke
			(width 0.762)
			(type default)
		)
		(layer "In1.Cu")
	)
	(gr_line
		(start 11.303 -45.9486)
		(end 11.1506 -45.7962)
		(stroke
			(width 1.27)
			(type default)
		)
		(layer "In1.Cu")
	)
	(gr_line
		(start 11.3284 -45.6184)
		(end 51.9176 -45.6184)
		(stroke
			(width 0.762)
			(type default)
		)
		(layer "In1.Cu")
	)
	(gr_line
		(start 11.4554 -45.9232)
		(end 51.943 -45.9232)
		(stroke
			(width 1.27)
			(type default)
		)
		(layer "In1.Cu")
	)
	(gr_line
		(start 11.5062 -50.7238)
		(end 11.5062 -46.5836)
		(stroke
			(width 2.54)
			(type default)
		)
		(layer "In1.Cu")
	)
	(gr_line
		(start 11.5062 -50.6222)
		(end 11.5062 -46.482)
		(stroke
			(width 2.54)
			(type default)
		)
		(layer "In1.Cu")
	)
	(gr_line
		(start 12.192 -51.6382)
		(end 12.192 -47.498)
		(stroke
			(width 2.54)
			(type default)
		)
		(layer "In1.Cu")
	)
	(gr_line
		(start 12.3444 -51.5874)
		(end 12.3444 -47.4472)
		(stroke
			(width 2.54)
			(type default)
		)
		(layer "In1.Cu")
	)
	(gr_line
		(start 12.649962 -53.299868)
		(end 50.580036 -53.299868)
		(stroke
			(width 1.016)
			(type default)
		)
		(layer "In1.Cu")
	)
	(gr_line
		(start 13.0302 -52.578)
		(end 13.0302 -48.4378)
		(stroke
			(width 2.54)
			(type default)
		)
		(layer "In1.Cu")
	)
	(gr_line
		(start 13.6906 -49.3268)
		(end 42.545 -49.3268)
		(stroke
			(width 7.62)
			(type default)
		)
		(layer "In1.Cu")
	)
	(gr_line
		(start 13.716 -52.197)
		(end 13.716 -48.0568)
		(stroke
			(width 2.54)
			(type default)
		)
		(layer "In1.Cu")
	)
	(gr_line
		(start 13.843 -49.276)
		(end 42.6974 -49.276)
		(stroke
			(width 7.62)
			(type default)
		)
		(layer "In1.Cu")
	)
	(gr_line
		(start 14.1986 -49.9872)
		(end 43.053 -49.9872)
		(stroke
			(width 7.62)
			(type default)
		)
		(layer "In1.Cu")
	)
	(gr_line
		(start 14.6304 -52.4002)
		(end 14.6304 -48.26)
		(stroke
			(width 2.54)
			(type default)
		)
		(layer "In1.Cu")
	)
	(gr_line
		(start 15.5448 -49.276)
		(end 44.3992 -49.276)
		(stroke
			(width 7.62)
			(type default)
		)
		(layer "In1.Cu")
	)
	(gr_line
		(start 15.9258 -52.5272)
		(end 15.9258 -48.387)
		(stroke
			(width 2.54)
			(type default)
		)
		(layer "In1.Cu")
	)
	(gr_line
		(start 18.4912 -49.5808)
		(end 47.3456 -49.5808)
		(stroke
			(width 7.62)
			(type default)
		)
		(layer "In1.Cu")
	)
	(gr_line
		(start 18.6436 -49.4792)
		(end 47.498 -49.4792)
		(stroke
			(width 7.62)
			(type default)
		)
		(layer "In1.Cu")
	)
	(gr_line
		(start 18.9738 -49.3776)
		(end 47.8282 -49.3776)
		(stroke
			(width 7.62)
			(type default)
		)
		(layer "In1.Cu")
	)
	(gr_line
		(start 19.3294 -49.9872)
		(end 48.1838 -49.9872)
		(stroke
			(width 7.62)
			(type default)
		)
		(layer "In1.Cu")
	)
	(gr_line
		(start 19.7866 -49.8348)
		(end 48.641 -49.8348)
		(stroke
			(width 7.62)
			(type default)
		)
		(layer "In1.Cu")
	)
	(gr_line
		(start 19.7866 -49.276)
		(end 48.641 -49.276)
		(stroke
			(width 7.62)
			(type default)
		)
		(layer "In1.Cu")
	)
	(gr_line
		(start 19.8882 -49.022)
		(end 48.7426 -49.022)
		(stroke
			(width 7.62)
			(type default)
		)
		(layer "In1.Cu")
	)
	(gr_line
		(start 49.9872 -52.5272)
		(end 49.9872 -48.387)
		(stroke
			(width 2.54)
			(type default)
		)
		(layer "In1.Cu")
	)
	(gr_line
		(start 50.038 -51.1556)
		(end 50.038 -47.0154)
		(stroke
			(width 2.54)
			(type default)
		)
		(layer "In1.Cu")
	)
	(gr_line
		(start 50.3174 -52.451)
		(end 50.3174 -48.3108)
		(stroke
			(width 2.54)
			(type default)
		)
		(layer "In1.Cu")
	)
	(gr_line
		(start 50.546 -52.2224)
		(end 50.546 -48.0822)
		(stroke
			(width 2.54)
			(type default)
		)
		(layer "In1.Cu")
	)
	(gr_line
		(start 50.580036 -53.299868)
		(end 52.079906 -51.799998)
		(stroke
			(width 1.016)
			(type default)
		)
		(layer "In1.Cu")
	)
	(gr_line
		(start 50.8254 -51.8922)
		(end 50.8254 -47.752)
		(stroke
			(width 2.54)
			(type default)
		)
		(layer "In1.Cu")
	)
	(gr_line
		(start 50.927 -50.7746)
		(end 50.927 -46.6344)
		(stroke
			(width 2.54)
			(type default)
		)
		(layer "In1.Cu")
	)
	(gr_line
		(start 51.0286 -50.6984)
		(end 51.0286 -46.5582)
		(stroke
			(width 2.54)
			(type default)
		)
		(layer "In1.Cu")
	)
	(gr_line
		(start 51.2318 -51.4858)
		(end 51.2318 -47.3456)
		(stroke
			(width 2.54)
			(type default)
		)
		(layer "In1.Cu")
	)
	(gr_line
		(start 51.2826 -50.7238)
		(end 51.2826 -46.5836)
		(stroke
			(width 2.54)
			(type default)
		)
		(layer "In1.Cu")
	)
	(gr_line
		(start 51.816 -45.72)
		(end 10.7696 -45.72)
		(stroke
			(width 0.762)
			(type default)
		)
		(layer "In1.Cu")
	)
	(gr_line
		(start 51.9176 -45.9486)
		(end 11.303 -45.9486)
		(stroke
			(width 1.27)
			(type default)
		)
		(layer "In1.Cu")
	)
	(gr_line
		(start 51.9176 -45.6184)
		(end 51.816 -45.72)
		(stroke
			(width 0.762)
			(type default)
		)
		(layer "In1.Cu")
	)
	(gr_line
		(start 51.943 -45.9232)
		(end 51.9176 -45.9486)
		(stroke
			(width 1.27)
			(type default)
		)
		(layer "In1.Cu")
	)
	(gr_line
		(start 52.079906 -51.799998)
		(end 52.079906 -43.319954)
		(stroke
			(width 1.016)
			(type default)
		)
		(layer "In1.Cu")
	)
	(gr_arc
		(start 53.079904 -42.319956)
		(mid 52.37278 -42.612844)
		(end 52.079906 -43.319954)
		(stroke
			(width 1.016)
			(type default)
		)
		(layer "In1.Cu")
	)
	(gr_line
		(start 53.079904 -42.319956)
		(end 55.0799 -42.319956)
		(stroke
			(width 1.016)
			(type default)
		)
		(layer "In1.Cu")
	)
	(gr_arc
		(start 56.079898 -50.31994)
		(mid 56.665683 -51.734151)
		(end 58.079894 -52.319936)
		(stroke
			(width 1.016)
			(type default)
		)
		(layer "In1.Cu")
	)
	(gr_arc
		(start 56.079898 -43.319954)
		(mid 55.786989 -42.612878)
		(end 55.0799 -42.319956)
		(stroke
			(width 1.016)
			(type default)
		)
		(layer "In1.Cu")
	)
	(gr_line
		(start 56.079898 -43.319954)
		(end 56.079898 -50.31994)
		(stroke
			(width 1.016)
			(type default)
		)
		(layer "In1.Cu")
	)
	(gr_line
		(start 58.079894 -52.319936)
		(end 94.681802 -52.319936)
		(stroke
			(width 1.016)
			(type default)
		)
		(layer "In1.Cu")
	)
	(gr_arc
		(start 78.060042 -45.063664)
		(mid 79.682839 -50.497558)
		(end 81.760314 -45.22089)
		(stroke
			(width 1.016)
			(type default)
		)
		(layer "In1.Cu")
	)
	(gr_line
		(start 78.060042 -41.70807)
		(end 78.060042 -45.063664)
		(stroke
			(width 1.016)
			(type default)
		)
		(layer "In1.Cu")
	)
	(gr_line
		(start 78.07071 -41.697402)
		(end 78.060042 -41.70807)
		(stroke
			(width 1.016)
			(type default)
		)
		(layer "In1.Cu")
	)
	(gr_line
		(start 79.809594 -47.500286)
		(end 79.809848 -47.50054)
		(stroke
			(width 4.064)
			(type default)
		)
		(layer "In1.Cu")
	)
	(gr_line
		(start 79.809594 -41.500044)
		(end 79.809594 -47.500286)
		(stroke
			(width 4.064)
			(type default)
		)
		(layer "In1.Cu")
	)
	(gr_line
		(start 79.809848 -47.50054)
		(end 79.809848 -47.500286)
		(stroke
			(width 6.604)
			(type default)
		)
		(layer "In1.Cu")
	)
	(gr_line
		(start 81.559908 -45.020484)
		(end 81.559908 -41.500298)
		(stroke
			(width 1.016)
			(type default)
		)
		(layer "In1.Cu")
	)
	(gr_arc
		(start 81.559908 -41.500298)
		(mid 79.711152 -39.752769)
		(end 78.07071 -41.697402)
		(stroke
			(width 1.016)
			(type default)
		)
		(layer "In1.Cu")
	)
	(gr_line
		(start 81.760314 -45.22089)
		(end 81.559908 -45.020484)
		(stroke
			(width 1.016)
			(type default)
		)
		(layer "In1.Cu")
	)
	(gr_arc
		(start 94.681802 -52.319936)
		(mid 95.388907 -52.027043)
		(end 95.6818 -51.319938)
		(stroke
			(width 1.016)
			(type default)
		)
		(layer "In1.Cu")
	)
	(gr_line
		(start 95.6818 -51.319938)
		(end 95.6818 -50.8)
		(stroke
			(width 1.016)
			(type default)
		)
		(layer "In1.Cu")
	)
	(gr_arc
		(start 96.681798 -49.800002)
		(mid 95.974694 -50.092895)
		(end 95.6818 -50.8)
		(stroke
			(width 1.016)
			(type default)
		)
		(layer "In1.Cu")
	)
	(gr_line
		(start 96.681798 -49.800002)
		(end 112.06988 -49.800002)
		(stroke
			(width 1.016)
			(type default)
		)
		(layer "In1.Cu")
	)
	(gr_line
		(start 101.576632 -11.378946)
		(end 101.576632 -9.194546)
		(stroke
			(width 0.254)
			(type default)
		)
		(layer "In1.Cu")
	)
	(gr_line
		(start 101.576632 -9.194546)
		(end 103.151432 -9.194546)
		(stroke
			(width 0.254)
			(type default)
		)
		(layer "In1.Cu")
	)
	(gr_line
		(start 101.602032 -11.378946)
		(end 101.602032 -9.245346)
		(stroke
			(width 0.254)
			(type default)
		)
		(layer "In1.Cu")
	)
	(gr_line
		(start 101.602032 -9.245346)
		(end 103.126032 -9.245346)
		(stroke
			(width 0.254)
			(type default)
		)
		(layer "In1.Cu")
	)
	(gr_line
		(start 101.652832 -11.353546)
		(end 101.652832 -9.372346)
		(stroke
			(width 0.254)
			(type default)
		)
		(layer "In1.Cu")
	)
	(gr_line
		(start 101.652832 -9.372346)
		(end 103.100632 -9.372346)
		(stroke
			(width 0.254)
			(type default)
		)
		(layer "In1.Cu")
	)
	(gr_line
		(start 101.706934 -11.302746)
		(end 102.011734 -11.302746)
		(stroke
			(width 0.1016)
			(type default)
		)
		(layer "In1.Cu")
	)
	(gr_line
		(start 101.706934 -9.296146)
		(end 101.706934 -11.302746)
		(stroke
			(width 0.1016)
			(type default)
		)
		(layer "In1.Cu")
	)
	(gr_line
		(start 101.734874 -5.57784)
		(end 103.004874 -5.57784)
		(stroke
			(width 1.016)
			(type default)
		)
		(layer "In1.Cu")
	)
	(gr_line
		(start 101.757734 -11.226546)
		(end 102.849934 -11.226546)
		(stroke
			(width 0.2032)
			(type default)
		)
		(layer "In1.Cu")
	)
	(gr_line
		(start 101.757734 -9.372346)
		(end 101.757734 -11.226546)
		(stroke
			(width 0.2032)
			(type default)
		)
		(layer "In1.Cu")
	)
	(gr_line
		(start 101.783134 -11.226546)
		(end 102.951534 -11.226546)
		(stroke
			(width 0.2032)
			(type default)
		)
		(layer "In1.Cu")
	)
	(gr_line
		(start 101.783134 -9.423146)
		(end 101.783134 -11.226546)
		(stroke
			(width 0.2032)
			(type default)
		)
		(layer "In1.Cu")
	)
	(gr_line
		(start 101.830632 -11.124946)
		(end 101.830632 -9.575546)
		(stroke
			(width 0.762)
			(type default)
		)
		(layer "In1.Cu")
	)
	(gr_line
		(start 101.830632 -11.124946)
		(end 102.745032 -11.124946)
		(stroke
			(width 0.762)
			(type default)
		)
		(layer "In1.Cu")
	)
	(gr_line
		(start 101.830632 -11.099546)
		(end 101.830632 -9.550146)
		(stroke
			(width 0.762)
			(type default)
		)
		(layer "In1.Cu")
	)
	(gr_line
		(start 101.830632 -10.997946)
		(end 101.830632 -9.448546)
		(stroke
			(width 0.762)
			(type default)
		)
		(layer "In1.Cu")
	)
	(gr_line
		(start 101.830632 -9.448546)
		(end 102.745032 -9.448546)
		(stroke
			(width 0.762)
			(type default)
		)
		(layer "In1.Cu")
	)
	(gr_line
		(start 101.833934 -11.175746)
		(end 102.926134 -11.175746)
		(stroke
			(width 0.2032)
			(type default)
		)
		(layer "In1.Cu")
	)
	(gr_line
		(start 101.833934 -9.473946)
		(end 101.833934 -11.175746)
		(stroke
			(width 0.2032)
			(type default)
		)
		(layer "In1.Cu")
	)
	(gr_line
		(start 101.856032 -10.997946)
		(end 102.770432 -10.997946)
		(stroke
			(width 0.762)
			(type default)
		)
		(layer "In1.Cu")
	)
	(gr_line
		(start 101.856032 -9.575546)
		(end 102.770432 -9.575546)
		(stroke
			(width 0.762)
			(type default)
		)
		(layer "In1.Cu")
	)
	(gr_line
		(start 101.935534 -11.074146)
		(end 102.722934 -11.074146)
		(stroke
			(width 0.508)
			(type default)
		)
		(layer "In1.Cu")
	)
	(gr_line
		(start 101.935534 -11.048746)
		(end 101.935534 -9.524746)
		(stroke
			(width 0.508)
			(type default)
		)
		(layer "In1.Cu")
	)
	(gr_line
		(start 101.960934 -11.074146)
		(end 101.960934 -9.550146)
		(stroke
			(width 0.508)
			(type default)
		)
		(layer "In1.Cu")
	)
	(gr_line
		(start 101.983032 -11.124946)
		(end 102.897432 -11.124946)
		(stroke
			(width 0.762)
			(type default)
		)
		(layer "In1.Cu")
	)
	(gr_line
		(start 101.983032 -9.448546)
		(end 102.897432 -9.448546)
		(stroke
			(width 0.762)
			(type default)
		)
		(layer "In1.Cu")
	)
	(gr_line
		(start 101.986334 -9.524746)
		(end 102.722934 -9.524746)
		(stroke
			(width 0.508)
			(type default)
		)
		(layer "In1.Cu")
	)
	(gr_line
		(start 102.011734 -11.302746)
		(end 103.002334 -11.302746)
		(stroke
			(width 0.1016)
			(type default)
		)
		(layer "In1.Cu")
	)
	(gr_line
		(start 102.011734 -11.074146)
		(end 102.011734 -9.550146)
		(stroke
			(width 0.508)
			(type default)
		)
		(layer "In1.Cu")
	)
	(gr_line
		(start 102.037134 -11.074146)
		(end 102.037134 -9.550146)
		(stroke
			(width 0.508)
			(type default)
		)
		(layer "In1.Cu")
	)
	(gr_line
		(start 102.062534 -11.074146)
		(end 102.062534 -9.550146)
		(stroke
			(width 0.508)
			(type default)
		)
		(layer "In1.Cu")
	)
	(gr_line
		(start 102.087934 -11.074146)
		(end 102.087934 -9.550146)
		(stroke
			(width 0.508)
			(type default)
		)
		(layer "In1.Cu")
	)
	(gr_line
		(start 102.087934 -11.048746)
		(end 102.087934 -9.524746)
		(stroke
			(width 0.508)
			(type default)
		)
		(layer "In1.Cu")
	)
	(gr_line
		(start 102.113334 -11.074146)
		(end 102.113334 -9.550146)
		(stroke
			(width 0.508)
			(type default)
		)
		(layer "In1.Cu")
	)
	(gr_line
		(start 102.138734 -11.074146)
		(end 102.138734 -9.550146)
		(stroke
			(width 0.508)
			(type default)
		)
		(layer "In1.Cu")
	)
	(gr_line
		(start 102.189534 -11.074146)
		(end 102.189534 -9.550146)
		(stroke
			(width 0.508)
			(type default)
		)
		(layer "In1.Cu")
	)
	(gr_line
		(start 102.189534 -11.048746)
		(end 102.189534 -9.524746)
		(stroke
			(width 0.508)
			(type default)
		)
		(layer "In1.Cu")
	)
	(gr_line
		(start 102.214934 -11.074146)
		(end 102.214934 -9.550146)
		(stroke
			(width 0.508)
			(type default)
		)
		(layer "In1.Cu")
	)
	(gr_line
		(start 102.240334 -11.074146)
		(end 102.240334 -9.550146)
		(stroke
			(width 0.508)
			(type default)
		)
		(layer "In1.Cu")
	)
	(gr_line
		(start 102.265734 -11.074146)
		(end 102.265734 -9.550146)
		(stroke
			(width 0.508)
			(type default)
		)
		(layer "In1.Cu")
	)
	(gr_line
		(start 102.316534 -11.074146)
		(end 102.316534 -9.550146)
		(stroke
			(width 0.508)
			(type default)
		)
		(layer "In1.Cu")
	)
	(gr_line
		(start 102.341934 -11.074146)
		(end 102.341934 -9.550146)
		(stroke
			(width 0.508)
			(type default)
		)
		(layer "In1.Cu")
	)
	(gr_line
		(start 102.341934 -11.048746)
		(end 102.341934 -9.524746)
		(stroke
			(width 0.508)
			(type default)
		)
		(layer "In1.Cu")
	)
	(gr_line
		(start 102.367334 -11.074146)
		(end 102.367334 -9.550146)
		(stroke
			(width 0.508)
			(type default)
		)
		(layer "In1.Cu")
	)
	(gr_line
		(start 102.392734 -11.074146)
		(end 102.392734 -9.550146)
		(stroke
			(width 0.508)
			(type default)
		)
		(layer "In1.Cu")
	)
	(gr_line
		(start 102.418134 -11.074146)
		(end 102.418134 -9.550146)
		(stroke
			(width 0.508)
			(type default)
		)
		(layer "In1.Cu")
	)
	(gr_line
		(start 102.418134 -11.048746)
		(end 102.418134 -9.524746)
		(stroke
			(width 0.508)
			(type default)
		)
		(layer "In1.Cu")
	)
	(gr_line
		(start 102.443534 -11.074146)
		(end 102.443534 -9.550146)
		(stroke
			(width 0.508)
			(type default)
		)
		(layer "In1.Cu")
	)
	(gr_line
		(start 102.468934 -11.074146)
		(end 102.468934 -9.550146)
		(stroke
			(width 0.508)
			(type default)
		)
		(layer "In1.Cu")
	)
	(gr_line
		(start 102.468934 -11.048746)
		(end 102.468934 -9.524746)
		(stroke
			(width 0.508)
			(type default)
		)
		(layer "In1.Cu")
	)
	(gr_line
		(start 102.494334 -11.074146)
		(end 102.494334 -9.550146)
		(stroke
			(width 0.508)
			(type default)
		)
		(layer "In1.Cu")
	)
	(gr_line
		(start 102.494334 -11.048746)
		(end 102.494334 -9.524746)
		(stroke
			(width 0.508)
			(type default)
		)
		(layer "In1.Cu")
	)
	(gr_line
		(start 102.519734 -11.048746)
		(end 102.519734 -9.524746)
		(stroke
			(width 0.508)
			(type default)
		)
		(layer "In1.Cu")
	)
	(gr_line
		(start 102.545134 -11.074146)
		(end 102.545134 -9.550146)
		(stroke
			(width 0.508)
			(type default)
		)
		(layer "In1.Cu")
	)
	(gr_line
		(start 102.567232 -11.378946)
		(end 101.576632 -11.378946)
		(stroke
			(width 0.254)
			(type default)
		)
		(layer "In1.Cu")
	)
	(gr_line
		(start 102.570534 -11.048746)
		(end 102.570534 -9.524746)
		(stroke
			(width 0.508)
			(type default)
		)
		(layer "In1.Cu")
	)
	(gr_line
		(start 102.595934 -11.048746)
		(end 102.595934 -9.524746)
		(stroke
			(width 0.508)
			(type default)
		)
		(layer "In1.Cu")
	)
	(gr_line
		(start 102.621334 -11.074146)
		(end 102.621334 -9.550146)
		(stroke
			(width 0.508)
			(type default)
		)
		(layer "In1.Cu")
	)
	(gr_line
		(start 102.646734 -11.074146)
		(end 102.646734 -9.550146)
		(stroke
			(width 0.508)
			(type default)
		)
		(layer "In1.Cu")
	)
	(gr_line
		(start 102.646734 -11.048746)
		(end 102.646734 -9.524746)
		(stroke
			(width 0.508)
			(type default)
		)
		(layer "In1.Cu")
	)
	(gr_line
		(start 102.697534 -11.074146)
		(end 102.697534 -9.550146)
		(stroke
			(width 0.508)
			(type default)
		)
		(layer "In1.Cu")
	)
	(gr_line
		(start 102.697534 -11.048746)
		(end 102.697534 -9.524746)
		(stroke
			(width 0.508)
			(type default)
		)
		(layer "In1.Cu")
	)
	(gr_line
		(start 102.748334 -11.074146)
		(end 102.748334 -9.550146)
		(stroke
			(width 0.508)
			(type default)
		)
		(layer "In1.Cu")
	)
	(gr_line
		(start 102.748334 -11.048746)
		(end 102.748334 -9.524746)
		(stroke
			(width 0.508)
			(type default)
		)
		(layer "In1.Cu")
	)
	(gr_line
		(start 102.770432 -11.099546)
		(end 102.770432 -9.550146)
		(stroke
			(width 0.762)
			(type default)
		)
		(layer "In1.Cu")
	)
	(gr_line
		(start 102.773734 -11.074146)
		(end 102.773734 -9.550146)
		(stroke
			(width 0.508)
			(type default)
		)
		(layer "In1.Cu")
	)
	(gr_line
		(start 102.799134 -11.074146)
		(end 102.799134 -9.550146)
		(stroke
			(width 0.508)
			(type default)
		)
		(layer "In1.Cu")
	)
	(gr_line
		(start 102.849934 -11.226546)
		(end 102.875334 -11.226546)
		(stroke
			(width 0.2032)
			(type default)
		)
		(layer "In1.Cu")
	)
	(gr_line
		(start 102.875334 -11.226546)
		(end 102.875334 -9.473946)
		(stroke
			(width 0.2032)
			(type default)
		)
		(layer "In1.Cu")
	)
	(gr_line
		(start 102.875334 -9.473946)
		(end 101.833934 -9.473946)
		(stroke
			(width 0.2032)
			(type default)
		)
		(layer "In1.Cu")
	)
	(gr_line
		(start 102.897432 -11.124946)
		(end 102.897432 -9.575546)
		(stroke
			(width 0.762)
			(type default)
		)
		(layer "In1.Cu")
	)
	(gr_line
		(start 102.897432 -11.099546)
		(end 102.897432 -9.600946)
		(stroke
			(width 0.762)
			(type default)
		)
		(layer "In1.Cu")
	)
	(gr_line
		(start 102.897432 -10.997946)
		(end 102.897432 -9.448546)
		(stroke
			(width 0.762)
			(type default)
		)
		(layer "In1.Cu")
	)
	(gr_line
		(start 102.926134 -11.175746)
		(end 102.926134 -9.423146)
		(stroke
			(width 0.2032)
			(type default)
		)
		(layer "In1.Cu")
	)
	(gr_line
		(start 102.926134 -9.423146)
		(end 101.783134 -9.423146)
		(stroke
			(width 0.2032)
			(type default)
		)
		(layer "In1.Cu")
	)
	(gr_line
		(start 102.951534 -11.226546)
		(end 102.951534 -9.372346)
		(stroke
			(width 0.2032)
			(type default)
		)
		(layer "In1.Cu")
	)
	(gr_line
		(start 102.951534 -9.372346)
		(end 101.757734 -9.372346)
		(stroke
			(width 0.2032)
			(type default)
		)
		(layer "In1.Cu")
	)
	(gr_line
		(start 103.002334 -11.302746)
		(end 103.002334 -9.296146)
		(stroke
			(width 0.1016)
			(type default)
		)
		(layer "In1.Cu")
	)
	(gr_line
		(start 103.002334 -9.296146)
		(end 101.706934 -9.296146)
		(stroke
			(width 0.1016)
			(type default)
		)
		(layer "In1.Cu")
	)
	(gr_line
		(start 103.100632 -11.226546)
		(end 102.849934 -11.226546)
		(stroke
			(width 0.254)
			(type default)
		)
		(layer "In1.Cu")
	)
	(gr_line
		(start 103.100632 -9.372346)
		(end 103.100632 -11.226546)
		(stroke
			(width 0.254)
			(type default)
		)
		(layer "In1.Cu")
	)
	(gr_line
		(start 103.126032 -11.353546)
		(end 101.652832 -11.353546)
		(stroke
			(width 0.254)
			(type default)
		)
		(layer "In1.Cu")
	)
	(gr_line
		(start 103.126032 -9.245346)
		(end 103.126032 -11.353546)
		(stroke
			(width 0.254)
			(type default)
		)
		(layer "In1.Cu")
	)
	(gr_line
		(start 103.151432 -11.378946)
		(end 101.602032 -11.378946)
		(stroke
			(width 0.254)
			(type default)
		)
		(layer "In1.Cu")
	)
	(gr_line
		(start 103.151432 -9.194546)
		(end 103.151432 -11.378946)
		(stroke
			(width 0.254)
			(type default)
		)
		(layer "In1.Cu")
	)
	(gr_line
		(start 106.376724 -11.378946)
		(end 106.376724 -9.194546)
		(stroke
			(width 0.254)
			(type default)
		)
		(layer "In1.Cu")
	)
	(gr_line
		(start 106.376724 -9.194546)
		(end 107.951524 -9.194546)
		(stroke
			(width 0.254)
			(type default)
		)
		(layer "In1.Cu")
	)
	(gr_line
		(start 106.402124 -11.378946)
		(end 106.402124 -9.245346)
		(stroke
			(width 0.254)
			(type default)
		)
		(layer "In1.Cu")
	)
	(gr_line
		(start 106.402124 -9.245346)
		(end 107.926124 -9.245346)
		(stroke
			(width 0.254)
			(type default)
		)
		(layer "In1.Cu")
	)
	(gr_line
		(start 106.452924 -11.353546)
		(end 106.452924 -9.372346)
		(stroke
			(width 0.254)
			(type default)
		)
		(layer "In1.Cu")
	)
	(gr_line
		(start 106.452924 -9.372346)
		(end 107.900724 -9.372346)
		(stroke
			(width 0.254)
			(type default)
		)
		(layer "In1.Cu")
	)
	(gr_line
		(start 106.507026 -11.302746)
		(end 106.811826 -11.302746)
		(stroke
			(width 0.1016)
			(type default)
		)
		(layer "In1.Cu")
	)
	(gr_line
		(start 106.507026 -9.296146)
		(end 106.507026 -11.302746)
		(stroke
			(width 0.1016)
			(type default)
		)
		(layer "In1.Cu")
	)
	(gr_line
		(start 106.557826 -11.226546)
		(end 107.650026 -11.226546)
		(stroke
			(width 0.2032)
			(type default)
		)
		(layer "In1.Cu")
	)
	(gr_line
		(start 106.557826 -9.372346)
		(end 106.557826 -11.226546)
		(stroke
			(width 0.2032)
			(type default)
		)
		(layer "In1.Cu")
	)
	(gr_line
		(start 106.583226 -11.226546)
		(end 107.751626 -11.226546)
		(stroke
			(width 0.2032)
			(type default)
		)
		(layer "In1.Cu")
	)
	(gr_line
		(start 106.583226 -9.423146)
		(end 106.583226 -11.226546)
		(stroke
			(width 0.2032)
			(type default)
		)
		(layer "In1.Cu")
	)
	(gr_line
		(start 106.630724 -11.124946)
		(end 106.630724 -9.575546)
		(stroke
			(width 0.762)
			(type default)
		)
		(layer "In1.Cu")
	)
	(gr_line
		(start 106.630724 -11.124946)
		(end 107.545124 -11.124946)
		(stroke
			(width 0.762)
			(type default)
		)
		(layer "In1.Cu")
	)
	(gr_line
		(start 106.630724 -11.099546)
		(end 106.630724 -9.550146)
		(stroke
			(width 0.762)
			(type default)
		)
		(layer "In1.Cu")
	)
	(gr_line
		(start 106.630724 -10.997946)
		(end 106.630724 -9.448546)
		(stroke
			(width 0.762)
			(type default)
		)
		(layer "In1.Cu")
	)
	(gr_line
		(start 106.630724 -9.448546)
		(end 107.545124 -9.448546)
		(stroke
			(width 0.762)
			(type default)
		)
		(layer "In1.Cu")
	)
	(gr_line
		(start 106.634026 -11.175746)
		(end 107.726226 -11.175746)
		(stroke
			(width 0.2032)
			(type default)
		)
		(layer "In1.Cu")
	)
	(gr_line
		(start 106.634026 -9.473946)
		(end 106.634026 -11.175746)
		(stroke
			(width 0.2032)
			(type default)
		)
		(layer "In1.Cu")
	)
	(gr_line
		(start 106.656124 -10.997946)
		(end 107.570524 -10.997946)
		(stroke
			(width 0.762)
			(type default)
		)
		(layer "In1.Cu")
	)
	(gr_line
		(start 106.656124 -9.575546)
		(end 107.570524 -9.575546)
		(stroke
			(width 0.762)
			(type default)
		)
		(layer "In1.Cu")
	)
	(gr_line
		(start 106.735626 -11.074146)
		(end 107.523026 -11.074146)
		(stroke
			(width 0.508)
			(type default)
		)
		(layer "In1.Cu")
	)
	(gr_line
		(start 106.735626 -11.048746)
		(end 106.735626 -9.524746)
		(stroke
			(width 0.508)
			(type default)
		)
		(layer "In1.Cu")
	)
	(gr_line
		(start 106.761026 -11.074146)
		(end 106.761026 -9.550146)
		(stroke
			(width 0.508)
			(type default)
		)
		(layer "In1.Cu")
	)
	(gr_line
		(start 106.783124 -11.124946)
		(end 107.697524 -11.124946)
		(stroke
			(width 0.762)
			(type default)
		)
		(layer "In1.Cu")
	)
	(gr_line
		(start 106.783124 -9.448546)
		(end 107.697524 -9.448546)
		(stroke
			(width 0.762)
			(type default)
		)
		(layer "In1.Cu")
	)
	(gr_line
		(start 106.786426 -9.524746)
		(end 107.523026 -9.524746)
		(stroke
			(width 0.508)
			(type default)
		)
		(layer "In1.Cu")
	)
	(gr_line
		(start 106.811826 -11.302746)
		(end 107.802426 -11.302746)
		(stroke
			(width 0.1016)
			(type default)
		)
		(layer "In1.Cu")
	)
	(gr_line
		(start 106.811826 -11.074146)
		(end 106.811826 -9.550146)
		(stroke
			(width 0.508)
			(type default)
		)
		(layer "In1.Cu")
	)
	(gr_line
		(start 106.837226 -11.074146)
		(end 106.837226 -9.550146)
		(stroke
			(width 0.508)
			(type default)
		)
		(layer "In1.Cu")
	)
	(gr_line
		(start 106.862626 -11.074146)
		(end 106.862626 -9.550146)
		(stroke
			(width 0.508)
			(type default)
		)
		(layer "In1.Cu")
	)
	(gr_line
		(start 106.888026 -11.074146)
		(end 106.888026 -9.550146)
		(stroke
			(width 0.508)
			(type default)
		)
		(layer "In1.Cu")
	)
	(gr_line
		(start 106.888026 -11.048746)
		(end 106.888026 -9.524746)
		(stroke
			(width 0.508)
			(type default)
		)
		(layer "In1.Cu")
	)
	(gr_line
		(start 106.913426 -11.074146)
		(end 106.913426 -9.550146)
		(stroke
			(width 0.508)
			(type default)
		)
		(layer "In1.Cu")
	)
	(gr_line
		(start 106.938826 -11.074146)
		(end 106.938826 -9.550146)
		(stroke
			(width 0.508)
			(type default)
		)
		(layer "In1.Cu")
	)
	(gr_line
		(start 106.989626 -11.074146)
		(end 106.989626 -9.550146)
		(stroke
			(width 0.508)
			(type default)
		)
		(layer "In1.Cu")
	)
	(gr_line
		(start 106.989626 -11.048746)
		(end 106.989626 -9.524746)
		(stroke
			(width 0.508)
			(type default)
		)
		(layer "In1.Cu")
	)
	(gr_line
		(start 107.015026 -11.074146)
		(end 107.015026 -9.550146)
		(stroke
			(width 0.508)
			(type default)
		)
		(layer "In1.Cu")
	)
	(gr_line
		(start 107.040426 -11.074146)
		(end 107.040426 -9.550146)
		(stroke
			(width 0.508)
			(type default)
		)
		(layer "In1.Cu")
	)
	(gr_line
		(start 107.065826 -11.074146)
		(end 107.065826 -9.550146)
		(stroke
			(width 0.508)
			(type default)
		)
		(layer "In1.Cu")
	)
	(gr_line
		(start 107.116626 -11.074146)
		(end 107.116626 -9.550146)
		(stroke
			(width 0.508)
			(type default)
		)
		(layer "In1.Cu")
	)
	(gr_line
		(start 107.142026 -11.074146)
		(end 107.142026 -9.550146)
		(stroke
			(width 0.508)
			(type default)
		)
		(layer "In1.Cu")
	)
	(gr_line
		(start 107.142026 -11.048746)
		(end 107.142026 -9.524746)
		(stroke
			(width 0.508)
			(type default)
		)
		(layer "In1.Cu")
	)
	(gr_line
		(start 107.167426 -11.074146)
		(end 107.167426 -9.550146)
		(stroke
			(width 0.508)
			(type default)
		)
		(layer "In1.Cu")
	)
	(gr_line
		(start 107.192826 -11.074146)
		(end 107.192826 -9.550146)
		(stroke
			(width 0.508)
			(type default)
		)
		(layer "In1.Cu")
	)
	(gr_line
		(start 107.218226 -11.074146)
		(end 107.218226 -9.550146)
		(stroke
			(width 0.508)
			(type default)
		)
		(layer "In1.Cu")
	)
	(gr_line
		(start 107.218226 -11.048746)
		(end 107.218226 -9.524746)
		(stroke
			(width 0.508)
			(type default)
		)
		(layer "In1.Cu")
	)
	(gr_line
		(start 107.243626 -11.074146)
		(end 107.243626 -9.550146)
		(stroke
			(width 0.508)
			(type default)
		)
		(layer "In1.Cu")
	)
	(gr_line
		(start 107.269026 -11.074146)
		(end 107.269026 -9.550146)
		(stroke
			(width 0.508)
			(type default)
		)
		(layer "In1.Cu")
	)
	(gr_line
		(start 107.269026 -11.048746)
		(end 107.269026 -9.524746)
		(stroke
			(width 0.508)
			(type default)
		)
		(layer "In1.Cu")
	)
	(gr_line
		(start 107.294426 -11.074146)
		(end 107.294426 -9.550146)
		(stroke
			(width 0.508)
			(type default)
		)
		(layer "In1.Cu")
	)
	(gr_line
		(start 107.294426 -11.048746)
		(end 107.294426 -9.524746)
		(stroke
			(width 0.508)
			(type default)
		)
		(layer "In1.Cu")
	)
	(gr_line
		(start 107.319826 -11.048746)
		(end 107.319826 -9.524746)
		(stroke
			(width 0.508)
			(type default)
		)
		(layer "In1.Cu")
	)
	(gr_line
		(start 107.345226 -11.074146)
		(end 107.345226 -9.550146)
		(stroke
			(width 0.508)
			(type default)
		)
		(layer "In1.Cu")
	)
	(gr_line
		(start 107.367324 -11.378946)
		(end 106.376724 -11.378946)
		(stroke
			(width 0.254)
			(type default)
		)
		(layer "In1.Cu")
	)
	(gr_line
		(start 107.370626 -11.048746)
		(end 107.370626 -9.524746)
		(stroke
			(width 0.508)
			(type default)
		)
		(layer "In1.Cu")
	)
	(gr_line
		(start 107.396026 -11.048746)
		(end 107.396026 -9.524746)
		(stroke
			(width 0.508)
			(type default)
		)
		(layer "In1.Cu")
	)
	(gr_line
		(start 107.421426 -11.074146)
		(end 107.421426 -9.550146)
		(stroke
			(width 0.508)
			(type default)
		)
		(layer "In1.Cu")
	)
	(gr_line
		(start 107.446826 -11.074146)
		(end 107.446826 -9.550146)
		(stroke
			(width 0.508)
			(type default)
		)
		(layer "In1.Cu")
	)
	(gr_line
		(start 107.446826 -11.048746)
		(end 107.446826 -9.524746)
		(stroke
			(width 0.508)
			(type default)
		)
		(layer "In1.Cu")
	)
	(gr_line
		(start 107.497626 -11.074146)
		(end 107.497626 -9.550146)
		(stroke
			(width 0.508)
			(type default)
		)
		(layer "In1.Cu")
	)
	(gr_line
		(start 107.497626 -11.048746)
		(end 107.497626 -9.524746)
		(stroke
			(width 0.508)
			(type default)
		)
		(layer "In1.Cu")
	)
	(gr_line
		(start 107.548426 -11.074146)
		(end 107.548426 -9.550146)
		(stroke
			(width 0.508)
			(type default)
		)
		(layer "In1.Cu")
	)
	(gr_line
		(start 107.548426 -11.048746)
		(end 107.548426 -9.524746)
		(stroke
			(width 0.508)
			(type default)
		)
		(layer "In1.Cu")
	)
	(gr_line
		(start 107.570524 -11.099546)
		(end 107.570524 -9.550146)
		(stroke
			(width 0.762)
			(type default)
		)
		(layer "In1.Cu")
	)
	(gr_line
		(start 107.573826 -11.074146)
		(end 107.573826 -9.550146)
		(stroke
			(width 0.508)
			(type default)
		)
		(layer "In1.Cu")
	)
	(gr_line
		(start 107.599226 -11.074146)
		(end 107.599226 -9.550146)
		(stroke
			(width 0.508)
			(type default)
		)
		(layer "In1.Cu")
	)
	(gr_line
		(start 107.650026 -11.226546)
		(end 107.675426 -11.226546)
		(stroke
			(width 0.2032)
			(type default)
		)
		(layer "In1.Cu")
	)
	(gr_line
		(start 107.675426 -11.226546)
		(end 107.675426 -9.473946)
		(stroke
			(width 0.2032)
			(type default)
		)
		(layer "In1.Cu")
	)
	(gr_line
		(start 107.675426 -9.473946)
		(end 106.634026 -9.473946)
		(stroke
			(width 0.2032)
			(type default)
		)
		(layer "In1.Cu")
	)
	(gr_line
		(start 107.697524 -11.124946)
		(end 107.697524 -9.575546)
		(stroke
			(width 0.762)
			(type default)
		)
		(layer "In1.Cu")
	)
	(gr_line
		(start 107.697524 -11.099546)
		(end 107.697524 -9.600946)
		(stroke
			(width 0.762)
			(type default)
		)
		(layer "In1.Cu")
	)
	(gr_line
		(start 107.697524 -10.997946)
		(end 107.697524 -9.448546)
		(stroke
			(width 0.762)
			(type default)
		)
		(layer "In1.Cu")
	)
	(gr_line
		(start 107.726226 -11.175746)
		(end 107.726226 -9.423146)
		(stroke
			(width 0.2032)
			(type default)
		)
		(layer "In1.Cu")
	)
	(gr_line
		(start 107.726226 -9.423146)
		(end 106.583226 -9.423146)
		(stroke
			(width 0.2032)
			(type default)
		)
		(layer "In1.Cu")
	)
	(gr_line
		(start 107.751626 -11.226546)
		(end 107.751626 -9.372346)
		(stroke
			(width 0.2032)
			(type default)
		)
		(layer "In1.Cu")
	)
	(gr_line
		(start 107.751626 -9.372346)
		(end 106.557826 -9.372346)
		(stroke
			(width 0.2032)
			(type default)
		)
		(layer "In1.Cu")
	)
	(gr_line
		(start 107.802426 -11.302746)
		(end 107.802426 -9.296146)
		(stroke
			(width 0.1016)
			(type default)
		)
		(layer "In1.Cu")
	)
	(gr_line
		(start 107.802426 -9.296146)
		(end 106.507026 -9.296146)
		(stroke
			(width 0.1016)
			(type default)
		)
		(layer "In1.Cu")
	)
	(gr_line
		(start 107.900724 -11.226546)
		(end 107.650026 -11.226546)
		(stroke
			(width 0.254)
			(type default)
		)
		(layer "In1.Cu")
	)
	(gr_line
		(start 107.900724 -9.372346)
		(end 107.900724 -11.226546)
		(stroke
			(width 0.254)
			(type default)
		)
		(layer "In1.Cu")
	)
	(gr_line
		(start 107.926124 -11.353546)
		(end 106.452924 -11.353546)
		(stroke
			(width 0.254)
			(type default)
		)
		(layer "In1.Cu")
	)
	(gr_line
		(start 107.926124 -9.245346)
		(end 107.926124 -11.353546)
		(stroke
			(width 0.254)
			(type default)
		)
		(layer "In1.Cu")
	)
	(gr_line
		(start 107.951524 -11.378946)
		(end 106.402124 -11.378946)
		(stroke
			(width 0.254)
			(type default)
		)
		(layer "In1.Cu")
	)
	(gr_line
		(start 107.951524 -9.194546)
		(end 107.951524 -11.378946)
		(stroke
			(width 0.254)
			(type default)
		)
		(layer "In1.Cu")
	)
	(gr_arc
		(start 113.069878 -51.319938)
		(mid 113.362771 -52.027043)
		(end 114.069876 -52.319936)
		(stroke
			(width 1.016)
			(type default)
		)
		(layer "In1.Cu")
	)
	(gr_arc
		(start 113.069878 -50.8)
		(mid 112.776984 -50.092902)
		(end 112.06988 -49.800002)
		(stroke
			(width 1.016)
			(type default)
		)
		(layer "In1.Cu")
	)
	(gr_line
		(start 113.069878 -50.8)
		(end 113.069878 -51.319938)
		(stroke
			(width 1.016)
			(type default)
		)
		(layer "In1.Cu")
	)
	(gr_line
		(start 113.76152 -9.1948)
		(end 115.18392 -9.1948)
		(stroke
			(width 1.016)
			(type default)
		)
		(layer "In1.Cu")
	)
	(gr_line
		(start 114.069876 -52.319936)
		(end 132.990082 -52.319936)
		(stroke
			(width 1.016)
			(type default)
		)
		(layer "In1.Cu")
	)
	(gr_line
		(start 117.856 -13.843)
		(end 118.6942 -13.843)
		(stroke
			(width 0.1016)
			(type default)
		)
		(layer "In1.Cu")
	)
	(gr_line
		(start 117.856 -11.1252)
		(end 117.856 -13.843)
		(stroke
			(width 0.1016)
			(type default)
		)
		(layer "In1.Cu")
	)
	(gr_line
		(start 117.856 -9.64311)
		(end 118.6942 -9.64311)
		(stroke
			(width 0.1016)
			(type default)
		)
		(layer "In1.Cu")
	)
	(gr_line
		(start 117.856 -6.92531)
		(end 117.856 -9.64311)
		(stroke
			(width 0.1016)
			(type default)
		)
		(layer "In1.Cu")
	)
	(gr_line
		(start 117.8814 -13.8176)
		(end 117.8814 -11.1506)
		(stroke
			(width 0.127)
			(type default)
		)
		(layer "In1.Cu")
	)
	(gr_line
		(start 117.8814 -11.1506)
		(end 119.1768 -11.1506)
		(stroke
			(width 0.127)
			(type default)
		)
		(layer "In1.Cu")
	)
	(gr_line
		(start 117.8814 -9.61771)
		(end 117.8814 -6.95071)
		(stroke
			(width 0.127)
			(type default)
		)
		(layer "In1.Cu")
	)
	(gr_line
		(start 117.8814 -6.95071)
		(end 119.1768 -6.95071)
		(stroke
			(width 0.127)
			(type default)
		)
		(layer "In1.Cu")
	)
	(gr_line
		(start 117.9068 -13.8176)
		(end 117.9068 -11.176)
		(stroke
			(width 0.127)
			(type default)
		)
		(layer "In1.Cu")
	)
	(gr_line
		(start 117.9068 -13.7922)
		(end 117.9068 -11.176)
		(stroke
			(width 0.1778)
			(type default)
		)
		(layer "In1.Cu")
	)
	(gr_line
		(start 117.9068 -11.176)
		(end 119.1514 -11.176)
		(stroke
			(width 0.127)
			(type default)
		)
		(layer "In1.Cu")
	)
	(gr_line
		(start 117.9068 -11.176)
		(end 119.1514 -11.176)
		(stroke
			(width 0.1778)
			(type default)
		)
		(layer "In1.Cu")
	)
	(gr_line
		(start 117.9068 -9.61771)
		(end 117.9068 -6.97611)
		(stroke
			(width 0.127)
			(type default)
		)
		(layer "In1.Cu")
	)
	(gr_line
		(start 117.9068 -9.59231)
		(end 117.9068 -6.97611)
		(stroke
			(width 0.1778)
			(type default)
		)
		(layer "In1.Cu")
	)
	(gr_line
		(start 117.9068 -6.97611)
		(end 119.1514 -6.97611)
		(stroke
			(width 0.127)
			(type default)
		)
		(layer "In1.Cu")
	)
	(gr_line
		(start 117.9068 -6.97611)
		(end 119.1514 -6.97611)
		(stroke
			(width 0.1778)
			(type default)
		)
		(layer "In1.Cu")
	)
	(gr_line
		(start 117.9322 -13.7922)
		(end 117.9322 -11.2014)
		(stroke
			(width 0.1778)
			(type default)
		)
		(layer "In1.Cu")
	)
	(gr_line
		(start 117.9322 -11.2014)
		(end 119.126 -11.2014)
		(stroke
			(width 0.1778)
			(type default)
		)
		(layer "In1.Cu")
	)
	(gr_line
		(start 117.9322 -9.59231)
		(end 117.9322 -7.00151)
		(stroke
			(width 0.1778)
			(type default)
		)
		(layer "In1.Cu")
	)
	(gr_line
		(start 117.9322 -7.00151)
		(end 119.126 -7.00151)
		(stroke
			(width 0.1778)
			(type default)
		)
		(layer "In1.Cu")
	)
	(gr_line
		(start 117.9576 -13.7668)
		(end 117.9576 -11.2268)
		(stroke
			(width 0.254)
			(type default)
		)
		(layer "In1.Cu")
	)
	(gr_line
		(start 117.9576 -11.2268)
		(end 119.126 -11.2268)
		(stroke
			(width 0.254)
			(type default)
		)
		(layer "In1.Cu")
	)
	(gr_line
		(start 117.9576 -9.56691)
		(end 117.9576 -7.02691)
		(stroke
			(width 0.254)
			(type default)
		)
		(layer "In1.Cu")
	)
	(gr_line
		(start 117.9576 -7.02691)
		(end 119.126 -7.02691)
		(stroke
			(width 0.254)
			(type default)
		)
		(layer "In1.Cu")
	)
	(gr_line
		(start 117.983 -13.7668)
		(end 117.983 -11.2522)
		(stroke
			(width 0.254)
			(type default)
		)
		(layer "In1.Cu")
	)
	(gr_line
		(start 117.983 -11.2522)
		(end 119.1006 -11.2522)
		(stroke
			(width 0.254)
			(type default)
		)
		(layer "In1.Cu")
	)
	(gr_line
		(start 117.983 -9.56691)
		(end 117.983 -7.05231)
		(stroke
			(width 0.254)
			(type default)
		)
		(layer "In1.Cu")
	)
	(gr_line
		(start 117.983 -7.05231)
		(end 119.1006 -7.05231)
		(stroke
			(width 0.254)
			(type default)
		)
		(layer "In1.Cu")
	)
	(gr_line
		(start 118.0084 -13.716)
		(end 118.0084 -11.2776)
		(stroke
			(width 0.3556)
			(type default)
		)
		(layer "In1.Cu")
	)
	(gr_line
		(start 118.0084 -11.2776)
		(end 119.0498 -11.2776)
		(stroke
			(width 0.3556)
			(type default)
		)
		(layer "In1.Cu")
	)
	(gr_line
		(start 118.0084 -9.51611)
		(end 118.0084 -7.07771)
		(stroke
			(width 0.3556)
			(type default)
		)
		(layer "In1.Cu")
	)
	(gr_line
		(start 118.0084 -7.07771)
		(end 119.0498 -7.07771)
		(stroke
			(width 0.3556)
			(type default)
		)
		(layer "In1.Cu")
	)
	(gr_line
		(start 118.0592 -13.6906)
		(end 118.0592 -11.3284)
		(stroke
			(width 0.381)
			(type default)
		)
		(layer "In1.Cu")
	)
	(gr_line
		(start 118.0592 -11.3284)
		(end 118.999 -11.3284)
		(stroke
			(width 0.381)
			(type default)
		)
		(layer "In1.Cu")
	)
	(gr_line
		(start 118.0592 -9.49071)
		(end 118.0592 -7.12851)
		(stroke
			(width 0.381)
			(type default)
		)
		(layer "In1.Cu")
	)
	(gr_line
		(start 118.0592 -7.12851)
		(end 118.999 -7.12851)
		(stroke
			(width 0.381)
			(type default)
		)
		(layer "In1.Cu")
	)
	(gr_line
		(start 118.1354 -13.6398)
		(end 118.1354 -11.3792)
		(stroke
			(width 0.381)
			(type default)
		)
		(layer "In1.Cu")
	)
	(gr_line
		(start 118.1354 -11.3792)
		(end 118.9482 -11.3792)
		(stroke
			(width 0.381)
			(type default)
		)
		(layer "In1.Cu")
	)
	(gr_line
		(start 118.1354 -9.43991)
		(end 118.1354 -7.17931)
		(stroke
			(width 0.381)
			(type default)
		)
		(layer "In1.Cu")
	)
	(gr_line
		(start 118.1354 -7.17931)
		(end 118.9482 -7.17931)
		(stroke
			(width 0.381)
			(type default)
		)
		(layer "In1.Cu")
	)
	(gr_line
		(start 118.1608 -13.5636)
		(end 118.1608 -11.3792)
		(stroke
			(width 0.508)
			(type default)
		)
		(layer "In1.Cu")
	)
	(gr_line
		(start 118.1608 -11.3792)
		(end 118.9228 -11.3792)
		(stroke
			(width 0.508)
			(type default)
		)
		(layer "In1.Cu")
	)
	(gr_line
		(start 118.1608 -9.36371)
		(end 118.1608 -7.17931)
		(stroke
			(width 0.508)
			(type default)
		)
		(layer "In1.Cu")
	)
	(gr_line
		(start 118.1608 -7.17931)
		(end 118.9228 -7.17931)
		(stroke
			(width 0.508)
			(type default)
		)
		(layer "In1.Cu")
	)
	(gr_line
		(start 118.1862 -13.4112)
		(end 118.7704 -13.4112)
		(stroke
			(width 0.762)
			(type default)
		)
		(layer "In1.Cu")
	)
	(gr_line
		(start 118.1862 -11.5824)
		(end 118.7704 -11.5824)
		(stroke
			(width 0.762)
			(type default)
		)
		(layer "In1.Cu")
	)
	(gr_line
		(start 118.1862 -9.21131)
		(end 118.7704 -9.21131)
		(stroke
			(width 0.762)
			(type default)
		)
		(layer "In1.Cu")
	)
	(gr_line
		(start 118.1862 -7.38251)
		(end 118.7704 -7.38251)
		(stroke
			(width 0.762)
			(type default)
		)
		(layer "In1.Cu")
	)
	(gr_line
		(start 118.2116 -13.5636)
		(end 118.2116 -11.43)
		(stroke
			(width 0.635)
			(type default)
		)
		(layer "In1.Cu")
	)
	(gr_line
		(start 118.2116 -13.5128)
		(end 118.2116 -11.4808)
		(stroke
			(width 0.762)
			(type default)
		)
		(layer "In1.Cu")
	)
	(gr_line
		(start 118.2116 -11.43)
		(end 118.8974 -11.43)
		(stroke
			(width 0.635)
			(type default)
		)
		(layer "In1.Cu")
	)
	(gr_line
		(start 118.2116 -9.36371)
		(end 118.2116 -7.23011)
		(stroke
			(width 0.635)
			(type default)
		)
		(layer "In1.Cu")
	)
	(gr_line
		(start 118.2116 -9.31291)
		(end 118.2116 -7.28091)
		(stroke
			(width 0.762)
			(type default)
		)
		(layer "In1.Cu")
	)
	(gr_line
		(start 118.2116 -7.23011)
		(end 118.8974 -7.23011)
		(stroke
			(width 0.635)
			(type default)
		)
		(layer "In1.Cu")
	)
	(gr_line
		(start 118.237 -13.5128)
		(end 118.237 -11.4808)
		(stroke
			(width 0.762)
			(type default)
		)
		(layer "In1.Cu")
	)
	(gr_line
		(start 118.237 -11.4808)
		(end 118.8212 -11.4808)
		(stroke
			(width 0.762)
			(type default)
		)
		(layer "In1.Cu")
	)
	(gr_line
		(start 118.237 -9.31291)
		(end 118.237 -7.28091)
		(stroke
			(width 0.762)
			(type default)
		)
		(layer "In1.Cu")
	)
	(gr_line
		(start 118.237 -7.28091)
		(end 118.8212 -7.28091)
		(stroke
			(width 0.762)
			(type default)
		)
		(layer "In1.Cu")
	)
	(gr_line
		(start 118.2624 -13.5128)
		(end 118.2624 -11.4808)
		(stroke
			(width 0.762)
			(type default)
		)
		(layer "In1.Cu")
	)
	(gr_line
		(start 118.2624 -13.5128)
		(end 118.8466 -13.5128)
		(stroke
			(width 0.762)
			(type default)
		)
		(layer "In1.Cu")
	)
	(gr_line
		(start 118.2624 -13.4874)
		(end 118.2624 -11.4554)
		(stroke
			(width 0.762)
			(type default)
		)
		(layer "In1.Cu")
	)
	(gr_line
		(start 118.2624 -9.31291)
		(end 118.2624 -7.28091)
		(stroke
			(width 0.762)
			(type default)
		)
		(layer "In1.Cu")
	)
	(gr_line
		(start 118.2624 -9.31291)
		(end 118.8466 -9.31291)
		(stroke
			(width 0.762)
			(type default)
		)
		(layer "In1.Cu")
	)
	(gr_line
		(start 118.2624 -9.28751)
		(end 118.2624 -7.25551)
		(stroke
			(width 0.762)
			(type default)
		)
		(layer "In1.Cu")
	)
	(gr_line
		(start 118.2878 -13.5128)
		(end 118.2878 -11.4808)
		(stroke
			(width 0.762)
			(type default)
		)
		(layer "In1.Cu")
	)
	(gr_line
		(start 118.2878 -9.31291)
		(end 118.2878 -7.28091)
		(stroke
			(width 0.762)
			(type default)
		)
		(layer "In1.Cu")
	)
	(gr_line
		(start 118.3132 -13.5128)
		(end 118.3132 -11.4808)
		(stroke
			(width 0.762)
			(type default)
		)
		(layer "In1.Cu")
	)
	(gr_line
		(start 118.3132 -9.31291)
		(end 118.3132 -7.28091)
		(stroke
			(width 0.762)
			(type default)
		)
		(layer "In1.Cu")
	)
	(gr_line
		(start 118.3386 -13.5128)
		(end 118.3386 -11.4808)
		(stroke
			(width 0.762)
			(type default)
		)
		(layer "In1.Cu")
	)
	(gr_line
		(start 118.3386 -9.31291)
		(end 118.3386 -7.28091)
		(stroke
			(width 0.762)
			(type default)
		)
		(layer "In1.Cu")
	)
	(gr_line
		(start 118.3894 -13.5128)
		(end 118.3894 -11.4808)
		(stroke
			(width 0.762)
			(type default)
		)
		(layer "In1.Cu")
	)
	(gr_line
		(start 118.3894 -9.31291)
		(end 118.3894 -7.28091)
		(stroke
			(width 0.762)
			(type default)
		)
		(layer "In1.Cu")
	)
	(gr_line
		(start 118.4148 -13.5128)
		(end 118.4148 -11.4808)
		(stroke
			(width 0.762)
			(type default)
		)
		(layer "In1.Cu")
	)
	(gr_line
		(start 118.4148 -9.31291)
		(end 118.4148 -7.28091)
		(stroke
			(width 0.762)
			(type default)
		)
		(layer "In1.Cu")
	)
	(gr_line
		(start 118.4402 -13.5128)
		(end 118.4402 -11.7094)
		(stroke
			(width 0.635)
			(type default)
		)
		(layer "In1.Cu")
	)
	(gr_line
		(start 118.4402 -11.7094)
		(end 118.5418 -11.7094)
		(stroke
			(width 0.635)
			(type default)
		)
		(layer "In1.Cu")
	)
	(gr_line
		(start 118.4402 -9.31291)
		(end 118.4402 -7.50951)
		(stroke
			(width 0.635)
			(type default)
		)
		(layer "In1.Cu")
	)
	(gr_line
		(start 118.4402 -7.50951)
		(end 118.5418 -7.50951)
		(stroke
			(width 0.635)
			(type default)
		)
		(layer "In1.Cu")
	)
	(gr_line
		(start 118.4656 -13.5128)
		(end 118.4656 -11.4808)
		(stroke
			(width 0.762)
			(type default)
		)
		(layer "In1.Cu")
	)
	(gr_line
		(start 118.4656 -13.4874)
		(end 118.4656 -11.4554)
		(stroke
			(width 0.762)
			(type default)
		)
		(layer "In1.Cu")
	)
	(gr_line
		(start 118.4656 -13.4366)
		(end 118.4656 -11.6586)
		(stroke
			(width 0.635)
			(type default)
		)
		(layer "In1.Cu")
	)
	(gr_line
		(start 118.4656 -9.31291)
		(end 118.4656 -7.28091)
		(stroke
			(width 0.762)
			(type default)
		)
		(layer "In1.Cu")
	)
	(gr_line
		(start 118.4656 -9.28751)
		(end 118.4656 -7.25551)
		(stroke
			(width 0.762)
			(type default)
		)
		(layer "In1.Cu")
	)
	(gr_line
		(start 118.4656 -9.23671)
		(end 118.4656 -7.45871)
		(stroke
			(width 0.635)
			(type default)
		)
		(layer "In1.Cu")
	)
	(gr_line
		(start 118.5164 -13.5128)
		(end 118.5164 -11.4808)
		(stroke
			(width 0.762)
			(type default)
		)
		(layer "In1.Cu")
	)
	(gr_line
		(start 118.5164 -9.31291)
		(end 118.5164 -7.28091)
		(stroke
			(width 0.762)
			(type default)
		)
		(layer "In1.Cu")
	)
	(gr_line
		(start 118.5418 -13.5128)
		(end 118.5418 -11.4808)
		(stroke
			(width 0.762)
			(type default)
		)
		(layer "In1.Cu")
	)
	(gr_line
		(start 118.5418 -13.4874)
		(end 118.5418 -11.4554)
		(stroke
			(width 0.762)
			(type default)
		)
		(layer "In1.Cu")
	)
	(gr_line
		(start 118.5418 -13.4366)
		(end 118.4656 -13.4366)
		(stroke
			(width 0.635)
			(type default)
		)
		(layer "In1.Cu")
	)
	(gr_line
		(start 118.5418 -11.7094)
		(end 118.5418 -13.4366)
		(stroke
			(width 0.635)
			(type default)
		)
		(layer "In1.Cu")
	)
	(gr_line
		(start 118.5418 -9.31291)
		(end 118.5418 -7.28091)
		(stroke
			(width 0.762)
			(type default)
		)
		(layer "In1.Cu")
	)
	(gr_line
		(start 118.5418 -9.28751)
		(end 118.5418 -7.25551)
		(stroke
			(width 0.762)
			(type default)
		)
		(layer "In1.Cu")
	)
	(gr_line
		(start 118.5418 -9.23671)
		(end 118.4656 -9.23671)
		(stroke
			(width 0.635)
			(type default)
		)
		(layer "In1.Cu")
	)
	(gr_line
		(start 118.5418 -7.50951)
		(end 118.5418 -9.23671)
		(stroke
			(width 0.635)
			(type default)
		)
		(layer "In1.Cu")
	)
	(gr_line
		(start 118.5926 -13.4874)
		(end 118.5926 -11.4554)
		(stroke
			(width 0.762)
			(type default)
		)
		(layer "In1.Cu")
	)
	(gr_line
		(start 118.5926 -9.28751)
		(end 118.5926 -7.25551)
		(stroke
			(width 0.762)
			(type default)
		)
		(layer "In1.Cu")
	)
	(gr_line
		(start 118.618 -13.4874)
		(end 118.618 -11.4554)
		(stroke
			(width 0.762)
			(type default)
		)
		(layer "In1.Cu")
	)
	(gr_line
		(start 118.618 -9.28751)
		(end 118.618 -7.25551)
		(stroke
			(width 0.762)
			(type default)
		)
		(layer "In1.Cu")
	)
	(gr_line
		(start 118.6688 -13.5128)
		(end 118.6688 -11.4808)
		(stroke
			(width 0.762)
			(type default)
		)
		(layer "In1.Cu")
	)
	(gr_line
		(start 118.6688 -9.31291)
		(end 118.6688 -7.28091)
		(stroke
			(width 0.762)
			(type default)
		)
		(layer "In1.Cu")
	)
	(gr_line
		(start 118.6942 -13.843)
		(end 119.2022 -13.843)
		(stroke
			(width 0.1016)
			(type default)
		)
		(layer "In1.Cu")
	)
	(gr_line
		(start 118.6942 -13.4874)
		(end 118.6942 -11.4554)
		(stroke
			(width 0.762)
			(type default)
		)
		(layer "In1.Cu")
	)
	(gr_line
		(start 118.6942 -9.64311)
		(end 119.2022 -9.64311)
		(stroke
			(width 0.1016)
			(type default)
		)
		(layer "In1.Cu")
	)
	(gr_line
		(start 118.6942 -9.28751)
		(end 118.6942 -7.25551)
		(stroke
			(width 0.762)
			(type default)
		)
		(layer "In1.Cu")
	)
	(gr_line
		(start 118.745 -13.5128)
		(end 118.745 -11.4808)
		(stroke
			(width 0.762)
			(type default)
		)
		(layer "In1.Cu")
	)
	(gr_line
		(start 118.745 -13.4874)
		(end 118.745 -11.4554)
		(stroke
			(width 0.762)
			(type default)
		)
		(layer "In1.Cu")
	)
	(gr_line
		(start 118.745 -9.31291)
		(end 118.745 -7.28091)
		(stroke
			(width 0.762)
			(type default)
		)
		(layer "In1.Cu")
	)
	(gr_line
		(start 118.745 -9.28751)
		(end 118.745 -7.25551)
		(stroke
			(width 0.762)
			(type default)
		)
		(layer "In1.Cu")
	)
	(gr_line
		(start 118.7704 -13.4874)
		(end 118.7704 -11.4554)
		(stroke
			(width 0.762)
			(type default)
		)
		(layer "In1.Cu")
	)
	(gr_line
		(start 118.7704 -9.28751)
		(end 118.7704 -7.25551)
		(stroke
			(width 0.762)
			(type default)
		)
		(layer "In1.Cu")
	)
	(gr_line
		(start 118.7958 -13.5636)
		(end 118.1608 -13.5636)
		(stroke
			(width 0.508)
			(type default)
		)
		(layer "In1.Cu")
	)
	(gr_line
		(start 118.7958 -13.5636)
		(end 118.2116 -13.5636)
		(stroke
			(width 0.635)
			(type default)
		)
		(layer "In1.Cu")
	)
	(gr_line
		(start 118.7958 -9.36371)
		(end 118.1608 -9.36371)
		(stroke
			(width 0.508)
			(type default)
		)
		(layer "In1.Cu")
	)
	(gr_line
		(start 118.7958 -9.36371)
		(end 118.2116 -9.36371)
		(stroke
			(width 0.635)
			(type default)
		)
		(layer "In1.Cu")
	)
	(gr_line
		(start 118.8212 -13.4874)
		(end 118.8212 -11.4554)
		(stroke
			(width 0.762)
			(type default)
		)
		(layer "In1.Cu")
	)
	(gr_line
		(start 118.8212 -9.28751)
		(end 118.8212 -7.25551)
		(stroke
			(width 0.762)
			(type default)
		)
		(layer "In1.Cu")
	)
	(gr_line
		(start 118.8466 -13.716)
		(end 118.0084 -13.716)
		(stroke
			(width 0.3556)
			(type default)
		)
		(layer "In1.Cu")
	)
	(gr_line
		(start 118.8466 -13.6906)
		(end 118.0592 -13.6906)
		(stroke
			(width 0.381)
			(type default)
		)
		(layer "In1.Cu")
	)
	(gr_line
		(start 118.8466 -9.51611)
		(end 118.0084 -9.51611)
		(stroke
			(width 0.3556)
			(type default)
		)
		(layer "In1.Cu")
	)
	(gr_line
		(start 118.8466 -9.49071)
		(end 118.0592 -9.49071)
		(stroke
			(width 0.381)
			(type default)
		)
		(layer "In1.Cu")
	)
	(gr_line
		(start 118.872 -13.5128)
		(end 118.872 -11.4808)
		(stroke
			(width 0.762)
			(type default)
		)
		(layer "In1.Cu")
	)
	(gr_line
		(start 118.872 -9.31291)
		(end 118.872 -7.28091)
		(stroke
			(width 0.762)
			(type default)
		)
		(layer "In1.Cu")
	)
	(gr_line
		(start 118.8974 -13.7668)
		(end 117.9576 -13.7668)
		(stroke
			(width 0.254)
			(type default)
		)
		(layer "In1.Cu")
	)
	(gr_line
		(start 118.8974 -13.5128)
		(end 118.4402 -13.5128)
		(stroke
			(width 0.635)
			(type default)
		)
		(layer "In1.Cu")
	)
	(gr_line
		(start 118.8974 -11.43)
		(end 118.8974 -13.5128)
		(stroke
			(width 0.635)
			(type default)
		)
		(layer "In1.Cu")
	)
	(gr_line
		(start 118.8974 -9.56691)
		(end 117.9576 -9.56691)
		(stroke
			(width 0.254)
			(type default)
		)
		(layer "In1.Cu")
	)
	(gr_line
		(start 118.8974 -9.31291)
		(end 118.4402 -9.31291)
		(stroke
			(width 0.635)
			(type default)
		)
		(layer "In1.Cu")
	)
	(gr_line
		(start 118.8974 -7.23011)
		(end 118.8974 -9.31291)
		(stroke
			(width 0.635)
			(type default)
		)
		(layer "In1.Cu")
	)
	(gr_line
		(start 118.9228 -13.7922)
		(end 117.9068 -13.7922)
		(stroke
			(width 0.1778)
			(type default)
		)
		(layer "In1.Cu")
	)
	(gr_line
		(start 118.9228 -13.5636)
		(end 118.7958 -13.5636)
		(stroke
			(width 0.508)
			(type default)
		)
		(layer "In1.Cu")
	)
	(gr_line
		(start 118.9228 -11.3792)
		(end 118.9228 -13.5636)
		(stroke
			(width 0.508)
			(type default)
		)
		(layer "In1.Cu")
	)
	(gr_line
		(start 118.9228 -9.59231)
		(end 117.9068 -9.59231)
		(stroke
			(width 0.1778)
			(type default)
		)
		(layer "In1.Cu")
	)
	(gr_line
		(start 118.9228 -9.36371)
		(end 118.7958 -9.36371)
		(stroke
			(width 0.508)
			(type default)
		)
		(layer "In1.Cu")
	)
	(gr_line
		(start 118.9228 -7.17931)
		(end 118.9228 -9.36371)
		(stroke
			(width 0.508)
			(type default)
		)
		(layer "In1.Cu")
	)
	(gr_line
		(start 118.9482 -13.5636)
		(end 118.7958 -13.5636)
		(stroke
			(width 0.381)
			(type default)
		)
		(layer "In1.Cu")
	)
	(gr_line
		(start 118.9482 -11.3792)
		(end 118.9482 -13.5636)
		(stroke
			(width 0.381)
			(type default)
		)
		(layer "In1.Cu")
	)
	(gr_line
		(start 118.9482 -9.36371)
		(end 118.7958 -9.36371)
		(stroke
			(width 0.381)
			(type default)
		)
		(layer "In1.Cu")
	)
	(gr_line
		(start 118.9482 -7.17931)
		(end 118.9482 -9.36371)
		(stroke
			(width 0.381)
			(type default)
		)
		(layer "In1.Cu")
	)
	(gr_line
		(start 118.999 -13.6398)
		(end 118.1354 -13.6398)
		(stroke
			(width 0.381)
			(type default)
		)
		(layer "In1.Cu")
	)
	(gr_line
		(start 118.999 -11.3284)
		(end 118.999 -13.6398)
		(stroke
			(width 0.381)
			(type default)
		)
		(layer "In1.Cu")
	)
	(gr_line
		(start 118.999 -9.43991)
		(end 118.1354 -9.43991)
		(stroke
			(width 0.381)
			(type default)
		)
		(layer "In1.Cu")
	)
	(gr_line
		(start 118.999 -7.12851)
		(end 118.999 -9.43991)
		(stroke
			(width 0.381)
			(type default)
		)
		(layer "In1.Cu")
	)
	(gr_line
		(start 119.0498 -13.6906)
		(end 118.8466 -13.6906)
		(stroke
			(width 0.3556)
			(type default)
		)
		(layer "In1.Cu")
	)
	(gr_line
		(start 119.0498 -11.2776)
		(end 119.0498 -13.6906)
		(stroke
			(width 0.3556)
			(type default)
		)
		(layer "In1.Cu")
	)
	(gr_line
		(start 119.0498 -9.49071)
		(end 118.8466 -9.49071)
		(stroke
			(width 0.3556)
			(type default)
		)
		(layer "In1.Cu")
	)
	(gr_line
		(start 119.0498 -7.07771)
		(end 119.0498 -9.49071)
		(stroke
			(width 0.3556)
			(type default)
		)
		(layer "In1.Cu")
	)
	(gr_line
		(start 119.0752 -13.8176)
		(end 117.8814 -13.8176)
		(stroke
			(width 0.127)
			(type default)
		)
		(layer "In1.Cu")
	)
	(gr_line
		(start 119.0752 -9.61771)
		(end 117.8814 -9.61771)
		(stroke
			(width 0.127)
			(type default)
		)
		(layer "In1.Cu")
	)
	(gr_line
		(start 119.1006 -13.716)
		(end 118.8466 -13.716)
		(stroke
			(width 0.254)
			(type default)
		)
		(layer "In1.Cu")
	)
	(gr_line
		(start 119.1006 -11.2522)
		(end 119.1006 -13.716)
		(stroke
			(width 0.254)
			(type default)
		)
		(layer "In1.Cu")
	)
	(gr_line
		(start 119.1006 -9.51611)
		(end 118.8466 -9.51611)
		(stroke
			(width 0.254)
			(type default)
		)
		(layer "In1.Cu")
	)
	(gr_line
		(start 119.1006 -7.05231)
		(end 119.1006 -9.51611)
		(stroke
			(width 0.254)
			(type default)
		)
		(layer "In1.Cu")
	)
	(gr_line
		(start 119.126 -13.7668)
		(end 117.983 -13.7668)
		(stroke
			(width 0.254)
			(type default)
		)
		(layer "In1.Cu")
	)
	(gr_line
		(start 119.126 -13.7668)
		(end 118.8974 -13.7668)
		(stroke
			(width 0.1778)
			(type default)
		)
		(layer "In1.Cu")
	)
	(gr_line
		(start 119.126 -11.2268)
		(end 119.126 -13.7668)
		(stroke
			(width 0.254)
			(type default)
		)
		(layer "In1.Cu")
	)
	(gr_line
		(start 119.126 -11.2014)
		(end 119.126 -13.7668)
		(stroke
			(width 0.1778)
			(type default)
		)
		(layer "In1.Cu")
	)
	(gr_line
		(start 119.126 -9.56691)
		(end 117.983 -9.56691)
		(stroke
			(width 0.254)
			(type default)
		)
		(layer "In1.Cu")
	)
	(gr_line
		(start 119.126 -9.56691)
		(end 118.8974 -9.56691)
		(stroke
			(width 0.1778)
			(type default)
		)
		(layer "In1.Cu")
	)
	(gr_line
		(start 119.126 -7.02691)
		(end 119.126 -9.56691)
		(stroke
			(width 0.254)
			(type default)
		)
		(layer "In1.Cu")
	)
	(gr_line
		(start 119.126 -7.00151)
		(end 119.126 -9.56691)
		(stroke
			(width 0.1778)
			(type default)
		)
		(layer "In1.Cu")
	)
	(gr_line
		(start 119.1514 -13.7922)
		(end 117.9322 -13.7922)
		(stroke
			(width 0.1778)
			(type default)
		)
		(layer "In1.Cu")
	)
	(gr_line
		(start 119.1514 -13.7922)
		(end 118.9228 -13.7922)
		(stroke
			(width 0.127)
			(type default)
		)
		(layer "In1.Cu")
	)
	(gr_line
		(start 119.1514 -11.176)
		(end 119.1514 -13.7922)
		(stroke
			(width 0.127)
			(type default)
		)
		(layer "In1.Cu")
	)
	(gr_line
		(start 119.1514 -11.176)
		(end 119.1514 -13.7922)
		(stroke
			(width 0.1778)
			(type default)
		)
		(layer "In1.Cu")
	)
	(gr_line
		(start 119.1514 -9.59231)
		(end 117.9322 -9.59231)
		(stroke
			(width 0.1778)
			(type default)
		)
		(layer "In1.Cu")
	)
	(gr_line
		(start 119.1514 -9.59231)
		(end 118.9228 -9.59231)
		(stroke
			(width 0.127)
			(type default)
		)
		(layer "In1.Cu")
	)
	(gr_line
		(start 119.1514 -6.97611)
		(end 119.1514 -9.59231)
		(stroke
			(width 0.127)
			(type default)
		)
		(layer "In1.Cu")
	)
	(gr_line
		(start 119.1514 -6.97611)
		(end 119.1514 -9.59231)
		(stroke
			(width 0.1778)
			(type default)
		)
		(layer "In1.Cu")
	)
	(gr_line
		(start 119.1768 -13.8176)
		(end 117.9068 -13.8176)
		(stroke
			(width 0.127)
			(type default)
		)
		(layer "In1.Cu")
	)
	(gr_line
		(start 119.1768 -11.1506)
		(end 119.1768 -13.8176)
		(stroke
			(width 0.127)
			(type default)
		)
		(layer "In1.Cu")
	)
	(gr_line
		(start 119.1768 -9.61771)
		(end 117.9068 -9.61771)
		(stroke
			(width 0.127)
			(type default)
		)
		(layer "In1.Cu")
	)
	(gr_line
		(start 119.1768 -6.95071)
		(end 119.1768 -9.61771)
		(stroke
			(width 0.127)
			(type default)
		)
		(layer "In1.Cu")
	)
	(gr_line
		(start 119.2022 -13.843)
		(end 119.2022 -11.1252)
		(stroke
			(width 0.1016)
			(type default)
		)
		(layer "In1.Cu")
	)
	(gr_line
		(start 119.2022 -11.1252)
		(end 117.856 -11.1252)
		(stroke
			(width 0.1016)
			(type default)
		)
		(layer "In1.Cu")
	)
	(gr_line
		(start 119.2022 -9.64311)
		(end 119.2022 -6.92531)
		(stroke
			(width 0.1016)
			(type default)
		)
		(layer "In1.Cu")
	)
	(gr_line
		(start 119.2022 -6.92531)
		(end 117.856 -6.92531)
		(stroke
			(width 0.1016)
			(type default)
		)
		(layer "In1.Cu")
	)
	(gr_line
		(start 127.85598 -12.543028)
		(end 128.69418 -12.543028)
		(stroke
			(width 0.1016)
			(type default)
		)
		(layer "In1.Cu")
	)
	(gr_line
		(start 127.85598 -9.825228)
		(end 127.85598 -12.543028)
		(stroke
			(width 0.1016)
			(type default)
		)
		(layer "In1.Cu")
	)
	(gr_line
		(start 127.85598 -8.343138)
		(end 128.69418 -8.343138)
		(stroke
			(width 0.1016)
			(type default)
		)
		(layer "In1.Cu")
	)
	(gr_line
		(start 127.85598 -5.625338)
		(end 127.85598 -8.343138)
		(stroke
			(width 0.1016)
			(type default)
		)
		(layer "In1.Cu")
	)
	(gr_line
		(start 127.88138 -12.517628)
		(end 127.88138 -9.850628)
		(stroke
			(width 0.127)
			(type default)
		)
		(layer "In1.Cu")
	)
	(gr_line
		(start 127.88138 -9.850628)
		(end 129.17678 -9.850628)
		(stroke
			(width 0.127)
			(type default)
		)
		(layer "In1.Cu")
	)
	(gr_line
		(start 127.88138 -8.317738)
		(end 127.88138 -5.650738)
		(stroke
			(width 0.127)
			(type default)
		)
		(layer "In1.Cu")
	)
	(gr_line
		(start 127.88138 -5.650738)
		(end 129.17678 -5.650738)
		(stroke
			(width 0.127)
			(type default)
		)
		(layer "In1.Cu")
	)
	(gr_line
		(start 127.90678 -12.517628)
		(end 127.90678 -9.876028)
		(stroke
			(width 0.127)
			(type default)
		)
		(layer "In1.Cu")
	)
	(gr_line
		(start 127.90678 -12.492228)
		(end 127.90678 -9.876028)
		(stroke
			(width 0.1778)
			(type default)
		)
		(layer "In1.Cu")
	)
	(gr_line
		(start 127.90678 -9.876028)
		(end 129.15138 -9.876028)
		(stroke
			(width 0.127)
			(type default)
		)
		(layer "In1.Cu")
	)
	(gr_line
		(start 127.90678 -9.876028)
		(end 129.15138 -9.876028)
		(stroke
			(width 0.1778)
			(type default)
		)
		(layer "In1.Cu")
	)
	(gr_line
		(start 127.90678 -8.317738)
		(end 127.90678 -5.676138)
		(stroke
			(width 0.127)
			(type default)
		)
		(layer "In1.Cu")
	)
	(gr_line
		(start 127.90678 -8.292338)
		(end 127.90678 -5.676138)
		(stroke
			(width 0.1778)
			(type default)
		)
		(layer "In1.Cu")
	)
	(gr_line
		(start 127.90678 -5.676138)
		(end 129.15138 -5.676138)
		(stroke
			(width 0.127)
			(type default)
		)
		(layer "In1.Cu")
	)
	(gr_line
		(start 127.90678 -5.676138)
		(end 129.15138 -5.676138)
		(stroke
			(width 0.1778)
			(type default)
		)
		(layer "In1.Cu")
	)
	(gr_line
		(start 127.93218 -12.492228)
		(end 127.93218 -9.901428)
		(stroke
			(width 0.1778)
			(type default)
		)
		(layer "In1.Cu")
	)
	(gr_line
		(start 127.93218 -9.901428)
		(end 129.12598 -9.901428)
		(stroke
			(width 0.1778)
			(type default)
		)
		(layer "In1.Cu")
	)
	(gr_line
		(start 127.93218 -8.292338)
		(end 127.93218 -5.701538)
		(stroke
			(width 0.1778)
			(type default)
		)
		(layer "In1.Cu")
	)
	(gr_line
		(start 127.93218 -5.701538)
		(end 129.12598 -5.701538)
		(stroke
			(width 0.1778)
			(type default)
		)
		(layer "In1.Cu")
	)
	(gr_line
		(start 127.95758 -12.466828)
		(end 127.95758 -9.926828)
		(stroke
			(width 0.254)
			(type default)
		)
		(layer "In1.Cu")
	)
	(gr_line
		(start 127.95758 -9.926828)
		(end 129.12598 -9.926828)
		(stroke
			(width 0.254)
			(type default)
		)
		(layer "In1.Cu")
	)
	(gr_line
		(start 127.95758 -8.266938)
		(end 127.95758 -5.726938)
		(stroke
			(width 0.254)
			(type default)
		)
		(layer "In1.Cu")
	)
	(gr_line
		(start 127.95758 -5.726938)
		(end 129.12598 -5.726938)
		(stroke
			(width 0.254)
			(type default)
		)
		(layer "In1.Cu")
	)
	(gr_line
		(start 127.98298 -12.466828)
		(end 127.98298 -9.952228)
		(stroke
			(width 0.254)
			(type default)
		)
		(layer "In1.Cu")
	)
	(gr_line
		(start 127.98298 -9.952228)
		(end 129.10058 -9.952228)
		(stroke
			(width 0.254)
			(type default)
		)
		(layer "In1.Cu")
	)
	(gr_line
		(start 127.98298 -8.266938)
		(end 127.98298 -5.752338)
		(stroke
			(width 0.254)
			(type default)
		)
		(layer "In1.Cu")
	)
	(gr_line
		(start 127.98298 -5.752338)
		(end 129.10058 -5.752338)
		(stroke
			(width 0.254)
			(type default)
		)
		(layer "In1.Cu")
	)
	(gr_line
		(start 128.00838 -12.416028)
		(end 128.00838 -9.977628)
		(stroke
			(width 0.3556)
			(type default)
		)
		(layer "In1.Cu")
	)
	(gr_line
		(start 128.00838 -9.977628)
		(end 129.04978 -9.977628)
		(stroke
			(width 0.3556)
			(type default)
		)
		(layer "In1.Cu")
	)
	(gr_line
		(start 128.00838 -8.216138)
		(end 128.00838 -5.777738)
		(stroke
			(width 0.3556)
			(type default)
		)
		(layer "In1.Cu")
	)
	(gr_line
		(start 128.00838 -5.777738)
		(end 129.04978 -5.777738)
		(stroke
			(width 0.3556)
			(type default)
		)
		(layer "In1.Cu")
	)
	(gr_line
		(start 128.05918 -12.390628)
		(end 128.05918 -10.028428)
		(stroke
			(width 0.381)
			(type default)
		)
		(layer "In1.Cu")
	)
	(gr_line
		(start 128.05918 -10.028428)
		(end 128.99898 -10.028428)
		(stroke
			(width 0.381)
			(type default)
		)
		(layer "In1.Cu")
	)
	(gr_line
		(start 128.05918 -8.190738)
		(end 128.05918 -5.828538)
		(stroke
			(width 0.381)
			(type default)
		)
		(layer "In1.Cu")
	)
	(gr_line
		(start 128.05918 -5.828538)
		(end 128.99898 -5.828538)
		(stroke
			(width 0.381)
			(type default)
		)
		(layer "In1.Cu")
	)
	(gr_line
		(start 128.13538 -12.339828)
		(end 128.13538 -10.079228)
		(stroke
			(width 0.381)
			(type default)
		)
		(layer "In1.Cu")
	)
	(gr_line
		(start 128.13538 -10.079228)
		(end 128.94818 -10.079228)
		(stroke
			(width 0.381)
			(type default)
		)
		(layer "In1.Cu")
	)
	(gr_line
		(start 128.13538 -8.139938)
		(end 128.13538 -5.879338)
		(stroke
			(width 0.381)
			(type default)
		)
		(layer "In1.Cu")
	)
	(gr_line
		(start 128.13538 -5.879338)
		(end 128.94818 -5.879338)
		(stroke
			(width 0.381)
			(type default)
		)
		(layer "In1.Cu")
	)
	(gr_line
		(start 128.16078 -12.263628)
		(end 128.16078 -10.079228)
		(stroke
			(width 0.508)
			(type default)
		)
		(layer "In1.Cu")
	)
	(gr_line
		(start 128.16078 -10.079228)
		(end 128.92278 -10.079228)
		(stroke
			(width 0.508)
			(type default)
		)
		(layer "In1.Cu")
	)
	(gr_line
		(start 128.16078 -8.063738)
		(end 128.16078 -5.879338)
		(stroke
			(width 0.508)
			(type default)
		)
		(layer "In1.Cu")
	)
	(gr_line
		(start 128.16078 -5.879338)
		(end 128.92278 -5.879338)
		(stroke
			(width 0.508)
			(type default)
		)
		(layer "In1.Cu")
	)
	(gr_line
		(start 128.18618 -12.111228)
		(end 128.77038 -12.111228)
		(stroke
			(width 0.762)
			(type default)
		)
		(layer "In1.Cu")
	)
	(gr_line
		(start 128.18618 -10.282428)
		(end 128.77038 -10.282428)
		(stroke
			(width 0.762)
			(type default)
		)
		(layer "In1.Cu")
	)
	(gr_line
		(start 128.18618 -7.911338)
		(end 128.77038 -7.911338)
		(stroke
			(width 0.762)
			(type default)
		)
		(layer "In1.Cu")
	)
	(gr_line
		(start 128.18618 -6.082538)
		(end 128.77038 -6.082538)
		(stroke
			(width 0.762)
			(type default)
		)
		(layer "In1.Cu")
	)
	(gr_line
		(start 128.21158 -12.263628)
		(end 128.21158 -10.130028)
		(stroke
			(width 0.635)
			(type default)
		)
		(layer "In1.Cu")
	)
	(gr_line
		(start 128.21158 -12.212828)
		(end 128.21158 -10.180828)
		(stroke
			(width 0.762)
			(type default)
		)
		(layer "In1.Cu")
	)
	(gr_line
		(start 128.21158 -10.130028)
		(end 128.89738 -10.130028)
		(stroke
			(width 0.635)
			(type default)
		)
		(layer "In1.Cu")
	)
	(gr_line
		(start 128.21158 -8.063738)
		(end 128.21158 -5.930138)
		(stroke
			(width 0.635)
			(type default)
		)
		(layer "In1.Cu")
	)
	(gr_line
		(start 128.21158 -8.012938)
		(end 128.21158 -5.980938)
		(stroke
			(width 0.762)
			(type default)
		)
		(layer "In1.Cu")
	)
	(gr_line
		(start 128.21158 -5.930138)
		(end 128.89738 -5.930138)
		(stroke
			(width 0.635)
			(type default)
		)
		(layer "In1.Cu")
	)
	(gr_line
		(start 128.23698 -12.212828)
		(end 128.23698 -10.180828)
		(stroke
			(width 0.762)
			(type default)
		)
		(layer "In1.Cu")
	)
	(gr_line
		(start 128.23698 -10.180828)
		(end 128.82118 -10.180828)
		(stroke
			(width 0.762)
			(type default)
		)
		(layer "In1.Cu")
	)
	(gr_line
		(start 128.23698 -8.012938)
		(end 128.23698 -5.980938)
		(stroke
			(width 0.762)
			(type default)
		)
		(layer "In1.Cu")
	)
	(gr_line
		(start 128.23698 -5.980938)
		(end 128.82118 -5.980938)
		(stroke
			(width 0.762)
			(type default)
		)
		(layer "In1.Cu")
	)
	(gr_line
		(start 128.26238 -12.212828)
		(end 128.26238 -10.180828)
		(stroke
			(width 0.762)
			(type default)
		)
		(layer "In1.Cu")
	)
	(gr_line
		(start 128.26238 -12.212828)
		(end 128.84658 -12.212828)
		(stroke
			(width 0.762)
			(type default)
		)
		(layer "In1.Cu")
	)
	(gr_line
		(start 128.26238 -12.187428)
		(end 128.26238 -10.155428)
		(stroke
			(width 0.762)
			(type default)
		)
		(layer "In1.Cu")
	)
	(gr_line
		(start 128.26238 -8.012938)
		(end 128.26238 -5.980938)
		(stroke
			(width 0.762)
			(type default)
		)
		(layer "In1.Cu")
	)
	(gr_line
		(start 128.26238 -8.012938)
		(end 128.84658 -8.012938)
		(stroke
			(width 0.762)
			(type default)
		)
		(layer "In1.Cu")
	)
	(gr_line
		(start 128.26238 -7.987538)
		(end 128.26238 -5.955538)
		(stroke
			(width 0.762)
			(type default)
		)
		(layer "In1.Cu")
	)
	(gr_line
		(start 128.28778 -12.212828)
		(end 128.28778 -10.180828)
		(stroke
			(width 0.762)
			(type default)
		)
		(layer "In1.Cu")
	)
	(gr_line
		(start 128.28778 -8.012938)
		(end 128.28778 -5.980938)
		(stroke
			(width 0.762)
			(type default)
		)
		(layer "In1.Cu")
	)
	(gr_line
		(start 128.31318 -12.212828)
		(end 128.31318 -10.180828)
		(stroke
			(width 0.762)
			(type default)
		)
		(layer "In1.Cu")
	)
	(gr_line
		(start 128.31318 -8.012938)
		(end 128.31318 -5.980938)
		(stroke
			(width 0.762)
			(type default)
		)
		(layer "In1.Cu")
	)
	(gr_line
		(start 128.33858 -12.212828)
		(end 128.33858 -10.180828)
		(stroke
			(width 0.762)
			(type default)
		)
		(layer "In1.Cu")
	)
	(gr_line
		(start 128.33858 -8.012938)
		(end 128.33858 -5.980938)
		(stroke
			(width 0.762)
			(type default)
		)
		(layer "In1.Cu")
	)
	(gr_line
		(start 128.38938 -12.212828)
		(end 128.38938 -10.180828)
		(stroke
			(width 0.762)
			(type default)
		)
		(layer "In1.Cu")
	)
	(gr_line
		(start 128.38938 -8.012938)
		(end 128.38938 -5.980938)
		(stroke
			(width 0.762)
			(type default)
		)
		(layer "In1.Cu")
	)
	(gr_line
		(start 128.41478 -12.212828)
		(end 128.41478 -10.180828)
		(stroke
			(width 0.762)
			(type default)
		)
		(layer "In1.Cu")
	)
	(gr_line
		(start 128.41478 -8.012938)
		(end 128.41478 -5.980938)
		(stroke
			(width 0.762)
			(type default)
		)
		(layer "In1.Cu")
	)
	(gr_line
		(start 128.44018 -12.212828)
		(end 128.44018 -10.409428)
		(stroke
			(width 0.635)
			(type default)
		)
		(layer "In1.Cu")
	)
	(gr_line
		(start 128.44018 -10.409428)
		(end 128.54178 -10.409428)
		(stroke
			(width 0.635)
			(type default)
		)
		(layer "In1.Cu")
	)
	(gr_line
		(start 128.44018 -8.012938)
		(end 128.44018 -6.209538)
		(stroke
			(width 0.635)
			(type default)
		)
		(layer "In1.Cu")
	)
	(gr_line
		(start 128.44018 -6.209538)
		(end 128.54178 -6.209538)
		(stroke
			(width 0.635)
			(type default)
		)
		(layer "In1.Cu")
	)
	(gr_line
		(start 128.46558 -12.212828)
		(end 128.46558 -10.180828)
		(stroke
			(width 0.762)
			(type default)
		)
		(layer "In1.Cu")
	)
	(gr_line
		(start 128.46558 -12.187428)
		(end 128.46558 -10.155428)
		(stroke
			(width 0.762)
			(type default)
		)
		(layer "In1.Cu")
	)
	(gr_line
		(start 128.46558 -12.136628)
		(end 128.46558 -10.358628)
		(stroke
			(width 0.635)
			(type default)
		)
		(layer "In1.Cu")
	)
	(gr_line
		(start 128.46558 -8.012938)
		(end 128.46558 -5.980938)
		(stroke
			(width 0.762)
			(type default)
		)
		(layer "In1.Cu")
	)
	(gr_line
		(start 128.46558 -7.987538)
		(end 128.46558 -5.955538)
		(stroke
			(width 0.762)
			(type default)
		)
		(layer "In1.Cu")
	)
	(gr_line
		(start 128.46558 -7.936738)
		(end 128.46558 -6.158738)
		(stroke
			(width 0.635)
			(type default)
		)
		(layer "In1.Cu")
	)
	(gr_line
		(start 128.51638 -12.212828)
		(end 128.51638 -10.180828)
		(stroke
			(width 0.762)
			(type default)
		)
		(layer "In1.Cu")
	)
	(gr_line
		(start 128.51638 -8.012938)
		(end 128.51638 -5.980938)
		(stroke
			(width 0.762)
			(type default)
		)
		(layer "In1.Cu")
	)
	(gr_line
		(start 128.54178 -12.212828)
		(end 128.54178 -10.180828)
		(stroke
			(width 0.762)
			(type default)
		)
		(layer "In1.Cu")
	)
	(gr_line
		(start 128.54178 -12.187428)
		(end 128.54178 -10.155428)
		(stroke
			(width 0.762)
			(type default)
		)
		(layer "In1.Cu")
	)
	(gr_line
		(start 128.54178 -12.136628)
		(end 128.46558 -12.136628)
		(stroke
			(width 0.635)
			(type default)
		)
		(layer "In1.Cu")
	)
	(gr_line
		(start 128.54178 -10.409428)
		(end 128.54178 -12.136628)
		(stroke
			(width 0.635)
			(type default)
		)
		(layer "In1.Cu")
	)
	(gr_line
		(start 128.54178 -8.012938)
		(end 128.54178 -5.980938)
		(stroke
			(width 0.762)
			(type default)
		)
		(layer "In1.Cu")
	)
	(gr_line
		(start 128.54178 -7.987538)
		(end 128.54178 -5.955538)
		(stroke
			(width 0.762)
			(type default)
		)
		(layer "In1.Cu")
	)
	(gr_line
		(start 128.54178 -7.936738)
		(end 128.46558 -7.936738)
		(stroke
			(width 0.635)
			(type default)
		)
		(layer "In1.Cu")
	)
	(gr_line
		(start 128.54178 -6.209538)
		(end 128.54178 -7.936738)
		(stroke
			(width 0.635)
			(type default)
		)
		(layer "In1.Cu")
	)
	(gr_line
		(start 128.59258 -12.187428)
		(end 128.59258 -10.155428)
		(stroke
			(width 0.762)
			(type default)
		)
		(layer "In1.Cu")
	)
	(gr_line
		(start 128.59258 -7.987538)
		(end 128.59258 -5.955538)
		(stroke
			(width 0.762)
			(type default)
		)
		(layer "In1.Cu")
	)
	(gr_line
		(start 128.61798 -12.187428)
		(end 128.61798 -10.155428)
		(stroke
			(width 0.762)
			(type default)
		)
		(layer "In1.Cu")
	)
	(gr_line
		(start 128.61798 -7.987538)
		(end 128.61798 -5.955538)
		(stroke
			(width 0.762)
			(type default)
		)
		(layer "In1.Cu")
	)
	(gr_line
		(start 128.66878 -12.212828)
		(end 128.66878 -10.180828)
		(stroke
			(width 0.762)
			(type default)
		)
		(layer "In1.Cu")
	)
	(gr_line
		(start 128.66878 -8.012938)
		(end 128.66878 -5.980938)
		(stroke
			(width 0.762)
			(type default)
		)
		(layer "In1.Cu")
	)
	(gr_line
		(start 128.69418 -12.543028)
		(end 129.20218 -12.543028)
		(stroke
			(width 0.1016)
			(type default)
		)
		(layer "In1.Cu")
	)
	(gr_line
		(start 128.69418 -12.187428)
		(end 128.69418 -10.155428)
		(stroke
			(width 0.762)
			(type default)
		)
		(layer "In1.Cu")
	)
	(gr_line
		(start 128.69418 -8.343138)
		(end 129.20218 -8.343138)
		(stroke
			(width 0.1016)
			(type default)
		)
		(layer "In1.Cu")
	)
	(gr_line
		(start 128.69418 -7.987538)
		(end 128.69418 -5.955538)
		(stroke
			(width 0.762)
			(type default)
		)
		(layer "In1.Cu")
	)
	(gr_line
		(start 128.74498 -12.212828)
		(end 128.74498 -10.180828)
		(stroke
			(width 0.762)
			(type default)
		)
		(layer "In1.Cu")
	)
	(gr_line
		(start 128.74498 -12.187428)
		(end 128.74498 -10.155428)
		(stroke
			(width 0.762)
			(type default)
		)
		(layer "In1.Cu")
	)
	(gr_line
		(start 128.74498 -8.012938)
		(end 128.74498 -5.980938)
		(stroke
			(width 0.762)
			(type default)
		)
		(layer "In1.Cu")
	)
	(gr_line
		(start 128.74498 -7.987538)
		(end 128.74498 -5.955538)
		(stroke
			(width 0.762)
			(type default)
		)
		(layer "In1.Cu")
	)
	(gr_line
		(start 128.77038 -12.187428)
		(end 128.77038 -10.155428)
		(stroke
			(width 0.762)
			(type default)
		)
		(layer "In1.Cu")
	)
	(gr_line
		(start 128.77038 -7.987538)
		(end 128.77038 -5.955538)
		(stroke
			(width 0.762)
			(type default)
		)
		(layer "In1.Cu")
	)
	(gr_line
		(start 128.79578 -12.263628)
		(end 128.16078 -12.263628)
		(stroke
			(width 0.508)
			(type default)
		)
		(layer "In1.Cu")
	)
	(gr_line
		(start 128.79578 -12.263628)
		(end 128.21158 -12.263628)
		(stroke
			(width 0.635)
			(type default)
		)
		(layer "In1.Cu")
	)
	(gr_line
		(start 128.79578 -8.063738)
		(end 128.16078 -8.063738)
		(stroke
			(width 0.508)
			(type default)
		)
		(layer "In1.Cu")
	)
	(gr_line
		(start 128.79578 -8.063738)
		(end 128.21158 -8.063738)
		(stroke
			(width 0.635)
			(type default)
		)
		(layer "In1.Cu")
	)
	(gr_line
		(start 128.82118 -12.187428)
		(end 128.82118 -10.155428)
		(stroke
			(width 0.762)
			(type default)
		)
		(layer "In1.Cu")
	)
	(gr_line
		(start 128.82118 -7.987538)
		(end 128.82118 -5.955538)
		(stroke
			(width 0.762)
			(type default)
		)
		(layer "In1.Cu")
	)
	(gr_line
		(start 128.84658 -12.416028)
		(end 128.00838 -12.416028)
		(stroke
			(width 0.3556)
			(type default)
		)
		(layer "In1.Cu")
	)
	(gr_line
		(start 128.84658 -12.390628)
		(end 128.05918 -12.390628)
		(stroke
			(width 0.381)
			(type default)
		)
		(layer "In1.Cu")
	)
	(gr_line
		(start 128.84658 -8.216138)
		(end 128.00838 -8.216138)
		(stroke
			(width 0.3556)
			(type default)
		)
		(layer "In1.Cu")
	)
	(gr_line
		(start 128.84658 -8.190738)
		(end 128.05918 -8.190738)
		(stroke
			(width 0.381)
			(type default)
		)
		(layer "In1.Cu")
	)
	(gr_line
		(start 128.87198 -12.212828)
		(end 128.87198 -10.180828)
		(stroke
			(width 0.762)
			(type default)
		)
		(layer "In1.Cu")
	)
	(gr_line
		(start 128.87198 -8.012938)
		(end 128.87198 -5.980938)
		(stroke
			(width 0.762)
			(type default)
		)
		(layer "In1.Cu")
	)
	(gr_line
		(start 128.89738 -12.466828)
		(end 127.95758 -12.466828)
		(stroke
			(width 0.254)
			(type default)
		)
		(layer "In1.Cu")
	)
	(gr_line
		(start 128.89738 -12.212828)
		(end 128.44018 -12.212828)
		(stroke
			(width 0.635)
			(type default)
		)
		(layer "In1.Cu")
	)
	(gr_line
		(start 128.89738 -10.130028)
		(end 128.89738 -12.212828)
		(stroke
			(width 0.635)
			(type default)
		)
		(layer "In1.Cu")
	)
	(gr_line
		(start 128.89738 -8.266938)
		(end 127.95758 -8.266938)
		(stroke
			(width 0.254)
			(type default)
		)
		(layer "In1.Cu")
	)
	(gr_line
		(start 128.89738 -8.012938)
		(end 128.44018 -8.012938)
		(stroke
			(width 0.635)
			(type default)
		)
		(layer "In1.Cu")
	)
	(gr_line
		(start 128.89738 -5.930138)
		(end 128.89738 -8.012938)
		(stroke
			(width 0.635)
			(type default)
		)
		(layer "In1.Cu")
	)
	(gr_line
		(start 128.92278 -12.492228)
		(end 127.90678 -12.492228)
		(stroke
			(width 0.1778)
			(type default)
		)
		(layer "In1.Cu")
	)
	(gr_line
		(start 128.92278 -12.263628)
		(end 128.79578 -12.263628)
		(stroke
			(width 0.508)
			(type default)
		)
		(layer "In1.Cu")
	)
	(gr_line
		(start 128.92278 -10.079228)
		(end 128.92278 -12.263628)
		(stroke
			(width 0.508)
			(type default)
		)
		(layer "In1.Cu")
	)
	(gr_line
		(start 128.92278 -8.292338)
		(end 127.90678 -8.292338)
		(stroke
			(width 0.1778)
			(type default)
		)
		(layer "In1.Cu")
	)
	(gr_line
		(start 128.92278 -8.063738)
		(end 128.79578 -8.063738)
		(stroke
			(width 0.508)
			(type default)
		)
		(layer "In1.Cu")
	)
	(gr_line
		(start 128.92278 -5.879338)
		(end 128.92278 -8.063738)
		(stroke
			(width 0.508)
			(type default)
		)
		(layer "In1.Cu")
	)
	(gr_line
		(start 128.94818 -12.263628)
		(end 128.79578 -12.263628)
		(stroke
			(width 0.381)
			(type default)
		)
		(layer "In1.Cu")
	)
	(gr_line
		(start 128.94818 -10.079228)
		(end 128.94818 -12.263628)
		(stroke
			(width 0.381)
			(type default)
		)
		(layer "In1.Cu")
	)
	(gr_line
		(start 128.94818 -8.063738)
		(end 128.79578 -8.063738)
		(stroke
			(width 0.381)
			(type default)
		)
		(layer "In1.Cu")
	)
	(gr_line
		(start 128.94818 -5.879338)
		(end 128.94818 -8.063738)
		(stroke
			(width 0.381)
			(type default)
		)
		(layer "In1.Cu")
	)
	(gr_line
		(start 128.99898 -12.339828)
		(end 128.13538 -12.339828)
		(stroke
			(width 0.381)
			(type default)
		)
		(layer "In1.Cu")
	)
	(gr_line
		(start 128.99898 -10.028428)
		(end 128.99898 -12.339828)
		(stroke
			(width 0.381)
			(type default)
		)
		(layer "In1.Cu")
	)
	(gr_line
		(start 128.99898 -8.139938)
		(end 128.13538 -8.139938)
		(stroke
			(width 0.381)
			(type default)
		)
		(layer "In1.Cu")
	)
	(gr_line
		(start 128.99898 -5.828538)
		(end 128.99898 -8.139938)
		(stroke
			(width 0.381)
			(type default)
		)
		(layer "In1.Cu")
	)
	(gr_line
		(start 129.04978 -12.390628)
		(end 128.84658 -12.390628)
		(stroke
			(width 0.3556)
			(type default)
		)
		(layer "In1.Cu")
	)
	(gr_line
		(start 129.04978 -9.977628)
		(end 129.04978 -12.390628)
		(stroke
			(width 0.3556)
			(type default)
		)
		(layer "In1.Cu")
	)
	(gr_line
		(start 129.04978 -8.190738)
		(end 128.84658 -8.190738)
		(stroke
			(width 0.3556)
			(type default)
		)
		(layer "In1.Cu")
	)
	(gr_line
		(start 129.04978 -5.777738)
		(end 129.04978 -8.190738)
		(stroke
			(width 0.3556)
			(type default)
		)
		(layer "In1.Cu")
	)
	(gr_line
		(start 129.07518 -12.517628)
		(end 127.88138 -12.517628)
		(stroke
			(width 0.127)
			(type default)
		)
		(layer "In1.Cu")
	)
	(gr_line
		(start 129.07518 -8.317738)
		(end 127.88138 -8.317738)
		(stroke
			(width 0.127)
			(type default)
		)
		(layer "In1.Cu")
	)
	(gr_line
		(start 129.10058 -12.416028)
		(end 128.84658 -12.416028)
		(stroke
			(width 0.254)
			(type default)
		)
		(layer "In1.Cu")
	)
	(gr_line
		(start 129.10058 -9.952228)
		(end 129.10058 -12.416028)
		(stroke
			(width 0.254)
			(type default)
		)
		(layer "In1.Cu")
	)
	(gr_line
		(start 129.10058 -8.216138)
		(end 128.84658 -8.216138)
		(stroke
			(width 0.254)
			(type default)
		)
		(layer "In1.Cu")
	)
	(gr_line
		(start 129.10058 -5.752338)
		(end 129.10058 -8.216138)
		(stroke
			(width 0.254)
			(type default)
		)
		(layer "In1.Cu")
	)
	(gr_line
		(start 129.12598 -12.466828)
		(end 127.98298 -12.466828)
		(stroke
			(width 0.254)
			(type default)
		)
		(layer "In1.Cu")
	)
	(gr_line
		(start 129.12598 -12.466828)
		(end 128.89738 -12.466828)
		(stroke
			(width 0.1778)
			(type default)
		)
		(layer "In1.Cu")
	)
	(gr_line
		(start 129.12598 -9.926828)
		(end 129.12598 -12.466828)
		(stroke
			(width 0.254)
			(type default)
		)
		(layer "In1.Cu")
	)
	(gr_line
		(start 129.12598 -9.901428)
		(end 129.12598 -12.466828)
		(stroke
			(width 0.1778)
			(type default)
		)
		(layer "In1.Cu")
	)
	(gr_line
		(start 129.12598 -8.266938)
		(end 127.98298 -8.266938)
		(stroke
			(width 0.254)
			(type default)
		)
		(layer "In1.Cu")
	)
	(gr_line
		(start 129.12598 -8.266938)
		(end 128.89738 -8.266938)
		(stroke
			(width 0.1778)
			(type default)
		)
		(layer "In1.Cu")
	)
	(gr_line
		(start 129.12598 -5.726938)
		(end 129.12598 -8.266938)
		(stroke
			(width 0.254)
			(type default)
		)
		(layer "In1.Cu")
	)
	(gr_line
		(start 129.12598 -5.701538)
		(end 129.12598 -8.266938)
		(stroke
			(width 0.1778)
			(type default)
		)
		(layer "In1.Cu")
	)
	(gr_line
		(start 129.15138 -12.492228)
		(end 127.93218 -12.492228)
		(stroke
			(width 0.1778)
			(type default)
		)
		(layer "In1.Cu")
	)
	(gr_line
		(start 129.15138 -12.492228)
		(end 128.92278 -12.492228)
		(stroke
			(width 0.127)
			(type default)
		)
		(layer "In1.Cu")
	)
	(gr_line
		(start 129.15138 -9.876028)
		(end 129.15138 -12.492228)
		(stroke
			(width 0.127)
			(type default)
		)
		(layer "In1.Cu")
	)
	(gr_line
		(start 129.15138 -9.876028)
		(end 129.15138 -12.492228)
		(stroke
			(width 0.1778)
			(type default)
		)
		(layer "In1.Cu")
	)
	(gr_line
		(start 129.15138 -8.292338)
		(end 127.93218 -8.292338)
		(stroke
			(width 0.1778)
			(type default)
		)
		(layer "In1.Cu")
	)
	(gr_line
		(start 129.15138 -8.292338)
		(end 128.92278 -8.292338)
		(stroke
			(width 0.127)
			(type default)
		)
		(layer "In1.Cu")
	)
	(gr_line
		(start 129.15138 -5.676138)
		(end 129.15138 -8.292338)
		(stroke
			(width 0.127)
			(type default)
		)
		(layer "In1.Cu")
	)
	(gr_line
		(start 129.15138 -5.676138)
		(end 129.15138 -8.292338)
		(stroke
			(width 0.1778)
			(type default)
		)
		(layer "In1.Cu")
	)
	(gr_line
		(start 129.17678 -12.517628)
		(end 127.90678 -12.517628)
		(stroke
			(width 0.127)
			(type default)
		)
		(layer "In1.Cu")
	)
	(gr_line
		(start 129.17678 -9.850628)
		(end 129.17678 -12.517628)
		(stroke
			(width 0.127)
			(type default)
		)
		(layer "In1.Cu")
	)
	(gr_line
		(start 129.17678 -8.317738)
		(end 127.90678 -8.317738)
		(stroke
			(width 0.127)
			(type default)
		)
		(layer "In1.Cu")
	)
	(gr_line
		(start 129.17678 -5.650738)
		(end 129.17678 -8.317738)
		(stroke
			(width 0.127)
			(type default)
		)
		(layer "In1.Cu")
	)
	(gr_line
		(start 129.20218 -12.543028)
		(end 129.20218 -9.825228)
		(stroke
			(width 0.1016)
			(type default)
		)
		(layer "In1.Cu")
	)
	(gr_line
		(start 129.20218 -9.825228)
		(end 127.85598 -9.825228)
		(stroke
			(width 0.1016)
			(type default)
		)
		(layer "In1.Cu")
	)
	(gr_line
		(start 129.20218 -8.343138)
		(end 129.20218 -5.625338)
		(stroke
			(width 0.1016)
			(type default)
		)
		(layer "In1.Cu")
	)
	(gr_line
		(start 129.20218 -5.625338)
		(end 127.85598 -5.625338)
		(stroke
			(width 0.1016)
			(type default)
		)
		(layer "In1.Cu")
	)
	(gr_line
		(start 132.9182 -3.95732)
		(end 132.9182 -5.22732)
		(stroke
			(width 1.016)
			(type default)
		)
		(layer "In1.Cu")
	)
	(gr_arc
		(start 132.990082 -52.319936)
		(mid 133.697187 -52.027043)
		(end 133.99008 -51.319938)
		(stroke
			(width 1.016)
			(type default)
		)
		(layer "In1.Cu")
	)
	(gr_line
		(start 133.99008 -51.319938)
		(end 133.99008 -50.8)
		(stroke
			(width 1.016)
			(type default)
		)
		(layer "In1.Cu")
	)
	(gr_arc
		(start 134.990078 -49.800002)
		(mid 134.282987 -50.092902)
		(end 133.99008 -50.8)
		(stroke
			(width 1.016)
			(type default)
		)
		(layer "In1.Cu")
	)
	(gr_line
		(start 134.990078 -49.800002)
		(end 149.990048 -49.800002)
		(stroke
			(width 1.016)
			(type default)
		)
		(layer "In1.Cu")
	)
	(gr_line
		(start 139.4968 -11.3792)
		(end 139.4968 -9.1948)
		(stroke
			(width 0.254)
			(type default)
		)
		(layer "In1.Cu")
	)
	(gr_line
		(start 139.4968 -9.1948)
		(end 141.0716 -9.1948)
		(stroke
			(width 0.254)
			(type default)
		)
		(layer "In1.Cu")
	)
	(gr_line
		(start 139.5222 -11.3792)
		(end 139.5222 -9.2456)
		(stroke
			(width 0.254)
			(type default)
		)
		(layer "In1.Cu")
	)
	(gr_line
		(start 139.5222 -9.2456)
		(end 141.0462 -9.2456)
		(stroke
			(width 0.254)
			(type default)
		)
		(layer "In1.Cu")
	)
	(gr_line
		(start 139.573 -11.3538)
		(end 139.573 -9.3726)
		(stroke
			(width 0.254)
			(type default)
		)
		(layer "In1.Cu")
	)
	(gr_line
		(start 139.573 -9.3726)
		(end 141.0208 -9.3726)
		(stroke
			(width 0.254)
			(type default)
		)
		(layer "In1.Cu")
	)
	(gr_line
		(start 139.627102 -11.303)
		(end 139.931902 -11.303)
		(stroke
			(width 0.1016)
			(type default)
		)
		(layer "In1.Cu")
	)
	(gr_line
		(start 139.627102 -9.2964)
		(end 139.627102 -11.303)
		(stroke
			(width 0.1016)
			(type default)
		)
		(layer "In1.Cu")
	)
	(gr_line
		(start 139.677902 -11.2268)
		(end 140.770102 -11.2268)
		(stroke
			(width 0.2032)
			(type default)
		)
		(layer "In1.Cu")
	)
	(gr_line
		(start 139.677902 -9.3726)
		(end 139.677902 -11.2268)
		(stroke
			(width 0.2032)
			(type default)
		)
		(layer "In1.Cu")
	)
	(gr_line
		(start 139.703302 -11.2268)
		(end 140.871702 -11.2268)
		(stroke
			(width 0.2032)
			(type default)
		)
		(layer "In1.Cu")
	)
	(gr_line
		(start 139.703302 -9.4234)
		(end 139.703302 -11.2268)
		(stroke
			(width 0.2032)
			(type default)
		)
		(layer "In1.Cu")
	)
	(gr_line
		(start 139.7508 -11.1252)
		(end 139.7508 -9.5758)
		(stroke
			(width 0.762)
			(type default)
		)
		(layer "In1.Cu")
	)
	(gr_line
		(start 139.7508 -11.1252)
		(end 140.6652 -11.1252)
		(stroke
			(width 0.762)
			(type default)
		)
		(layer "In1.Cu")
	)
	(gr_line
		(start 139.7508 -11.0998)
		(end 139.7508 -9.5504)
		(stroke
			(width 0.762)
			(type default)
		)
		(layer "In1.Cu")
	)
	(gr_line
		(start 139.7508 -10.9982)
		(end 139.7508 -9.4488)
		(stroke
			(width 0.762)
			(type default)
		)
		(layer "In1.Cu")
	)
	(gr_line
		(start 139.7508 -9.4488)
		(end 140.6652 -9.4488)
		(stroke
			(width 0.762)
			(type default)
		)
		(layer "In1.Cu")
	)
	(gr_line
		(start 139.754102 -11.176)
		(end 140.846302 -11.176)
		(stroke
			(width 0.2032)
			(type default)
		)
		(layer "In1.Cu")
	)
	(gr_line
		(start 139.754102 -9.4742)
		(end 139.754102 -11.176)
		(stroke
			(width 0.2032)
			(type default)
		)
		(layer "In1.Cu")
	)
	(gr_line
		(start 139.7762 -10.9982)
		(end 140.6906 -10.9982)
		(stroke
			(width 0.762)
			(type default)
		)
		(layer "In1.Cu")
	)
	(gr_line
		(start 139.7762 -9.5758)
		(end 140.6906 -9.5758)
		(stroke
			(width 0.762)
			(type default)
		)
		(layer "In1.Cu")
	)
	(gr_line
		(start 139.855702 -11.0744)
		(end 140.643102 -11.0744)
		(stroke
			(width 0.508)
			(type default)
		)
		(layer "In1.Cu")
	)
	(gr_line
		(start 139.855702 -11.049)
		(end 139.855702 -9.525)
		(stroke
			(width 0.508)
			(type default)
		)
		(layer "In1.Cu")
	)
	(gr_line
		(start 139.881102 -11.0744)
		(end 139.881102 -9.5504)
		(stroke
			(width 0.508)
			(type default)
		)
		(layer "In1.Cu")
	)
	(gr_line
		(start 139.9032 -11.1252)
		(end 140.8176 -11.1252)
		(stroke
			(width 0.762)
			(type default)
		)
		(layer "In1.Cu")
	)
	(gr_line
		(start 139.9032 -9.4488)
		(end 140.8176 -9.4488)
		(stroke
			(width 0.762)
			(type default)
		)
		(layer "In1.Cu")
	)
	(gr_line
		(start 139.906502 -9.525)
		(end 140.643102 -9.525)
		(stroke
			(width 0.508)
			(type default)
		)
		(layer "In1.Cu")
	)
	(gr_line
		(start 139.931902 -11.303)
		(end 140.922502 -11.303)
		(stroke
			(width 0.1016)
			(type default)
		)
		(layer "In1.Cu")
	)
	(gr_line
		(start 139.931902 -11.0744)
		(end 139.931902 -9.5504)
		(stroke
			(width 0.508)
			(type default)
		)
		(layer "In1.Cu")
	)
	(gr_line
		(start 139.957302 -11.0744)
		(end 139.957302 -9.5504)
		(stroke
			(width 0.508)
			(type default)
		)
		(layer "In1.Cu")
	)
	(gr_line
		(start 139.982702 -11.0744)
		(end 139.982702 -9.5504)
		(stroke
			(width 0.508)
			(type default)
		)
		(layer "In1.Cu")
	)
	(gr_line
		(start 140.008102 -11.0744)
		(end 140.008102 -9.5504)
		(stroke
			(width 0.508)
			(type default)
		)
		(layer "In1.Cu")
	)
	(gr_line
		(start 140.008102 -11.049)
		(end 140.008102 -9.525)
		(stroke
			(width 0.508)
			(type default)
		)
		(layer "In1.Cu")
	)
	(gr_line
		(start 140.033502 -11.0744)
		(end 140.033502 -9.5504)
		(stroke
			(width 0.508)
			(type default)
		)
		(layer "In1.Cu")
	)
	(gr_line
		(start 140.058902 -11.0744)
		(end 140.058902 -9.5504)
		(stroke
			(width 0.508)
			(type default)
		)
		(layer "In1.Cu")
	)
	(gr_line
		(start 140.109702 -11.0744)
		(end 140.109702 -9.5504)
		(stroke
			(width 0.508)
			(type default)
		)
		(layer "In1.Cu")
	)
	(gr_line
		(start 140.109702 -11.049)
		(end 140.109702 -9.525)
		(stroke
			(width 0.508)
			(type default)
		)
		(layer "In1.Cu")
	)
	(gr_line
		(start 140.135102 -11.0744)
		(end 140.135102 -9.5504)
		(stroke
			(width 0.508)
			(type default)
		)
		(layer "In1.Cu")
	)
	(gr_line
		(start 140.160502 -11.0744)
		(end 140.160502 -9.5504)
		(stroke
			(width 0.508)
			(type default)
		)
		(layer "In1.Cu")
	)
	(gr_line
		(start 140.185902 -11.0744)
		(end 140.185902 -9.5504)
		(stroke
			(width 0.508)
			(type default)
		)
		(layer "In1.Cu")
	)
	(gr_line
		(start 140.236702 -11.0744)
		(end 140.236702 -9.5504)
		(stroke
			(width 0.508)
			(type default)
		)
		(layer "In1.Cu")
	)
	(gr_line
		(start 140.262102 -11.0744)
		(end 140.262102 -9.5504)
		(stroke
			(width 0.508)
			(type default)
		)
		(layer "In1.Cu")
	)
	(gr_line
		(start 140.262102 -11.049)
		(end 140.262102 -9.525)
		(stroke
			(width 0.508)
			(type default)
		)
		(layer "In1.Cu")
	)
	(gr_line
		(start 140.287502 -11.0744)
		(end 140.287502 -9.5504)
		(stroke
			(width 0.508)
			(type default)
		)
		(layer "In1.Cu")
	)
	(gr_line
		(start 140.312902 -11.0744)
		(end 140.312902 -9.5504)
		(stroke
			(width 0.508)
			(type default)
		)
		(layer "In1.Cu")
	)
	(gr_line
		(start 140.338302 -11.0744)
		(end 140.338302 -9.5504)
		(stroke
			(width 0.508)
			(type default)
		)
		(layer "In1.Cu")
	)
	(gr_line
		(start 140.338302 -11.049)
		(end 140.338302 -9.525)
		(stroke
			(width 0.508)
			(type default)
		)
		(layer "In1.Cu")
	)
	(gr_line
		(start 140.363702 -11.0744)
		(end 140.363702 -9.5504)
		(stroke
			(width 0.508)
			(type default)
		)
		(layer "In1.Cu")
	)
	(gr_line
		(start 140.389102 -11.0744)
		(end 140.389102 -9.5504)
		(stroke
			(width 0.508)
			(type default)
		)
		(layer "In1.Cu")
	)
	(gr_line
		(start 140.389102 -11.049)
		(end 140.389102 -9.525)
		(stroke
			(width 0.508)
			(type default)
		)
		(layer "In1.Cu")
	)
	(gr_line
		(start 140.414502 -11.0744)
		(end 140.414502 -9.5504)
		(stroke
			(width 0.508)
			(type default)
		)
		(layer "In1.Cu")
	)
	(gr_line
		(start 140.414502 -11.049)
		(end 140.414502 -9.525)
		(stroke
			(width 0.508)
			(type default)
		)
		(layer "In1.Cu")
	)
	(gr_line
		(start 140.439902 -11.049)
		(end 140.439902 -9.525)
		(stroke
			(width 0.508)
			(type default)
		)
		(layer "In1.Cu")
	)
	(gr_line
		(start 140.465302 -11.0744)
		(end 140.465302 -9.5504)
		(stroke
			(width 0.508)
			(type default)
		)
		(layer "In1.Cu")
	)
	(gr_line
		(start 140.4874 -11.3792)
		(end 139.4968 -11.3792)
		(stroke
			(width 0.254)
			(type default)
		)
		(layer "In1.Cu")
	)
	(gr_line
		(start 140.490702 -11.049)
		(end 140.490702 -9.525)
		(stroke
			(width 0.508)
			(type default)
		)
		(layer "In1.Cu")
	)
	(gr_line
		(start 140.516102 -11.049)
		(end 140.516102 -9.525)
		(stroke
			(width 0.508)
			(type default)
		)
		(layer "In1.Cu")
	)
	(gr_line
		(start 140.541502 -11.0744)
		(end 140.541502 -9.5504)
		(stroke
			(width 0.508)
			(type default)
		)
		(layer "In1.Cu")
	)
	(gr_line
		(start 140.566902 -11.0744)
		(end 140.566902 -9.5504)
		(stroke
			(width 0.508)
			(type default)
		)
		(layer "In1.Cu")
	)
	(gr_line
		(start 140.566902 -11.049)
		(end 140.566902 -9.525)
		(stroke
			(width 0.508)
			(type default)
		)
		(layer "In1.Cu")
	)
	(gr_line
		(start 140.617702 -11.0744)
		(end 140.617702 -9.5504)
		(stroke
			(width 0.508)
			(type default)
		)
		(layer "In1.Cu")
	)
	(gr_line
		(start 140.617702 -11.049)
		(end 140.617702 -9.525)
		(stroke
			(width 0.508)
			(type default)
		)
		(layer "In1.Cu")
	)
	(gr_line
		(start 140.668502 -11.0744)
		(end 140.668502 -9.5504)
		(stroke
			(width 0.508)
			(type default)
		)
		(layer "In1.Cu")
	)
	(gr_line
		(start 140.668502 -11.049)
		(end 140.668502 -9.525)
		(stroke
			(width 0.508)
			(type default)
		)
		(layer "In1.Cu")
	)
	(gr_line
		(start 140.6906 -11.0998)
		(end 140.6906 -9.5504)
		(stroke
			(width 0.762)
			(type default)
		)
		(layer "In1.Cu")
	)
	(gr_line
		(start 140.693902 -11.0744)
		(end 140.693902 -9.5504)
		(stroke
			(width 0.508)
			(type default)
		)
		(layer "In1.Cu")
	)
	(gr_line
		(start 140.719302 -11.0744)
		(end 140.719302 -9.5504)
		(stroke
			(width 0.508)
			(type default)
		)
		(layer "In1.Cu")
	)
	(gr_line
		(start 140.770102 -11.2268)
		(end 140.795502 -11.2268)
		(stroke
			(width 0.2032)
			(type default)
		)
		(layer "In1.Cu")
	)
	(gr_line
		(start 140.795502 -11.2268)
		(end 140.795502 -9.4742)
		(stroke
			(width 0.2032)
			(type default)
		)
		(layer "In1.Cu")
	)
	(gr_line
		(start 140.795502 -9.4742)
		(end 139.754102 -9.4742)
		(stroke
			(width 0.2032)
			(type default)
		)
		(layer "In1.Cu")
	)
	(gr_line
		(start 140.8176 -11.1252)
		(end 140.8176 -9.5758)
		(stroke
			(width 0.762)
			(type default)
		)
		(layer "In1.Cu")
	)
	(gr_line
		(start 140.8176 -11.0998)
		(end 140.8176 -9.6012)
		(stroke
			(width 0.762)
			(type default)
		)
		(layer "In1.Cu")
	)
	(gr_line
		(start 140.8176 -10.9982)
		(end 140.8176 -9.4488)
		(stroke
			(width 0.762)
			(type default)
		)
		(layer "In1.Cu")
	)
	(gr_line
		(start 140.846302 -11.176)
		(end 140.846302 -9.4234)
		(stroke
			(width 0.2032)
			(type default)
		)
		(layer "In1.Cu")
	)
	(gr_line
		(start 140.846302 -9.4234)
		(end 139.703302 -9.4234)
		(stroke
			(width 0.2032)
			(type default)
		)
		(layer "In1.Cu")
	)
	(gr_line
		(start 140.871702 -11.2268)
		(end 140.871702 -9.3726)
		(stroke
			(width 0.2032)
			(type default)
		)
		(layer "In1.Cu")
	)
	(gr_line
		(start 140.871702 -9.3726)
		(end 139.677902 -9.3726)
		(stroke
			(width 0.2032)
			(type default)
		)
		(layer "In1.Cu")
	)
	(gr_line
		(start 140.922502 -11.303)
		(end 140.922502 -9.2964)
		(stroke
			(width 0.1016)
			(type default)
		)
		(layer "In1.Cu")
	)
	(gr_line
		(start 140.922502 -9.2964)
		(end 139.627102 -9.2964)
		(stroke
			(width 0.1016)
			(type default)
		)
		(layer "In1.Cu")
	)
	(gr_line
		(start 141.0208 -11.2268)
		(end 140.770102 -11.2268)
		(stroke
			(width 0.254)
			(type default)
		)
		(layer "In1.Cu")
	)
	(gr_line
		(start 141.0208 -9.3726)
		(end 141.0208 -11.2268)
		(stroke
			(width 0.254)
			(type default)
		)
		(layer "In1.Cu")
	)
	(gr_line
		(start 141.0462 -11.3538)
		(end 139.573 -11.3538)
		(stroke
			(width 0.254)
			(type default)
		)
		(layer "In1.Cu")
	)
	(gr_line
		(start 141.0462 -9.2456)
		(end 141.0462 -11.3538)
		(stroke
			(width 0.254)
			(type default)
		)
		(layer "In1.Cu")
	)
	(gr_line
		(start 141.0716 -11.3792)
		(end 139.5222 -11.3792)
		(stroke
			(width 0.254)
			(type default)
		)
		(layer "In1.Cu")
	)
	(gr_line
		(start 141.0716 -9.1948)
		(end 141.0716 -11.3792)
		(stroke
			(width 0.254)
			(type default)
		)
		(layer "In1.Cu")
	)
	(gr_line
		(start 144.296892 -11.3792)
		(end 144.296892 -9.1948)
		(stroke
			(width 0.254)
			(type default)
		)
		(layer "In1.Cu")
	)
	(gr_line
		(start 144.296892 -9.1948)
		(end 145.871692 -9.1948)
		(stroke
			(width 0.254)
			(type default)
		)
		(layer "In1.Cu")
	)
	(gr_line
		(start 144.322292 -11.3792)
		(end 144.322292 -9.2456)
		(stroke
			(width 0.254)
			(type default)
		)
		(layer "In1.Cu")
	)
	(gr_line
		(start 144.322292 -9.2456)
		(end 145.846292 -9.2456)
		(stroke
			(width 0.254)
			(type default)
		)
		(layer "In1.Cu")
	)
	(gr_line
		(start 144.373092 -11.3538)
		(end 144.373092 -9.3726)
		(stroke
			(width 0.254)
			(type default)
		)
		(layer "In1.Cu")
	)
	(gr_line
		(start 144.373092 -9.3726)
		(end 145.820892 -9.3726)
		(stroke
			(width 0.254)
			(type default)
		)
		(layer "In1.Cu")
	)
	(gr_line
		(start 144.427194 -11.303)
		(end 144.731994 -11.303)
		(stroke
			(width 0.1016)
			(type default)
		)
		(layer "In1.Cu")
	)
	(gr_line
		(start 144.427194 -9.2964)
		(end 144.427194 -11.303)
		(stroke
			(width 0.1016)
			(type default)
		)
		(layer "In1.Cu")
	)
	(gr_line
		(start 144.455134 -5.715)
		(end 145.725134 -5.715)
		(stroke
			(width 1.016)
			(type default)
		)
		(layer "In1.Cu")
	)
	(gr_line
		(start 144.477994 -11.2268)
		(end 145.570194 -11.2268)
		(stroke
			(width 0.2032)
			(type default)
		)
		(layer "In1.Cu")
	)
	(gr_line
		(start 144.477994 -9.3726)
		(end 144.477994 -11.2268)
		(stroke
			(width 0.2032)
			(type default)
		)
		(layer "In1.Cu")
	)
	(gr_line
		(start 144.503394 -11.2268)
		(end 145.671794 -11.2268)
		(stroke
			(width 0.2032)
			(type default)
		)
		(layer "In1.Cu")
	)
	(gr_line
		(start 144.503394 -9.4234)
		(end 144.503394 -11.2268)
		(stroke
			(width 0.2032)
			(type default)
		)
		(layer "In1.Cu")
	)
	(gr_line
		(start 144.550892 -11.1252)
		(end 144.550892 -9.5758)
		(stroke
			(width 0.762)
			(type default)
		)
		(layer "In1.Cu")
	)
	(gr_line
		(start 144.550892 -11.1252)
		(end 145.465292 -11.1252)
		(stroke
			(width 0.762)
			(type default)
		)
		(layer "In1.Cu")
	)
	(gr_line
		(start 144.550892 -11.0998)
		(end 144.550892 -9.5504)
		(stroke
			(width 0.762)
			(type default)
		)
		(layer "In1.Cu")
	)
	(gr_line
		(start 144.550892 -10.9982)
		(end 144.550892 -9.4488)
		(stroke
			(width 0.762)
			(type default)
		)
		(layer "In1.Cu")
	)
	(gr_line
		(start 144.550892 -9.4488)
		(end 145.465292 -9.4488)
		(stroke
			(width 0.762)
			(type default)
		)
		(layer "In1.Cu")
	)
	(gr_line
		(start 144.554194 -11.176)
		(end 145.646394 -11.176)
		(stroke
			(width 0.2032)
			(type default)
		)
		(layer "In1.Cu")
	)
	(gr_line
		(start 144.554194 -9.4742)
		(end 144.554194 -11.176)
		(stroke
			(width 0.2032)
			(type default)
		)
		(layer "In1.Cu")
	)
	(gr_line
		(start 144.576292 -10.9982)
		(end 145.490692 -10.9982)
		(stroke
			(width 0.762)
			(type default)
		)
		(layer "In1.Cu")
	)
	(gr_line
		(start 144.576292 -9.5758)
		(end 145.490692 -9.5758)
		(stroke
			(width 0.762)
			(type default)
		)
		(layer "In1.Cu")
	)
	(gr_line
		(start 144.655794 -11.0744)
		(end 145.443194 -11.0744)
		(stroke
			(width 0.508)
			(type default)
		)
		(layer "In1.Cu")
	)
	(gr_line
		(start 144.655794 -11.049)
		(end 144.655794 -9.525)
		(stroke
			(width 0.508)
			(type default)
		)
		(layer "In1.Cu")
	)
	(gr_line
		(start 144.681194 -11.0744)
		(end 144.681194 -9.5504)
		(stroke
			(width 0.508)
			(type default)
		)
		(layer "In1.Cu")
	)
	(gr_line
		(start 144.703292 -11.1252)
		(end 145.617692 -11.1252)
		(stroke
			(width 0.762)
			(type default)
		)
		(layer "In1.Cu")
	)
	(gr_line
		(start 144.703292 -9.4488)
		(end 145.617692 -9.4488)
		(stroke
			(width 0.762)
			(type default)
		)
		(layer "In1.Cu")
	)
	(gr_line
		(start 144.706594 -9.525)
		(end 145.443194 -9.525)
		(stroke
			(width 0.508)
			(type default)
		)
		(layer "In1.Cu")
	)
	(gr_line
		(start 144.731994 -11.303)
		(end 145.722594 -11.303)
		(stroke
			(width 0.1016)
			(type default)
		)
		(layer "In1.Cu")
	)
	(gr_line
		(start 144.731994 -11.0744)
		(end 144.731994 -9.5504)
		(stroke
			(width 0.508)
			(type default)
		)
		(layer "In1.Cu")
	)
	(gr_line
		(start 144.757394 -11.0744)
		(end 144.757394 -9.5504)
		(stroke
			(width 0.508)
			(type default)
		)
		(layer "In1.Cu")
	)
	(gr_line
		(start 144.782794 -11.0744)
		(end 144.782794 -9.5504)
		(stroke
			(width 0.508)
			(type default)
		)
		(layer "In1.Cu")
	)
	(gr_line
		(start 144.808194 -11.0744)
		(end 144.808194 -9.5504)
		(stroke
			(width 0.508)
			(type default)
		)
		(layer "In1.Cu")
	)
	(gr_line
		(start 144.808194 -11.049)
		(end 144.808194 -9.525)
		(stroke
			(width 0.508)
			(type default)
		)
		(layer "In1.Cu")
	)
	(gr_line
		(start 144.833594 -11.0744)
		(end 144.833594 -9.5504)
		(stroke
			(width 0.508)
			(type default)
		)
		(layer "In1.Cu")
	)
	(gr_line
		(start 144.858994 -11.0744)
		(end 144.858994 -9.5504)
		(stroke
			(width 0.508)
			(type default)
		)
		(layer "In1.Cu")
	)
	(gr_line
		(start 144.909794 -11.0744)
		(end 144.909794 -9.5504)
		(stroke
			(width 0.508)
			(type default)
		)
		(layer "In1.Cu")
	)
	(gr_line
		(start 144.909794 -11.049)
		(end 144.909794 -9.525)
		(stroke
			(width 0.508)
			(type default)
		)
		(layer "In1.Cu")
	)
	(gr_line
		(start 144.935194 -11.0744)
		(end 144.935194 -9.5504)
		(stroke
			(width 0.508)
			(type default)
		)
		(layer "In1.Cu")
	)
	(gr_line
		(start 144.960594 -11.0744)
		(end 144.960594 -9.5504)
		(stroke
			(width 0.508)
			(type default)
		)
		(layer "In1.Cu")
	)
	(gr_line
		(start 144.985994 -11.0744)
		(end 144.985994 -9.5504)
		(stroke
			(width 0.508)
			(type default)
		)
		(layer "In1.Cu")
	)
	(gr_line
		(start 145.036794 -11.0744)
		(end 145.036794 -9.5504)
		(stroke
			(width 0.508)
			(type default)
		)
		(layer "In1.Cu")
	)
	(gr_line
		(start 145.062194 -11.0744)
		(end 145.062194 -9.5504)
		(stroke
			(width 0.508)
			(type default)
		)
		(layer "In1.Cu")
	)
	(gr_line
		(start 145.062194 -11.049)
		(end 145.062194 -9.525)
		(stroke
			(width 0.508)
			(type default)
		)
		(layer "In1.Cu")
	)
	(gr_line
		(start 145.087594 -11.0744)
		(end 145.087594 -9.5504)
		(stroke
			(width 0.508)
			(type default)
		)
		(layer "In1.Cu")
	)
	(gr_line
		(start 145.112994 -11.0744)
		(end 145.112994 -9.5504)
		(stroke
			(width 0.508)
			(type default)
		)
		(layer "In1.Cu")
	)
	(gr_line
		(start 145.138394 -11.0744)
		(end 145.138394 -9.5504)
		(stroke
			(width 0.508)
			(type default)
		)
		(layer "In1.Cu")
	)
	(gr_line
		(start 145.138394 -11.049)
		(end 145.138394 -9.525)
		(stroke
			(width 0.508)
			(type default)
		)
		(layer "In1.Cu")
	)
	(gr_line
		(start 145.163794 -11.0744)
		(end 145.163794 -9.5504)
		(stroke
			(width 0.508)
			(type default)
		)
		(layer "In1.Cu")
	)
	(gr_line
		(start 145.189194 -11.0744)
		(end 145.189194 -9.5504)
		(stroke
			(width 0.508)
			(type default)
		)
		(layer "In1.Cu")
	)
	(gr_line
		(start 145.189194 -11.049)
		(end 145.189194 -9.525)
		(stroke
			(width 0.508)
			(type default)
		)
		(layer "In1.Cu")
	)
	(gr_line
		(start 145.214594 -11.0744)
		(end 145.214594 -9.5504)
		(stroke
			(width 0.508)
			(type default)
		)
		(layer "In1.Cu")
	)
	(gr_line
		(start 145.214594 -11.049)
		(end 145.214594 -9.525)
		(stroke
			(width 0.508)
			(type default)
		)
		(layer "In1.Cu")
	)
	(gr_line
		(start 145.239994 -11.049)
		(end 145.239994 -9.525)
		(stroke
			(width 0.508)
			(type default)
		)
		(layer "In1.Cu")
	)
	(gr_line
		(start 145.265394 -11.0744)
		(end 145.265394 -9.5504)
		(stroke
			(width 0.508)
			(type default)
		)
		(layer "In1.Cu")
	)
	(gr_line
		(start 145.287492 -11.3792)
		(end 144.296892 -11.3792)
		(stroke
			(width 0.254)
			(type default)
		)
		(layer "In1.Cu")
	)
	(gr_line
		(start 145.290794 -11.049)
		(end 145.290794 -9.525)
		(stroke
			(width 0.508)
			(type default)
		)
		(layer "In1.Cu")
	)
	(gr_line
		(start 145.316194 -11.049)
		(end 145.316194 -9.525)
		(stroke
			(width 0.508)
			(type default)
		)
		(layer "In1.Cu")
	)
	(gr_line
		(start 145.341594 -11.0744)
		(end 145.341594 -9.5504)
		(stroke
			(width 0.508)
			(type default)
		)
		(layer "In1.Cu")
	)
	(gr_line
		(start 145.366994 -11.0744)
		(end 145.366994 -9.5504)
		(stroke
			(width 0.508)
			(type default)
		)
		(layer "In1.Cu")
	)
	(gr_line
		(start 145.366994 -11.049)
		(end 145.366994 -9.525)
		(stroke
			(width 0.508)
			(type default)
		)
		(layer "In1.Cu")
	)
	(gr_line
		(start 145.417794 -11.0744)
		(end 145.417794 -9.5504)
		(stroke
			(width 0.508)
			(type default)
		)
		(layer "In1.Cu")
	)
	(gr_line
		(start 145.417794 -11.049)
		(end 145.417794 -9.525)
		(stroke
			(width 0.508)
			(type default)
		)
		(layer "In1.Cu")
	)
	(gr_line
		(start 145.468594 -11.0744)
		(end 145.468594 -9.5504)
		(stroke
			(width 0.508)
			(type default)
		)
		(layer "In1.Cu")
	)
	(gr_line
		(start 145.468594 -11.049)
		(end 145.468594 -9.525)
		(stroke
			(width 0.508)
			(type default)
		)
		(layer "In1.Cu")
	)
	(gr_line
		(start 145.490692 -11.0998)
		(end 145.490692 -9.5504)
		(stroke
			(width 0.762)
			(type default)
		)
		(layer "In1.Cu")
	)
	(gr_line
		(start 145.493994 -11.0744)
		(end 145.493994 -9.5504)
		(stroke
			(width 0.508)
			(type default)
		)
		(layer "In1.Cu")
	)
	(gr_line
		(start 145.519394 -11.0744)
		(end 145.519394 -9.5504)
		(stroke
			(width 0.508)
			(type default)
		)
		(layer "In1.Cu")
	)
	(gr_line
		(start 145.570194 -11.2268)
		(end 145.595594 -11.2268)
		(stroke
			(width 0.2032)
			(type default)
		)
		(layer "In1.Cu")
	)
	(gr_line
		(start 145.595594 -11.2268)
		(end 145.595594 -9.4742)
		(stroke
			(width 0.2032)
			(type default)
		)
		(layer "In1.Cu")
	)
	(gr_line
		(start 145.595594 -9.4742)
		(end 144.554194 -9.4742)
		(stroke
			(width 0.2032)
			(type default)
		)
		(layer "In1.Cu")
	)
	(gr_line
		(start 145.617692 -11.1252)
		(end 145.617692 -9.5758)
		(stroke
			(width 0.762)
			(type default)
		)
		(layer "In1.Cu")
	)
	(gr_line
		(start 145.617692 -11.0998)
		(end 145.617692 -9.6012)
		(stroke
			(width 0.762)
			(type default)
		)
		(layer "In1.Cu")
	)
	(gr_line
		(start 145.617692 -10.9982)
		(end 145.617692 -9.4488)
		(stroke
			(width 0.762)
			(type default)
		)
		(layer "In1.Cu")
	)
	(gr_line
		(start 145.646394 -11.176)
		(end 145.646394 -9.4234)
		(stroke
			(width 0.2032)
			(type default)
		)
		(layer "In1.Cu")
	)
	(gr_line
		(start 145.646394 -9.4234)
		(end 144.503394 -9.4234)
		(stroke
			(width 0.2032)
			(type default)
		)
		(layer "In1.Cu")
	)
	(gr_line
		(start 145.671794 -11.2268)
		(end 145.671794 -9.3726)
		(stroke
			(width 0.2032)
			(type default)
		)
		(layer "In1.Cu")
	)
	(gr_line
		(start 145.671794 -9.3726)
		(end 144.477994 -9.3726)
		(stroke
			(width 0.2032)
			(type default)
		)
		(layer "In1.Cu")
	)
	(gr_line
		(start 145.722594 -11.303)
		(end 145.722594 -9.2964)
		(stroke
			(width 0.1016)
			(type default)
		)
		(layer "In1.Cu")
	)
	(gr_line
		(start 145.722594 -9.2964)
		(end 144.427194 -9.2964)
		(stroke
			(width 0.1016)
			(type default)
		)
		(layer "In1.Cu")
	)
	(gr_line
		(start 145.820892 -11.2268)
		(end 145.570194 -11.2268)
		(stroke
			(width 0.254)
			(type default)
		)
		(layer "In1.Cu")
	)
	(gr_line
		(start 145.820892 -9.3726)
		(end 145.820892 -11.2268)
		(stroke
			(width 0.254)
			(type default)
		)
		(layer "In1.Cu")
	)
	(gr_line
		(start 145.846292 -11.3538)
		(end 144.373092 -11.3538)
		(stroke
			(width 0.254)
			(type default)
		)
		(layer "In1.Cu")
	)
	(gr_line
		(start 145.846292 -9.2456)
		(end 145.846292 -11.3538)
		(stroke
			(width 0.254)
			(type default)
		)
		(layer "In1.Cu")
	)
	(gr_line
		(start 145.871692 -11.3792)
		(end 144.322292 -11.3792)
		(stroke
			(width 0.254)
			(type default)
		)
		(layer "In1.Cu")
	)
	(gr_line
		(start 145.871692 -9.1948)
		(end 145.871692 -11.3792)
		(stroke
			(width 0.254)
			(type default)
		)
		(layer "In1.Cu")
	)
	(gr_arc
		(start 150.990046 -51.319938)
		(mid 151.282939 -52.027043)
		(end 151.990044 -52.319936)
		(stroke
			(width 1.016)
			(type default)
		)
		(layer "In1.Cu")
	)
	(gr_arc
		(start 150.990046 -50.8)
		(mid 150.697156 -50.092878)
		(end 149.990048 -49.800002)
		(stroke
			(width 1.016)
			(type default)
		)
		(layer "In1.Cu")
	)
	(gr_line
		(start 150.990046 -50.8)
		(end 150.990046 -51.319938)
		(stroke
			(width 1.016)
			(type default)
		)
		(layer "In1.Cu")
	)
	(gr_line
		(start 151.990044 -52.319936)
		(end 158.99003 -52.319936)
		(stroke
			(width 1.016)
			(type default)
		)
		(layer "In1.Cu")
	)
	(gr_line
		(start 158.99003 -52.319936)
		(end 159.372554 -52.24399)
		(stroke
			(width 1.016)
			(type default)
		)
		(layer "In1.Cu")
	)
	(gr_line
		(start 159.372554 -52.24399)
		(end 159.697166 -52.027074)
		(stroke
			(width 1.016)
			(type default)
		)
		(layer "In1.Cu")
	)
	(gr_line
		(start 159.697166 -52.027074)
		(end 159.913828 -51.702716)
		(stroke
			(width 1.016)
			(type default)
		)
		(layer "In1.Cu")
	)
	(gr_line
		(start 159.913828 -51.702716)
		(end 159.982154 -51.376072)
		(stroke
			(width 1.016)
			(type default)
		)
		(layer "In1.Cu")
	)
	(gr_line
		(start 159.982154 -51.376072)
		(end 160.0708 -50.996088)
		(stroke
			(width 1.016)
			(type default)
		)
		(layer "In1.Cu")
	)
	(gr_line
		(start 160.0708 -50.996088)
		(end 160.288732 -50.677064)
		(stroke
			(width 1.016)
			(type default)
		)
		(layer "In1.Cu")
	)
	(gr_line
		(start 160.288732 -50.677064)
		(end 160.611058 -50.464466)
		(stroke
			(width 1.016)
			(type default)
		)
		(layer "In1.Cu")
	)
	(gr_line
		(start 160.611058 -50.464466)
		(end 160.990026 -50.390044)
		(stroke
			(width 1.016)
			(type default)
		)
		(layer "In1.Cu")
	)
	(gr_line
		(start 160.990026 -50.390044)
		(end 202.989942 -50.390044)
		(stroke
			(width 1.016)
			(type default)
		)
		(layer "In1.Cu")
	)
	(gr_line
		(start 164.2872 -13.8176)
		(end 165.0746 -13.8176)
		(stroke
			(width 0.1016)
			(type default)
		)
		(layer "In1.Cu")
	)
	(gr_line
		(start 164.2872 -13.7668)
		(end 164.2872 -11.1506)
		(stroke
			(width 0.1016)
			(type default)
		)
		(layer "In1.Cu")
	)
	(gr_line
		(start 164.2872 -11.1506)
		(end 164.2872 -13.8176)
		(stroke
			(width 0.1016)
			(type default)
		)
		(layer "In1.Cu")
	)
	(gr_line
		(start 164.2872 -11.1506)
		(end 165.481 -11.1506)
		(stroke
			(width 0.1016)
			(type default)
		)
		(layer "In1.Cu")
	)
	(gr_line
		(start 164.2872 -9.617456)
		(end 165.0746 -9.617456)
		(stroke
			(width 0.1016)
			(type default)
		)
		(layer "In1.Cu")
	)
	(gr_line
		(start 164.2872 -9.566656)
		(end 164.2872 -6.950456)
		(stroke
			(width 0.1016)
			(type default)
		)
		(layer "In1.Cu")
	)
	(gr_line
		(start 164.2872 -6.950456)
		(end 164.2872 -9.617456)
		(stroke
			(width 0.1016)
			(type default)
		)
		(layer "In1.Cu")
	)
	(gr_line
		(start 164.2872 -6.950456)
		(end 165.481 -6.950456)
		(stroke
			(width 0.1016)
			(type default)
		)
		(layer "In1.Cu")
	)
	(gr_line
		(start 164.2872 -5.417312)
		(end 165.0746 -5.417312)
		(stroke
			(width 0.1016)
			(type default)
		)
		(layer "In1.Cu")
	)
	(gr_line
		(start 164.2872 -5.366512)
		(end 164.2872 -2.750312)
		(stroke
			(width 0.1016)
			(type default)
		)
		(layer "In1.Cu")
	)
	(gr_line
		(start 164.2872 -2.750312)
		(end 164.2872 -5.417312)
		(stroke
			(width 0.1016)
			(type default)
		)
		(layer "In1.Cu")
	)
	(gr_line
		(start 164.2872 -2.750312)
		(end 165.481 -2.750312)
		(stroke
			(width 0.1016)
			(type default)
		)
		(layer "In1.Cu")
	)
	(gr_line
		(start 164.3126 -13.7668)
		(end 164.3126 -11.176)
		(stroke
			(width 0.1016)
			(type default)
		)
		(layer "In1.Cu")
	)
	(gr_line
		(start 164.3126 -11.176)
		(end 165.4556 -11.176)
		(stroke
			(width 0.1016)
			(type default)
		)
		(layer "In1.Cu")
	)
	(gr_line
		(start 164.3126 -9.566656)
		(end 164.3126 -6.975856)
		(stroke
			(width 0.1016)
			(type default)
		)
		(layer "In1.Cu")
	)
	(gr_line
		(start 164.3126 -6.975856)
		(end 165.4556 -6.975856)
		(stroke
			(width 0.1016)
			(type default)
		)
		(layer "In1.Cu")
	)
	(gr_line
		(start 164.3126 -5.366512)
		(end 164.3126 -2.775712)
		(stroke
			(width 0.1016)
			(type default)
		)
		(layer "In1.Cu")
	)
	(gr_line
		(start 164.3126 -2.775712)
		(end 165.4556 -2.775712)
		(stroke
			(width 0.1016)
			(type default)
		)
		(layer "In1.Cu")
	)
	(gr_line
		(start 164.338 -13.7668)
		(end 164.338 -11.2014)
		(stroke
			(width 0.1016)
			(type default)
		)
		(layer "In1.Cu")
	)
	(gr_line
		(start 164.338 -11.2014)
		(end 164.592 -11.2014)
		(stroke
			(width 0.1016)
			(type default)
		)
		(layer "In1.Cu")
	)
	(gr_line
		(start 164.338 -9.566656)
		(end 164.338 -7.001256)
		(stroke
			(width 0.1016)
			(type default)
		)
		(layer "In1.Cu")
	)
	(gr_line
		(start 164.338 -7.001256)
		(end 164.592 -7.001256)
		(stroke
			(width 0.1016)
			(type default)
		)
		(layer "In1.Cu")
	)
	(gr_line
		(start 164.338 -5.366512)
		(end 164.338 -2.801112)
		(stroke
			(width 0.1016)
			(type default)
		)
		(layer "In1.Cu")
	)
	(gr_line
		(start 164.338 -2.801112)
		(end 164.592 -2.801112)
		(stroke
			(width 0.1016)
			(type default)
		)
		(layer "In1.Cu")
	)
	(gr_line
		(start 164.3634 -13.7668)
		(end 164.3634 -11.2014)
		(stroke
			(width 0.2032)
			(type default)
		)
		(layer "In1.Cu")
	)
	(gr_line
		(start 164.3634 -11.2014)
		(end 165.3794 -11.2014)
		(stroke
			(width 0.2032)
			(type default)
		)
		(layer "In1.Cu")
	)
	(gr_line
		(start 164.3634 -9.566656)
		(end 164.3634 -7.001256)
		(stroke
			(width 0.2032)
			(type default)
		)
		(layer "In1.Cu")
	)
	(gr_line
		(start 164.3634 -7.001256)
		(end 165.3794 -7.001256)
		(stroke
			(width 0.2032)
			(type default)
		)
		(layer "In1.Cu")
	)
	(gr_line
		(start 164.3634 -5.366512)
		(end 164.3634 -2.801112)
		(stroke
			(width 0.2032)
			(type default)
		)
		(layer "In1.Cu")
	)
	(gr_line
		(start 164.3634 -2.801112)
		(end 165.3794 -2.801112)
		(stroke
			(width 0.2032)
			(type default)
		)
		(layer "In1.Cu")
	)
	(gr_line
		(start 164.4142 -13.7414)
		(end 164.4142 -11.2522)
		(stroke
			(width 0.2032)
			(type default)
		)
		(layer "In1.Cu")
	)
	(gr_line
		(start 164.4142 -13.7414)
		(end 164.4142 -11.2522)
		(stroke
			(width 0.254)
			(type default)
		)
		(layer "In1.Cu")
	)
	(gr_line
		(start 164.4142 -11.2522)
		(end 164.6174 -11.2522)
		(stroke
			(width 0.2032)
			(type default)
		)
		(layer "In1.Cu")
	)
	(gr_line
		(start 164.4142 -11.2522)
		(end 165.3032 -11.2522)
		(stroke
			(width 0.254)
			(type default)
		)
		(layer "In1.Cu")
	)
	(gr_line
		(start 164.4142 -9.541256)
		(end 164.4142 -7.052056)
		(stroke
			(width 0.2032)
			(type default)
		)
		(layer "In1.Cu")
	)
	(gr_line
		(start 164.4142 -9.541256)
		(end 164.4142 -7.052056)
		(stroke
			(width 0.254)
			(type default)
		)
		(layer "In1.Cu")
	)
	(gr_line
		(start 164.4142 -7.052056)
		(end 164.6174 -7.052056)
		(stroke
			(width 0.2032)
			(type default)
		)
		(layer "In1.Cu")
	)
	(gr_line
		(start 164.4142 -7.052056)
		(end 165.3032 -7.052056)
		(stroke
			(width 0.254)
			(type default)
		)
		(layer "In1.Cu")
	)
	(gr_line
		(start 164.4142 -5.341112)
		(end 164.4142 -2.851912)
		(stroke
			(width 0.2032)
			(type default)
		)
		(layer "In1.Cu")
	)
	(gr_line
		(start 164.4142 -5.341112)
		(end 164.4142 -2.851912)
		(stroke
			(width 0.254)
			(type default)
		)
		(layer "In1.Cu")
	)
	(gr_line
		(start 164.4142 -2.851912)
		(end 164.6174 -2.851912)
		(stroke
			(width 0.2032)
			(type default)
		)
		(layer "In1.Cu")
	)
	(gr_line
		(start 164.4142 -2.851912)
		(end 165.3032 -2.851912)
		(stroke
			(width 0.254)
			(type default)
		)
		(layer "In1.Cu")
	)
	(gr_line
		(start 164.4396 -13.716)
		(end 164.4396 -11.2776)
		(stroke
			(width 0.254)
			(type default)
		)
		(layer "In1.Cu")
	)
	(gr_line
		(start 164.4396 -11.2776)
		(end 165.2778 -11.2776)
		(stroke
			(width 0.254)
			(type default)
		)
		(layer "In1.Cu")
	)
	(gr_line
		(start 164.4396 -9.515856)
		(end 164.4396 -7.077456)
		(stroke
			(width 0.254)
			(type default)
		)
		(layer "In1.Cu")
	)
	(gr_line
		(start 164.4396 -7.077456)
		(end 165.2778 -7.077456)
		(stroke
			(width 0.254)
			(type default)
		)
		(layer "In1.Cu")
	)
	(gr_line
		(start 164.4396 -5.315712)
		(end 164.4396 -2.877312)
		(stroke
			(width 0.254)
			(type default)
		)
		(layer "In1.Cu")
	)
	(gr_line
		(start 164.4396 -2.877312)
		(end 165.2778 -2.877312)
		(stroke
			(width 0.254)
			(type default)
		)
		(layer "In1.Cu")
	)
	(gr_line
		(start 164.465 -13.6906)
		(end 164.465 -11.303)
		(stroke
			(width 0.254)
			(type default)
		)
		(layer "In1.Cu")
	)
	(gr_line
		(start 164.465 -11.303)
		(end 165.2524 -11.303)
		(stroke
			(width 0.254)
			(type default)
		)
		(layer "In1.Cu")
	)
	(gr_line
		(start 164.465 -9.490456)
		(end 164.465 -7.102856)
		(stroke
			(width 0.254)
			(type default)
		)
		(layer "In1.Cu")
	)
	(gr_line
		(start 164.465 -7.102856)
		(end 165.2524 -7.102856)
		(stroke
			(width 0.254)
			(type default)
		)
		(layer "In1.Cu")
	)
	(gr_line
		(start 164.465 -5.290312)
		(end 164.465 -2.902712)
		(stroke
			(width 0.254)
			(type default)
		)
		(layer "In1.Cu")
	)
	(gr_line
		(start 164.465 -2.902712)
		(end 165.2524 -2.902712)
		(stroke
			(width 0.254)
			(type default)
		)
		(layer "In1.Cu")
	)
	(gr_line
		(start 164.4904 -13.6144)
		(end 165.1254 -13.6144)
		(stroke
			(width 0.508)
			(type default)
		)
		(layer "In1.Cu")
	)
	(gr_line
		(start 164.4904 -11.43)
		(end 165.1254 -11.43)
		(stroke
			(width 0.508)
			(type default)
		)
		(layer "In1.Cu")
	)
	(gr_line
		(start 164.4904 -11.3792)
		(end 165.1254 -11.3792)
		(stroke
			(width 0.508)
			(type default)
		)
		(layer "In1.Cu")
	)
	(gr_line
		(start 164.4904 -9.414256)
		(end 165.1254 -9.414256)
		(stroke
			(width 0.508)
			(type default)
		)
		(layer "In1.Cu")
	)
	(gr_line
		(start 164.4904 -7.229856)
		(end 165.1254 -7.229856)
		(stroke
			(width 0.508)
			(type default)
		)
		(layer "In1.Cu")
	)
	(gr_line
		(start 164.4904 -7.179056)
		(end 165.1254 -7.179056)
		(stroke
			(width 0.508)
			(type default)
		)
		(layer "In1.Cu")
	)
	(gr_line
		(start 164.4904 -5.214112)
		(end 165.1254 -5.214112)
		(stroke
			(width 0.508)
			(type default)
		)
		(layer "In1.Cu")
	)
	(gr_line
		(start 164.4904 -3.029712)
		(end 165.1254 -3.029712)
		(stroke
			(width 0.508)
			(type default)
		)
		(layer "In1.Cu")
	)
	(gr_line
		(start 164.4904 -2.978912)
		(end 165.1254 -2.978912)
		(stroke
			(width 0.508)
			(type default)
		)
		(layer "In1.Cu")
	)
	(gr_line
		(start 164.5158 -11.684)
		(end 165.1508 -11.684)
		(stroke
			(width 0.508)
			(type default)
		)
		(layer "In1.Cu")
	)
	(gr_line
		(start 164.5158 -7.483856)
		(end 165.1508 -7.483856)
		(stroke
			(width 0.508)
			(type default)
		)
		(layer "In1.Cu")
	)
	(gr_line
		(start 164.5158 -3.283712)
		(end 165.1508 -3.283712)
		(stroke
			(width 0.508)
			(type default)
		)
		(layer "In1.Cu")
	)
	(gr_line
		(start 164.5412 -13.6398)
		(end 164.5412 -11.3792)
		(stroke
			(width 0.254)
			(type default)
		)
		(layer "In1.Cu")
	)
	(gr_line
		(start 164.5412 -13.4874)
		(end 165.1762 -13.4874)
		(stroke
			(width 0.508)
			(type default)
		)
		(layer "In1.Cu")
	)
	(gr_line
		(start 164.5412 -11.3792)
		(end 165.1762 -11.3792)
		(stroke
			(width 0.254)
			(type default)
		)
		(layer "In1.Cu")
	)
	(gr_line
		(start 164.5412 -9.439656)
		(end 164.5412 -7.179056)
		(stroke
			(width 0.254)
			(type default)
		)
		(layer "In1.Cu")
	)
	(gr_line
		(start 164.5412 -9.287256)
		(end 165.1762 -9.287256)
		(stroke
			(width 0.508)
			(type default)
		)
		(layer "In1.Cu")
	)
	(gr_line
		(start 164.5412 -7.179056)
		(end 165.1762 -7.179056)
		(stroke
			(width 0.254)
			(type default)
		)
		(layer "In1.Cu")
	)
	(gr_line
		(start 164.5412 -5.239512)
		(end 164.5412 -2.978912)
		(stroke
			(width 0.254)
			(type default)
		)
		(layer "In1.Cu")
	)
	(gr_line
		(start 164.5412 -5.087112)
		(end 165.1762 -5.087112)
		(stroke
			(width 0.508)
			(type default)
		)
		(layer "In1.Cu")
	)
	(gr_line
		(start 164.5412 -2.978912)
		(end 165.1762 -2.978912)
		(stroke
			(width 0.254)
			(type default)
		)
		(layer "In1.Cu")
	)
	(gr_line
		(start 164.5666 -13.335)
		(end 165.2016 -13.335)
		(stroke
			(width 0.508)
			(type default)
		)
		(layer "In1.Cu")
	)
	(gr_line
		(start 164.5666 -9.134856)
		(end 165.2016 -9.134856)
		(stroke
			(width 0.508)
			(type default)
		)
		(layer "In1.Cu")
	)
	(gr_line
		(start 164.5666 -4.934712)
		(end 165.2016 -4.934712)
		(stroke
			(width 0.508)
			(type default)
		)
		(layer "In1.Cu")
	)
	(gr_line
		(start 164.592 -13.6144)
		(end 165.227 -13.6144)
		(stroke
			(width 0.508)
			(type default)
		)
		(layer "In1.Cu")
	)
	(gr_line
		(start 164.592 -11.2014)
		(end 165.4302 -11.2014)
		(stroke
			(width 0.2032)
			(type default)
		)
		(layer "In1.Cu")
	)
	(gr_line
		(start 164.592 -9.414256)
		(end 165.227 -9.414256)
		(stroke
			(width 0.508)
			(type default)
		)
		(layer "In1.Cu")
	)
	(gr_line
		(start 164.592 -7.001256)
		(end 165.4302 -7.001256)
		(stroke
			(width 0.2032)
			(type default)
		)
		(layer "In1.Cu")
	)
	(gr_line
		(start 164.592 -5.214112)
		(end 165.227 -5.214112)
		(stroke
			(width 0.508)
			(type default)
		)
		(layer "In1.Cu")
	)
	(gr_line
		(start 164.592 -2.801112)
		(end 165.4302 -2.801112)
		(stroke
			(width 0.2032)
			(type default)
		)
		(layer "In1.Cu")
	)
	(gr_line
		(start 164.6174 -13.6144)
		(end 164.6174 -11.43)
		(stroke
			(width 0.254)
			(type default)
		)
		(layer "In1.Cu")
	)
	(gr_line
		(start 164.6174 -11.43)
		(end 165.1 -11.43)
		(stroke
			(width 0.254)
			(type default)
		)
		(layer "In1.Cu")
	)
	(gr_line
		(start 164.6174 -11.2522)
		(end 165.354 -11.2522)
		(stroke
			(width 0.254)
			(type default)
		)
		(layer "In1.Cu")
	)
	(gr_line
		(start 164.6174 -9.414256)
		(end 164.6174 -7.229856)
		(stroke
			(width 0.254)
			(type default)
		)
		(layer "In1.Cu")
	)
	(gr_line
		(start 164.6174 -7.229856)
		(end 165.1 -7.229856)
		(stroke
			(width 0.254)
			(type default)
		)
		(layer "In1.Cu")
	)
	(gr_line
		(start 164.6174 -7.052056)
		(end 165.354 -7.052056)
		(stroke
			(width 0.254)
			(type default)
		)
		(layer "In1.Cu")
	)
	(gr_line
		(start 164.6174 -5.214112)
		(end 164.6174 -3.029712)
		(stroke
			(width 0.254)
			(type default)
		)
		(layer "In1.Cu")
	)
	(gr_line
		(start 164.6174 -3.029712)
		(end 165.1 -3.029712)
		(stroke
			(width 0.254)
			(type default)
		)
		(layer "In1.Cu")
	)
	(gr_line
		(start 164.6174 -2.851912)
		(end 165.354 -2.851912)
		(stroke
			(width 0.254)
			(type default)
		)
		(layer "In1.Cu")
	)
	(gr_line
		(start 164.635942 -11.36523)
		(end 165.270942 -11.36523)
		(stroke
			(width 0.508)
			(type default)
		)
		(layer "In1.Cu")
	)
	(gr_line
		(start 164.635942 -7.165086)
		(end 165.270942 -7.165086)
		(stroke
			(width 0.508)
			(type default)
		)
		(layer "In1.Cu")
	)
	(gr_line
		(start 164.635942 -2.964942)
		(end 165.270942 -2.964942)
		(stroke
			(width 0.508)
			(type default)
		)
		(layer "In1.Cu")
	)
	(gr_line
		(start 164.6428 -13.6144)
		(end 165.2778 -13.6144)
		(stroke
			(width 0.508)
			(type default)
		)
		(layer "In1.Cu")
	)
	(gr_line
		(start 164.6428 -13.4874)
		(end 164.6428 -11.5062)
		(stroke
			(width 0.762)
			(type default)
		)
		(layer "In1.Cu")
	)
	(gr_line
		(start 164.6428 -11.5062)
		(end 165.2778 -11.5062)
		(stroke
			(width 0.508)
			(type default)
		)
		(layer "In1.Cu")
	)
	(gr_line
		(start 164.6428 -9.414256)
		(end 165.2778 -9.414256)
		(stroke
			(width 0.508)
			(type default)
		)
		(layer "In1.Cu")
	)
	(gr_line
		(start 164.6428 -9.287256)
		(end 164.6428 -7.306056)
		(stroke
			(width 0.762)
			(type default)
		)
		(layer "In1.Cu")
	)
	(gr_line
		(start 164.6428 -7.306056)
		(end 165.2778 -7.306056)
		(stroke
			(width 0.508)
			(type default)
		)
		(layer "In1.Cu")
	)
	(gr_line
		(start 164.6428 -5.214112)
		(end 165.2778 -5.214112)
		(stroke
			(width 0.508)
			(type default)
		)
		(layer "In1.Cu")
	)
	(gr_line
		(start 164.6428 -5.087112)
		(end 164.6428 -3.105912)
		(stroke
			(width 0.762)
			(type default)
		)
		(layer "In1.Cu")
	)
	(gr_line
		(start 164.6428 -3.105912)
		(end 165.2778 -3.105912)
		(stroke
			(width 0.508)
			(type default)
		)
		(layer "In1.Cu")
	)
	(gr_line
		(start 164.6936 -13.5382)
		(end 164.6936 -11.5062)
		(stroke
			(width 0.254)
			(type default)
		)
		(layer "In1.Cu")
	)
	(gr_line
		(start 164.6936 -11.5062)
		(end 165.0238 -11.5062)
		(stroke
			(width 0.254)
			(type default)
		)
		(layer "In1.Cu")
	)
	(gr_line
		(start 164.6936 -9.338056)
		(end 164.6936 -7.306056)
		(stroke
			(width 0.254)
			(type default)
		)
		(layer "In1.Cu")
	)
	(gr_line
		(start 164.6936 -7.306056)
		(end 165.0238 -7.306056)
		(stroke
			(width 0.254)
			(type default)
		)
		(layer "In1.Cu")
	)
	(gr_line
		(start 164.6936 -5.137912)
		(end 164.6936 -3.105912)
		(stroke
			(width 0.254)
			(type default)
		)
		(layer "In1.Cu")
	)
	(gr_line
		(start 164.6936 -3.105912)
		(end 165.0238 -3.105912)
		(stroke
			(width 0.254)
			(type default)
		)
		(layer "In1.Cu")
	)
	(gr_line
		(start 164.7952 -13.462)
		(end 164.7952 -11.6586)
		(stroke
			(width 0.254)
			(type default)
		)
		(layer "In1.Cu")
	)
	(gr_line
		(start 164.7952 -13.462)
		(end 164.7952 -11.4808)
		(stroke
			(width 0.762)
			(type default)
		)
		(layer "In1.Cu")
	)
	(gr_line
		(start 164.7952 -11.6586)
		(end 164.8968 -11.6586)
		(stroke
			(width 0.254)
			(type default)
		)
		(layer "In1.Cu")
	)
	(gr_line
		(start 164.7952 -9.261856)
		(end 164.7952 -7.458456)
		(stroke
			(width 0.254)
			(type default)
		)
		(layer "In1.Cu")
	)
	(gr_line
		(start 164.7952 -9.261856)
		(end 164.7952 -7.280656)
		(stroke
			(width 0.762)
			(type default)
		)
		(layer "In1.Cu")
	)
	(gr_line
		(start 164.7952 -7.458456)
		(end 164.8968 -7.458456)
		(stroke
			(width 0.254)
			(type default)
		)
		(layer "In1.Cu")
	)
	(gr_line
		(start 164.7952 -5.061712)
		(end 164.7952 -3.258312)
		(stroke
			(width 0.254)
			(type default)
		)
		(layer "In1.Cu")
	)
	(gr_line
		(start 164.7952 -5.061712)
		(end 164.7952 -3.080512)
		(stroke
			(width 0.762)
			(type default)
		)
		(layer "In1.Cu")
	)
	(gr_line
		(start 164.7952 -3.258312)
		(end 164.8968 -3.258312)
		(stroke
			(width 0.254)
			(type default)
		)
		(layer "In1.Cu")
	)
	(gr_line
		(start 164.8968 -13.5636)
		(end 164.846 -13.5636)
		(stroke
			(width 0.254)
			(type default)
		)
		(layer "In1.Cu")
	)
	(gr_line
		(start 164.8968 -11.6586)
		(end 164.8968 -13.5636)
		(stroke
			(width 0.254)
			(type default)
		)
		(layer "In1.Cu")
	)
	(gr_line
		(start 164.8968 -9.363456)
		(end 164.846 -9.363456)
		(stroke
			(width 0.254)
			(type default)
		)
		(layer "In1.Cu")
	)
	(gr_line
		(start 164.8968 -7.458456)
		(end 164.8968 -9.363456)
		(stroke
			(width 0.254)
			(type default)
		)
		(layer "In1.Cu")
	)
	(gr_line
		(start 164.8968 -5.163312)
		(end 164.846 -5.163312)
		(stroke
			(width 0.254)
			(type default)
		)
		(layer "In1.Cu")
	)
	(gr_line
		(start 164.8968 -3.258312)
		(end 164.8968 -5.163312)
		(stroke
			(width 0.254)
			(type default)
		)
		(layer "In1.Cu")
	)
	(gr_line
		(start 164.9476 -13.4874)
		(end 164.9476 -11.5062)
		(stroke
			(width 0.762)
			(type default)
		)
		(layer "In1.Cu")
	)
	(gr_line
		(start 164.9476 -9.287256)
		(end 164.9476 -7.306056)
		(stroke
			(width 0.762)
			(type default)
		)
		(layer "In1.Cu")
	)
	(gr_line
		(start 164.9476 -5.087112)
		(end 164.9476 -3.105912)
		(stroke
			(width 0.762)
			(type default)
		)
		(layer "In1.Cu")
	)
	(gr_line
		(start 165.0238 -13.462)
		(end 164.7952 -13.462)
		(stroke
			(width 0.254)
			(type default)
		)
		(layer "In1.Cu")
	)
	(gr_line
		(start 165.0238 -11.5062)
		(end 165.0238 -13.462)
		(stroke
			(width 0.254)
			(type default)
		)
		(layer "In1.Cu")
	)
	(gr_line
		(start 165.0238 -9.261856)
		(end 164.7952 -9.261856)
		(stroke
			(width 0.254)
			(type default)
		)
		(layer "In1.Cu")
	)
	(gr_line
		(start 165.0238 -7.306056)
		(end 165.0238 -9.261856)
		(stroke
			(width 0.254)
			(type default)
		)
		(layer "In1.Cu")
	)
	(gr_line
		(start 165.0238 -5.061712)
		(end 164.7952 -5.061712)
		(stroke
			(width 0.254)
			(type default)
		)
		(layer "In1.Cu")
	)
	(gr_line
		(start 165.0238 -3.105912)
		(end 165.0238 -5.061712)
		(stroke
			(width 0.254)
			(type default)
		)
		(layer "In1.Cu")
	)
	(gr_line
		(start 165.0746 -13.8176)
		(end 165.0746 -13.7668)
		(stroke
			(width 0.1016)
			(type default)
		)
		(layer "In1.Cu")
	)
	(gr_line
		(start 165.0746 -13.8176)
		(end 165.481 -13.8176)
		(stroke
			(width 0.1016)
			(type default)
		)
		(layer "In1.Cu")
	)
	(gr_line
		(start 165.0746 -13.7668)
		(end 164.3126 -13.7668)
		(stroke
			(width 0.1016)
			(type default)
		)
		(layer "In1.Cu")
	)
	(gr_line
		(start 165.0746 -13.4874)
		(end 165.0746 -11.5062)
		(stroke
			(width 0.762)
			(type default)
		)
		(layer "In1.Cu")
	)
	(gr_line
		(start 165.0746 -9.617456)
		(end 165.0746 -9.566656)
		(stroke
			(width 0.1016)
			(type default)
		)
		(layer "In1.Cu")
	)
	(gr_line
		(start 165.0746 -9.617456)
		(end 165.481 -9.617456)
		(stroke
			(width 0.1016)
			(type default)
		)
		(layer "In1.Cu")
	)
	(gr_line
		(start 165.0746 -9.566656)
		(end 164.3126 -9.566656)
		(stroke
			(width 0.1016)
			(type default)
		)
		(layer "In1.Cu")
	)
	(gr_line
		(start 165.0746 -9.287256)
		(end 165.0746 -7.306056)
		(stroke
			(width 0.762)
			(type default)
		)
		(layer "In1.Cu")
	)
	(gr_line
		(start 165.0746 -5.417312)
		(end 165.0746 -5.366512)
		(stroke
			(width 0.1016)
			(type default)
		)
		(layer "In1.Cu")
	)
	(gr_line
		(start 165.0746 -5.417312)
		(end 165.481 -5.417312)
		(stroke
			(width 0.1016)
			(type default)
		)
		(layer "In1.Cu")
	)
	(gr_line
		(start 165.0746 -5.366512)
		(end 164.3126 -5.366512)
		(stroke
			(width 0.1016)
			(type default)
		)
		(layer "In1.Cu")
	)
	(gr_line
		(start 165.0746 -5.087112)
		(end 165.0746 -3.105912)
		(stroke
			(width 0.762)
			(type default)
		)
		(layer "In1.Cu")
	)
	(gr_line
		(start 165.1 -13.5382)
		(end 164.6936 -13.5382)
		(stroke
			(width 0.254)
			(type default)
		)
		(layer "In1.Cu")
	)
	(gr_line
		(start 165.1 -11.43)
		(end 165.1 -13.5382)
		(stroke
			(width 0.254)
			(type default)
		)
		(layer "In1.Cu")
	)
	(gr_line
		(start 165.1 -9.338056)
		(end 164.6936 -9.338056)
		(stroke
			(width 0.254)
			(type default)
		)
		(layer "In1.Cu")
	)
	(gr_line
		(start 165.1 -7.229856)
		(end 165.1 -9.338056)
		(stroke
			(width 0.254)
			(type default)
		)
		(layer "In1.Cu")
	)
	(gr_line
		(start 165.1 -5.137912)
		(end 164.6936 -5.137912)
		(stroke
			(width 0.254)
			(type default)
		)
		(layer "In1.Cu")
	)
	(gr_line
		(start 165.1 -3.029712)
		(end 165.1 -5.137912)
		(stroke
			(width 0.254)
			(type default)
		)
		(layer "In1.Cu")
	)
	(gr_line
		(start 165.1508 -13.4874)
		(end 165.1508 -11.5062)
		(stroke
			(width 0.762)
			(type default)
		)
		(layer "In1.Cu")
	)
	(gr_line
		(start 165.1508 -9.287256)
		(end 165.1508 -7.306056)
		(stroke
			(width 0.762)
			(type default)
		)
		(layer "In1.Cu")
	)
	(gr_line
		(start 165.1508 -5.087112)
		(end 165.1508 -3.105912)
		(stroke
			(width 0.762)
			(type default)
		)
		(layer "In1.Cu")
	)
	(gr_line
		(start 165.1762 -13.6144)
		(end 164.6174 -13.6144)
		(stroke
			(width 0.254)
			(type default)
		)
		(layer "In1.Cu")
	)
	(gr_line
		(start 165.1762 -11.3792)
		(end 165.1762 -13.6144)
		(stroke
			(width 0.254)
			(type default)
		)
		(layer "In1.Cu")
	)
	(gr_line
		(start 165.1762 -9.414256)
		(end 164.6174 -9.414256)
		(stroke
			(width 0.254)
			(type default)
		)
		(layer "In1.Cu")
	)
	(gr_line
		(start 165.1762 -7.179056)
		(end 165.1762 -9.414256)
		(stroke
			(width 0.254)
			(type default)
		)
		(layer "In1.Cu")
	)
	(gr_line
		(start 165.1762 -5.214112)
		(end 164.6174 -5.214112)
		(stroke
			(width 0.254)
			(type default)
		)
		(layer "In1.Cu")
	)
	(gr_line
		(start 165.1762 -2.978912)
		(end 165.1762 -5.214112)
		(stroke
			(width 0.254)
			(type default)
		)
		(layer "In1.Cu")
	)
	(gr_line
		(start 165.2524 -13.6398)
		(end 164.5412 -13.6398)
		(stroke
			(width 0.254)
			(type default)
		)
		(layer "In1.Cu")
	)
	(gr_line
		(start 165.2524 -11.303)
		(end 165.2524 -13.6398)
		(stroke
			(width 0.254)
			(type default)
		)
		(layer "In1.Cu")
	)
	(gr_line
		(start 165.2524 -9.439656)
		(end 164.5412 -9.439656)
		(stroke
			(width 0.254)
			(type default)
		)
		(layer "In1.Cu")
	)
	(gr_line
		(start 165.2524 -7.102856)
		(end 165.2524 -9.439656)
		(stroke
			(width 0.254)
			(type default)
		)
		(layer "In1.Cu")
	)
	(gr_line
		(start 165.2524 -5.239512)
		(end 164.5412 -5.239512)
		(stroke
			(width 0.254)
			(type default)
		)
		(layer "In1.Cu")
	)
	(gr_line
		(start 165.2524 -2.902712)
		(end 165.2524 -5.239512)
		(stroke
			(width 0.254)
			(type default)
		)
		(layer "In1.Cu")
	)
	(gr_line
		(start 165.2778 -13.7668)
		(end 164.2872 -13.7668)
		(stroke
			(width 0.1016)
			(type default)
		)
		(layer "In1.Cu")
	)
	(gr_line
		(start 165.2778 -13.6906)
		(end 164.465 -13.6906)
		(stroke
			(width 0.254)
			(type default)
		)
		(layer "In1.Cu")
	)
	(gr_line
		(start 165.2778 -11.2776)
		(end 165.2778 -13.6906)
		(stroke
			(width 0.254)
			(type default)
		)
		(layer "In1.Cu")
	)
	(gr_line
		(start 165.2778 -9.566656)
		(end 164.2872 -9.566656)
		(stroke
			(width 0.1016)
			(type default)
		)
		(layer "In1.Cu")
	)
	(gr_line
		(start 165.2778 -9.490456)
		(end 164.465 -9.490456)
		(stroke
			(width 0.254)
			(type default)
		)
		(layer "In1.Cu")
	)
	(gr_line
		(start 165.2778 -7.077456)
		(end 165.2778 -9.490456)
		(stroke
			(width 0.254)
			(type default)
		)
		(layer "In1.Cu")
	)
	(gr_line
		(start 165.2778 -5.366512)
		(end 164.2872 -5.366512)
		(stroke
			(width 0.1016)
			(type default)
		)
		(layer "In1.Cu")
	)
	(gr_line
		(start 165.2778 -5.290312)
		(end 164.465 -5.290312)
		(stroke
			(width 0.254)
			(type default)
		)
		(layer "In1.Cu")
	)
	(gr_line
		(start 165.2778 -2.877312)
		(end 165.2778 -5.290312)
		(stroke
			(width 0.254)
			(type default)
		)
		(layer "In1.Cu")
	)
	(gr_line
		(start 165.3032 -13.716)
		(end 164.4396 -13.716)
		(stroke
			(width 0.254)
			(type default)
		)
		(layer "In1.Cu")
	)
	(gr_line
		(start 165.3032 -11.2522)
		(end 165.3032 -13.716)
		(stroke
			(width 0.254)
			(type default)
		)
		(layer "In1.Cu")
	)
	(gr_line
		(start 165.3032 -9.515856)
		(end 164.4396 -9.515856)
		(stroke
			(width 0.254)
			(type default)
		)
		(layer "In1.Cu")
	)
	(gr_line
		(start 165.3032 -7.052056)
		(end 165.3032 -9.515856)
		(stroke
			(width 0.254)
			(type default)
		)
		(layer "In1.Cu")
	)
	(gr_line
		(start 165.3032 -5.315712)
		(end 164.4396 -5.315712)
		(stroke
			(width 0.254)
			(type default)
		)
		(layer "In1.Cu")
	)
	(gr_line
		(start 165.3032 -2.851912)
		(end 165.3032 -5.315712)
		(stroke
			(width 0.254)
			(type default)
		)
		(layer "In1.Cu")
	)
	(gr_line
		(start 165.354 -13.7414)
		(end 164.4142 -13.7414)
		(stroke
			(width 0.254)
			(type default)
		)
		(layer "In1.Cu")
	)
	(gr_line
		(start 165.354 -11.2522)
		(end 165.354 -13.7414)
		(stroke
			(width 0.254)
			(type default)
		)
		(layer "In1.Cu")
	)
	(gr_line
		(start 165.354 -9.541256)
		(end 164.4142 -9.541256)
		(stroke
			(width 0.254)
			(type default)
		)
		(layer "In1.Cu")
	)
	(gr_line
		(start 165.354 -7.052056)
		(end 165.354 -9.541256)
		(stroke
			(width 0.254)
			(type default)
		)
		(layer "In1.Cu")
	)
	(gr_line
		(start 165.354 -5.341112)
		(end 164.4142 -5.341112)
		(stroke
			(width 0.254)
			(type default)
		)
		(layer "In1.Cu")
	)
	(gr_line
		(start 165.354 -2.851912)
		(end 165.354 -5.341112)
		(stroke
			(width 0.254)
			(type default)
		)
		(layer "In1.Cu")
	)
	(gr_line
		(start 165.3794 -13.7414)
		(end 164.4142 -13.7414)
		(stroke
			(width 0.2032)
			(type default)
		)
		(layer "In1.Cu")
	)
	(gr_line
		(start 165.3794 -11.2014)
		(end 165.3794 -13.7414)
		(stroke
			(width 0.2032)
			(type default)
		)
		(layer "In1.Cu")
	)
	(gr_line
		(start 165.3794 -9.541256)
		(end 164.4142 -9.541256)
		(stroke
			(width 0.2032)
			(type default)
		)
		(layer "In1.Cu")
	)
	(gr_line
		(start 165.3794 -7.001256)
		(end 165.3794 -9.541256)
		(stroke
			(width 0.2032)
			(type default)
		)
		(layer "In1.Cu")
	)
	(gr_line
		(start 165.3794 -5.341112)
		(end 164.4142 -5.341112)
		(stroke
			(width 0.2032)
			(type default)
		)
		(layer "In1.Cu")
	)
	(gr_line
		(start 165.3794 -2.801112)
		(end 165.3794 -5.341112)
		(stroke
			(width 0.2032)
			(type default)
		)
		(layer "In1.Cu")
	)
	(gr_line
		(start 165.4302 -13.7668)
		(end 164.3634 -13.7668)
		(stroke
			(width 0.2032)
			(type default)
		)
		(layer "In1.Cu")
	)
	(gr_line
		(start 165.4302 -11.2014)
		(end 165.4302 -13.7668)
		(stroke
			(width 0.2032)
			(type default)
		)
		(layer "In1.Cu")
	)
	(gr_line
		(start 165.4302 -9.566656)
		(end 164.3634 -9.566656)
		(stroke
			(width 0.2032)
			(type default)
		)
		(layer "In1.Cu")
	)
	(gr_line
		(start 165.4302 -7.001256)
		(end 165.4302 -9.566656)
		(stroke
			(width 0.2032)
			(type default)
		)
		(layer "In1.Cu")
	)
	(gr_line
		(start 165.4302 -5.366512)
		(end 164.3634 -5.366512)
		(stroke
			(width 0.2032)
			(type default)
		)
		(layer "In1.Cu")
	)
	(gr_line
		(start 165.4302 -2.801112)
		(end 165.4302 -5.366512)
		(stroke
			(width 0.2032)
			(type default)
		)
		(layer "In1.Cu")
	)
	(gr_line
		(start 165.4556 -13.7668)
		(end 164.338 -13.7668)
		(stroke
			(width 0.1016)
			(type default)
		)
		(layer "In1.Cu")
	)
	(gr_line
		(start 165.4556 -11.176)
		(end 165.4556 -13.7668)
		(stroke
			(width 0.1016)
			(type default)
		)
		(layer "In1.Cu")
	)
	(gr_line
		(start 165.4556 -9.566656)
		(end 164.338 -9.566656)
		(stroke
			(width 0.1016)
			(type default)
		)
		(layer "In1.Cu")
	)
	(gr_line
		(start 165.4556 -6.975856)
		(end 165.4556 -9.566656)
		(stroke
			(width 0.1016)
			(type default)
		)
		(layer "In1.Cu")
	)
	(gr_line
		(start 165.4556 -5.366512)
		(end 164.338 -5.366512)
		(stroke
			(width 0.1016)
			(type default)
		)
		(layer "In1.Cu")
	)
	(gr_line
		(start 165.4556 -2.775712)
		(end 165.4556 -5.366512)
		(stroke
			(width 0.1016)
			(type default)
		)
		(layer "In1.Cu")
	)
	(gr_line
		(start 165.481 -13.8176)
		(end 165.0746 -13.8176)
		(stroke
			(width 0.1016)
			(type default)
		)
		(layer "In1.Cu")
	)
	(gr_line
		(start 165.481 -13.8176)
		(end 165.481 -11.1506)
		(stroke
			(width 0.1016)
			(type default)
		)
		(layer "In1.Cu")
	)
	(gr_line
		(start 165.481 -11.1506)
		(end 164.2872 -11.1506)
		(stroke
			(width 0.1016)
			(type default)
		)
		(layer "In1.Cu")
	)
	(gr_line
		(start 165.481 -11.1506)
		(end 165.481 -13.8176)
		(stroke
			(width 0.1016)
			(type default)
		)
		(layer "In1.Cu")
	)
	(gr_line
		(start 165.481 -9.617456)
		(end 165.0746 -9.617456)
		(stroke
			(width 0.1016)
			(type default)
		)
		(layer "In1.Cu")
	)
	(gr_line
		(start 165.481 -9.617456)
		(end 165.481 -6.950456)
		(stroke
			(width 0.1016)
			(type default)
		)
		(layer "In1.Cu")
	)
	(gr_line
		(start 165.481 -6.950456)
		(end 164.2872 -6.950456)
		(stroke
			(width 0.1016)
			(type default)
		)
		(layer "In1.Cu")
	)
	(gr_line
		(start 165.481 -6.950456)
		(end 165.481 -9.617456)
		(stroke
			(width 0.1016)
			(type default)
		)
		(layer "In1.Cu")
	)
	(gr_line
		(start 165.481 -5.417312)
		(end 165.0746 -5.417312)
		(stroke
			(width 0.1016)
			(type default)
		)
		(layer "In1.Cu")
	)
	(gr_line
		(start 165.481 -5.417312)
		(end 165.481 -2.750312)
		(stroke
			(width 0.1016)
			(type default)
		)
		(layer "In1.Cu")
	)
	(gr_line
		(start 165.481 -2.750312)
		(end 164.2872 -2.750312)
		(stroke
			(width 0.1016)
			(type default)
		)
		(layer "In1.Cu")
	)
	(gr_line
		(start 165.481 -2.750312)
		(end 165.481 -5.417312)
		(stroke
			(width 0.1016)
			(type default)
		)
		(layer "In1.Cu")
	)
	(gr_line
		(start 166.2176 -24.6634)
		(end 166.2176 -23.3934)
		(stroke
			(width 0.7874)
			(type default)
		)
		(layer "In1.Cu")
	)
	(gr_line
		(start 166.287196 -12.563348)
		(end 167.074596 -12.563348)
		(stroke
			(width 0.1016)
			(type default)
		)
		(layer "In1.Cu")
	)
	(gr_line
		(start 166.287196 -12.512548)
		(end 166.287196 -9.896348)
		(stroke
			(width 0.1016)
			(type default)
		)
		(layer "In1.Cu")
	)
	(gr_line
		(start 166.287196 -12.463272)
		(end 167.074596 -12.463272)
		(stroke
			(width 0.1016)
			(type default)
		)
		(layer "In1.Cu")
	)
	(gr_line
		(start 166.287196 -12.412472)
		(end 166.287196 -9.796272)
		(stroke
			(width 0.1016)
			(type default)
		)
		(layer "In1.Cu")
	)
	(gr_line
		(start 166.287196 -9.896348)
		(end 166.287196 -12.563348)
		(stroke
			(width 0.1016)
			(type default)
		)
		(layer "In1.Cu")
	)
	(gr_line
		(start 166.287196 -9.896348)
		(end 167.480996 -9.896348)
		(stroke
			(width 0.1016)
			(type default)
		)
		(layer "In1.Cu")
	)
	(gr_line
		(start 166.287196 -9.796272)
		(end 166.287196 -12.463272)
		(stroke
			(width 0.1016)
			(type default)
		)
		(layer "In1.Cu")
	)
	(gr_line
		(start 166.287196 -9.796272)
		(end 167.480996 -9.796272)
		(stroke
			(width 0.1016)
			(type default)
		)
		(layer "In1.Cu")
	)
	(gr_line
		(start 166.287196 -8.363204)
		(end 167.074596 -8.363204)
		(stroke
			(width 0.1016)
			(type default)
		)
		(layer "In1.Cu")
	)
	(gr_line
		(start 166.287196 -8.312404)
		(end 166.287196 -5.696204)
		(stroke
			(width 0.1016)
			(type default)
		)
		(layer "In1.Cu")
	)
	(gr_line
		(start 166.287196 -8.263128)
		(end 167.074596 -8.263128)
		(stroke
			(width 0.1016)
			(type default)
		)
		(layer "In1.Cu")
	)
	(gr_line
		(start 166.287196 -8.212328)
		(end 166.287196 -5.596128)
		(stroke
			(width 0.1016)
			(type default)
		)
		(layer "In1.Cu")
	)
	(gr_line
		(start 166.287196 -5.696204)
		(end 166.287196 -8.363204)
		(stroke
			(width 0.1016)
			(type default)
		)
		(layer "In1.Cu")
	)
	(gr_line
		(start 166.287196 -5.696204)
		(end 167.480996 -5.696204)
		(stroke
			(width 0.1016)
			(type default)
		)
		(layer "In1.Cu")
	)
	(gr_line
		(start 166.287196 -5.596128)
		(end 166.287196 -8.263128)
		(stroke
			(width 0.1016)
			(type default)
		)
		(layer "In1.Cu")
	)
	(gr_line
		(start 166.287196 -5.596128)
		(end 167.480996 -5.596128)
		(stroke
			(width 0.1016)
			(type default)
		)
		(layer "In1.Cu")
	)
	(gr_line
		(start 166.287196 -4.16306)
		(end 167.074596 -4.16306)
		(stroke
			(width 0.1016)
			(type default)
		)
		(layer "In1.Cu")
	)
	(gr_line
		(start 166.287196 -4.11226)
		(end 166.287196 -1.49606)
		(stroke
			(width 0.1016)
			(type default)
		)
		(layer "In1.Cu")
	)
	(gr_line
		(start 166.287196 -4.062984)
		(end 167.074596 -4.062984)
		(stroke
			(width 0.1016)
			(type default)
		)
		(layer "In1.Cu")
	)
	(gr_line
		(start 166.287196 -4.012184)
		(end 166.287196 -1.395984)
		(stroke
			(width 0.1016)
			(type default)
		)
		(layer "In1.Cu")
	)
	(gr_line
		(start 166.287196 -1.49606)
		(end 166.287196 -4.16306)
		(stroke
			(width 0.1016)
			(type default)
		)
		(layer "In1.Cu")
	)
	(gr_line
		(start 166.287196 -1.49606)
		(end 167.480996 -1.49606)
		(stroke
			(width 0.1016)
			(type default)
		)
		(layer "In1.Cu")
	)
	(gr_line
		(start 166.287196 -1.395984)
		(end 166.287196 -4.062984)
		(stroke
			(width 0.1016)
			(type default)
		)
		(layer "In1.Cu")
	)
	(gr_line
		(start 166.287196 -1.395984)
		(end 167.480996 -1.395984)
		(stroke
			(width 0.1016)
			(type default)
		)
		(layer "In1.Cu")
	)
	(gr_line
		(start 166.312596 -12.512548)
		(end 166.312596 -9.921748)
		(stroke
			(width 0.1016)
			(type default)
		)
		(layer "In1.Cu")
	)
	(gr_line
		(start 166.312596 -12.412472)
		(end 166.312596 -9.821672)
		(stroke
			(width 0.1016)
			(type default)
		)
		(layer "In1.Cu")
	)
	(gr_line
		(start 166.312596 -9.921748)
		(end 167.455596 -9.921748)
		(stroke
			(width 0.1016)
			(type default)
		)
		(layer "In1.Cu")
	)
	(gr_line
		(start 166.312596 -9.821672)
		(end 167.455596 -9.821672)
		(stroke
			(width 0.1016)
			(type default)
		)
		(layer "In1.Cu")
	)
	(gr_line
		(start 166.312596 -8.312404)
		(end 166.312596 -5.721604)
		(stroke
			(width 0.1016)
			(type default)
		)
		(layer "In1.Cu")
	)
	(gr_line
		(start 166.312596 -8.212328)
		(end 166.312596 -5.621528)
		(stroke
			(width 0.1016)
			(type default)
		)
		(layer "In1.Cu")
	)
	(gr_line
		(start 166.312596 -5.721604)
		(end 167.455596 -5.721604)
		(stroke
			(width 0.1016)
			(type default)
		)
		(layer "In1.Cu")
	)
	(gr_line
		(start 166.312596 -5.621528)
		(end 167.455596 -5.621528)
		(stroke
			(width 0.1016)
			(type default)
		)
		(layer "In1.Cu")
	)
	(gr_line
		(start 166.312596 -4.11226)
		(end 166.312596 -1.52146)
		(stroke
			(width 0.1016)
			(type default)
		)
		(layer "In1.Cu")
	)
	(gr_line
		(start 166.312596 -4.012184)
		(end 166.312596 -1.421384)
		(stroke
			(width 0.1016)
			(type default)
		)
		(layer "In1.Cu")
	)
	(gr_line
		(start 166.312596 -1.52146)
		(end 167.455596 -1.52146)
		(stroke
			(width 0.1016)
			(type default)
		)
		(layer "In1.Cu")
	)
	(gr_line
		(start 166.312596 -1.421384)
		(end 167.455596 -1.421384)
		(stroke
			(width 0.1016)
			(type default)
		)
		(layer "In1.Cu")
	)
	(gr_line
		(start 166.337996 -12.512548)
		(end 166.337996 -9.947148)
		(stroke
			(width 0.1016)
			(type default)
		)
		(layer "In1.Cu")
	)
	(gr_line
		(start 166.337996 -12.412472)
		(end 166.337996 -9.847072)
		(stroke
			(width 0.1016)
			(type default)
		)
		(layer "In1.Cu")
	)
	(gr_line
		(start 166.337996 -9.947148)
		(end 166.591996 -9.947148)
		(stroke
			(width 0.1016)
			(type default)
		)
		(layer "In1.Cu")
	)
	(gr_line
		(start 166.337996 -9.847072)
		(end 166.591996 -9.847072)
		(stroke
			(width 0.1016)
			(type default)
		)
		(layer "In1.Cu")
	)
	(gr_line
		(start 166.337996 -8.312404)
		(end 166.337996 -5.747004)
		(stroke
			(width 0.1016)
			(type default)
		)
		(layer "In1.Cu")
	)
	(gr_line
		(start 166.337996 -8.212328)
		(end 166.337996 -5.646928)
		(stroke
			(width 0.1016)
			(type default)
		)
		(layer "In1.Cu")
	)
	(gr_line
		(start 166.337996 -5.747004)
		(end 166.591996 -5.747004)
		(stroke
			(width 0.1016)
			(type default)
		)
		(layer "In1.Cu")
	)
	(gr_line
		(start 166.337996 -5.646928)
		(end 166.591996 -5.646928)
		(stroke
			(width 0.1016)
			(type default)
		)
		(layer "In1.Cu")
	)
	(gr_line
		(start 166.337996 -4.11226)
		(end 166.337996 -1.54686)
		(stroke
			(width 0.1016)
			(type default)
		)
		(layer "In1.Cu")
	)
	(gr_line
		(start 166.337996 -4.012184)
		(end 166.337996 -1.446784)
		(stroke
			(width 0.1016)
			(type default)
		)
		(layer "In1.Cu")
	)
	(gr_line
		(start 166.337996 -1.54686)
		(end 166.591996 -1.54686)
		(stroke
			(width 0.1016)
			(type default)
		)
		(layer "In1.Cu")
	)
	(gr_line
		(start 166.337996 -1.446784)
		(end 166.591996 -1.446784)
		(stroke
			(width 0.1016)
			(type default)
		)
		(layer "In1.Cu")
	)
	(gr_line
		(start 166.363396 -12.512548)
		(end 166.363396 -9.947148)
		(stroke
			(width 0.2032)
			(type default)
		)
		(layer "In1.Cu")
	)
	(gr_line
		(start 166.363396 -12.412472)
		(end 166.363396 -9.847072)
		(stroke
			(width 0.2032)
			(type default)
		)
		(layer "In1.Cu")
	)
	(gr_line
		(start 166.363396 -9.947148)
		(end 167.379396 -9.947148)
		(stroke
			(width 0.2032)
			(type default)
		)
		(layer "In1.Cu")
	)
	(gr_line
		(start 166.363396 -9.847072)
		(end 167.379396 -9.847072)
		(stroke
			(width 0.2032)
			(type default)
		)
		(layer "In1.Cu")
	)
	(gr_line
		(start 166.363396 -8.312404)
		(end 166.363396 -5.747004)
		(stroke
			(width 0.2032)
			(type default)
		)
		(layer "In1.Cu")
	)
	(gr_line
		(start 166.363396 -8.212328)
		(end 166.363396 -5.646928)
		(stroke
			(width 0.2032)
			(type default)
		)
		(layer "In1.Cu")
	)
	(gr_line
		(start 166.363396 -5.747004)
		(end 167.379396 -5.747004)
		(stroke
			(width 0.2032)
			(type default)
		)
		(layer "In1.Cu")
	)
	(gr_line
		(start 166.363396 -5.646928)
		(end 167.379396 -5.646928)
		(stroke
			(width 0.2032)
			(type default)
		)
		(layer "In1.Cu")
	)
	(gr_line
		(start 166.363396 -4.11226)
		(end 166.363396 -1.54686)
		(stroke
			(width 0.2032)
			(type default)
		)
		(layer "In1.Cu")
	)
	(gr_line
		(start 166.363396 -4.012184)
		(end 166.363396 -1.446784)
		(stroke
			(width 0.2032)
			(type default)
		)
		(layer "In1.Cu")
	)
	(gr_line
		(start 166.363396 -1.54686)
		(end 167.379396 -1.54686)
		(stroke
			(width 0.2032)
			(type default)
		)
		(layer "In1.Cu")
	)
	(gr_line
		(start 166.363396 -1.446784)
		(end 167.379396 -1.446784)
		(stroke
			(width 0.2032)
			(type default)
		)
		(layer "In1.Cu")
	)
	(gr_line
		(start 166.414196 -12.487148)
		(end 166.414196 -9.997948)
		(stroke
			(width 0.2032)
			(type default)
		)
		(layer "In1.Cu")
	)
	(gr_line
		(start 166.414196 -12.487148)
		(end 166.414196 -9.997948)
		(stroke
			(width 0.254)
			(type default)
		)
		(layer "In1.Cu")
	)
	(gr_line
		(start 166.414196 -12.387072)
		(end 166.414196 -9.897872)
		(stroke
			(width 0.2032)
			(type default)
		)
		(layer "In1.Cu")
	)
	(gr_line
		(start 166.414196 -12.387072)
		(end 166.414196 -9.897872)
		(stroke
			(width 0.254)
			(type default)
		)
		(layer "In1.Cu")
	)
	(gr_line
		(start 166.414196 -9.997948)
		(end 166.617396 -9.997948)
		(stroke
			(width 0.2032)
			(type default)
		)
		(layer "In1.Cu")
	)
	(gr_line
		(start 166.414196 -9.997948)
		(end 167.303196 -9.997948)
		(stroke
			(width 0.254)
			(type default)
		)
		(layer "In1.Cu")
	)
	(gr_line
		(start 166.414196 -9.897872)
		(end 166.617396 -9.897872)
		(stroke
			(width 0.2032)
			(type default)
		)
		(layer "In1.Cu")
	)
	(gr_line
		(start 166.414196 -9.897872)
		(end 167.303196 -9.897872)
		(stroke
			(width 0.254)
			(type default)
		)
		(layer "In1.Cu")
	)
	(gr_line
		(start 166.414196 -8.287004)
		(end 166.414196 -5.797804)
		(stroke
			(width 0.2032)
			(type default)
		)
		(layer "In1.Cu")
	)
	(gr_line
		(start 166.414196 -8.287004)
		(end 166.414196 -5.797804)
		(stroke
			(width 0.254)
			(type default)
		)
		(layer "In1.Cu")
	)
	(gr_line
		(start 166.414196 -8.186928)
		(end 166.414196 -5.697728)
		(stroke
			(width 0.2032)
			(type default)
		)
		(layer "In1.Cu")
	)
	(gr_line
		(start 166.414196 -8.186928)
		(end 166.414196 -5.697728)
		(stroke
			(width 0.254)
			(type default)
		)
		(layer "In1.Cu")
	)
	(gr_line
		(start 166.414196 -5.797804)
		(end 166.617396 -5.797804)
		(stroke
			(width 0.2032)
			(type default)
		)
		(layer "In1.Cu")
	)
	(gr_line
		(start 166.414196 -5.797804)
		(end 167.303196 -5.797804)
		(stroke
			(width 0.254)
			(type default)
		)
		(layer "In1.Cu")
	)
	(gr_line
		(start 166.414196 -5.697728)
		(end 166.617396 -5.697728)
		(stroke
			(width 0.2032)
			(type default)
		)
		(layer "In1.Cu")
	)
	(gr_line
		(start 166.414196 -5.697728)
		(end 167.303196 -5.697728)
		(stroke
			(width 0.254)
			(type default)
		)
		(layer "In1.Cu")
	)
	(gr_line
		(start 166.414196 -4.08686)
		(end 166.414196 -1.59766)
		(stroke
			(width 0.2032)
			(type default)
		)
		(layer "In1.Cu")
	)
	(gr_line
		(start 166.414196 -4.08686)
		(end 166.414196 -1.59766)
		(stroke
			(width 0.254)
			(type default)
		)
		(layer "In1.Cu")
	)
	(gr_line
		(start 166.414196 -3.986784)
		(end 166.414196 -1.497584)
		(stroke
			(width 0.2032)
			(type default)
		)
		(layer "In1.Cu")
	)
	(gr_line
		(start 166.414196 -3.986784)
		(end 166.414196 -1.497584)
		(stroke
			(width 0.254)
			(type default)
		)
		(layer "In1.Cu")
	)
	(gr_line
		(start 166.414196 -1.59766)
		(end 166.617396 -1.59766)
		(stroke
			(width 0.2032)
			(type default)
		)
		(layer "In1.Cu")
	)
	(gr_line
		(start 166.414196 -1.59766)
		(end 167.303196 -1.59766)
		(stroke
			(width 0.254)
			(type default)
		)
		(layer "In1.Cu")
	)
	(gr_line
		(start 166.414196 -1.497584)
		(end 166.617396 -1.497584)
		(stroke
			(width 0.2032)
			(type default)
		)
		(layer "In1.Cu")
	)
	(gr_line
		(start 166.414196 -1.497584)
		(end 167.303196 -1.497584)
		(stroke
			(width 0.254)
			(type default)
		)
		(layer "In1.Cu")
	)
	(gr_line
		(start 166.439596 -12.461748)
		(end 166.439596 -10.023348)
		(stroke
			(width 0.254)
			(type default)
		)
		(layer "In1.Cu")
	)
	(gr_line
		(start 166.439596 -12.361672)
		(end 166.439596 -9.923272)
		(stroke
			(width 0.254)
			(type default)
		)
		(layer "In1.Cu")
	)
	(gr_line
		(start 166.439596 -10.023348)
		(end 167.277796 -10.023348)
		(stroke
			(width 0.254)
			(type default)
		)
		(layer "In1.Cu")
	)
	(gr_line
		(start 166.439596 -9.923272)
		(end 167.277796 -9.923272)
		(stroke
			(width 0.254)
			(type default)
		)
		(layer "In1.Cu")
	)
	(gr_line
		(start 166.439596 -8.261604)
		(end 166.439596 -5.823204)
		(stroke
			(width 0.254)
			(type default)
		)
		(layer "In1.Cu")
	)
	(gr_line
		(start 166.439596 -8.161528)
		(end 166.439596 -5.723128)
		(stroke
			(width 0.254)
			(type default)
		)
		(layer "In1.Cu")
	)
	(gr_line
		(start 166.439596 -5.823204)
		(end 167.277796 -5.823204)
		(stroke
			(width 0.254)
			(type default)
		)
		(layer "In1.Cu")
	)
	(gr_line
		(start 166.439596 -5.723128)
		(end 167.277796 -5.723128)
		(stroke
			(width 0.254)
			(type default)
		)
		(layer "In1.Cu")
	)
	(gr_line
		(start 166.439596 -4.06146)
		(end 166.439596 -1.62306)
		(stroke
			(width 0.254)
			(type default)
		)
		(layer "In1.Cu")
	)
	(gr_line
		(start 166.439596 -3.961384)
		(end 166.439596 -1.522984)
		(stroke
			(width 0.254)
			(type default)
		)
		(layer "In1.Cu")
	)
	(gr_line
		(start 166.439596 -1.62306)
		(end 167.277796 -1.62306)
		(stroke
			(width 0.254)
			(type default)
		)
		(layer "In1.Cu")
	)
	(gr_line
		(start 166.439596 -1.522984)
		(end 167.277796 -1.522984)
		(stroke
			(width 0.254)
			(type default)
		)
		(layer "In1.Cu")
	)
	(gr_line
		(start 166.464996 -12.436348)
		(end 166.464996 -10.048748)
		(stroke
			(width 0.254)
			(type default)
		)
		(layer "In1.Cu")
	)
	(gr_line
		(start 166.464996 -12.336272)
		(end 166.464996 -9.948672)
		(stroke
			(width 0.254)
			(type default)
		)
		(layer "In1.Cu")
	)
	(gr_line
		(start 166.464996 -10.048748)
		(end 167.252396 -10.048748)
		(stroke
			(width 0.254)
			(type default)
		)
		(layer "In1.Cu")
	)
	(gr_line
		(start 166.464996 -9.948672)
		(end 167.252396 -9.948672)
		(stroke
			(width 0.254)
			(type default)
		)
		(layer "In1.Cu")
	)
	(gr_line
		(start 166.464996 -8.236204)
		(end 166.464996 -5.848604)
		(stroke
			(width 0.254)
			(type default)
		)
		(layer "In1.Cu")
	)
	(gr_line
		(start 166.464996 -8.136128)
		(end 166.464996 -5.748528)
		(stroke
			(width 0.254)
			(type default)
		)
		(layer "In1.Cu")
	)
	(gr_line
		(start 166.464996 -5.848604)
		(end 167.252396 -5.848604)
		(stroke
			(width 0.254)
			(type default)
		)
		(layer "In1.Cu")
	)
	(gr_line
		(start 166.464996 -5.748528)
		(end 167.252396 -5.748528)
		(stroke
			(width 0.254)
			(type default)
		)
		(layer "In1.Cu")
	)
	(gr_line
		(start 166.464996 -4.03606)
		(end 166.464996 -1.64846)
		(stroke
			(width 0.254)
			(type default)
		)
		(layer "In1.Cu")
	)
	(gr_line
		(start 166.464996 -3.935984)
		(end 166.464996 -1.548384)
		(stroke
			(width 0.254)
			(type default)
		)
		(layer "In1.Cu")
	)
	(gr_line
		(start 166.464996 -1.64846)
		(end 167.252396 -1.64846)
		(stroke
			(width 0.254)
			(type default)
		)
		(layer "In1.Cu")
	)
	(gr_line
		(start 166.464996 -1.548384)
		(end 167.252396 -1.548384)
		(stroke
			(width 0.254)
			(type default)
		)
		(layer "In1.Cu")
	)
	(gr_line
		(start 166.490396 -12.360148)
		(end 167.125396 -12.360148)
		(stroke
			(width 0.508)
			(type default)
		)
		(layer "In1.Cu")
	)
	(gr_line
		(start 166.490396 -12.260072)
		(end 167.125396 -12.260072)
		(stroke
			(width 0.508)
			(type default)
		)
		(layer "In1.Cu")
	)
	(gr_line
		(start 166.490396 -10.175748)
		(end 167.125396 -10.175748)
		(stroke
			(width 0.508)
			(type default)
		)
		(layer "In1.Cu")
	)
	(gr_line
		(start 166.490396 -10.124948)
		(end 167.125396 -10.124948)
		(stroke
			(width 0.508)
			(type default)
		)
		(layer "In1.Cu")
	)
	(gr_line
		(start 166.490396 -10.075672)
		(end 167.125396 -10.075672)
		(stroke
			(width 0.508)
			(type default)
		)
		(layer "In1.Cu")
	)
	(gr_line
		(start 166.490396 -10.024872)
		(end 167.125396 -10.024872)
		(stroke
			(width 0.508)
			(type default)
		)
		(layer "In1.Cu")
	)
	(gr_line
		(start 166.490396 -8.160004)
		(end 167.125396 -8.160004)
		(stroke
			(width 0.508)
			(type default)
		)
		(layer "In1.Cu")
	)
	(gr_line
		(start 166.490396 -8.059928)
		(end 167.125396 -8.059928)
		(stroke
			(width 0.508)
			(type default)
		)
		(layer "In1.Cu")
	)
	(gr_line
		(start 166.490396 -5.975604)
		(end 167.125396 -5.975604)
		(stroke
			(width 0.508)
			(type default)
		)
		(layer "In1.Cu")
	)
	(gr_line
		(start 166.490396 -5.924804)
		(end 167.125396 -5.924804)
		(stroke
			(width 0.508)
			(type default)
		)
		(layer "In1.Cu")
	)
	(gr_line
		(start 166.490396 -5.875528)
		(end 167.125396 -5.875528)
		(stroke
			(width 0.508)
			(type default)
		)
		(layer "In1.Cu")
	)
	(gr_line
		(start 166.490396 -5.824728)
		(end 167.125396 -5.824728)
		(stroke
			(width 0.508)
			(type default)
		)
		(layer "In1.Cu")
	)
	(gr_line
		(start 166.490396 -3.95986)
		(end 167.125396 -3.95986)
		(stroke
			(width 0.508)
			(type default)
		)
		(layer "In1.Cu")
	)
	(gr_line
		(start 166.490396 -3.859784)
		(end 167.125396 -3.859784)
		(stroke
			(width 0.508)
			(type default)
		)
		(layer "In1.Cu")
	)
	(gr_line
		(start 166.490396 -1.77546)
		(end 167.125396 -1.77546)
		(stroke
			(width 0.508)
			(type default)
		)
		(layer "In1.Cu")
	)
	(gr_line
		(start 166.490396 -1.72466)
		(end 167.125396 -1.72466)
		(stroke
			(width 0.508)
			(type default)
		)
		(layer "In1.Cu")
	)
	(gr_line
		(start 166.490396 -1.675384)
		(end 167.125396 -1.675384)
		(stroke
			(width 0.508)
			(type default)
		)
		(layer "In1.Cu")
	)
	(gr_line
		(start 166.490396 -1.624584)
		(end 167.125396 -1.624584)
		(stroke
			(width 0.508)
			(type default)
		)
		(layer "In1.Cu")
	)
	(gr_line
		(start 166.515796 -10.429748)
		(end 167.150796 -10.429748)
		(stroke
			(width 0.508)
			(type default)
		)
		(layer "In1.Cu")
	)
	(gr_line
		(start 166.515796 -10.329672)
		(end 167.150796 -10.329672)
		(stroke
			(width 0.508)
			(type default)
		)
		(layer "In1.Cu")
	)
	(gr_line
		(start 166.515796 -6.229604)
		(end 167.150796 -6.229604)
		(stroke
			(width 0.508)
			(type default)
		)
		(layer "In1.Cu")
	)
	(gr_line
		(start 166.515796 -6.129528)
		(end 167.150796 -6.129528)
		(stroke
			(width 0.508)
			(type default)
		)
		(layer "In1.Cu")
	)
	(gr_line
		(start 166.515796 -2.02946)
		(end 167.150796 -2.02946)
		(stroke
			(width 0.508)
			(type default)
		)
		(layer "In1.Cu")
	)
	(gr_line
		(start 166.515796 -1.929384)
		(end 167.150796 -1.929384)
		(stroke
			(width 0.508)
			(type default)
		)
		(layer "In1.Cu")
	)
	(gr_line
		(start 166.541196 -12.385548)
		(end 166.541196 -10.124948)
		(stroke
			(width 0.254)
			(type default)
		)
		(layer "In1.Cu")
	)
	(gr_line
		(start 166.541196 -12.285472)
		(end 166.541196 -10.024872)
		(stroke
			(width 0.254)
			(type default)
		)
		(layer "In1.Cu")
	)
	(gr_line
		(start 166.541196 -12.233148)
		(end 167.176196 -12.233148)
		(stroke
			(width 0.508)
			(type default)
		)
		(layer "In1.Cu")
	)
	(gr_line
		(start 166.541196 -12.133072)
		(end 167.176196 -12.133072)
		(stroke
			(width 0.508)
			(type default)
		)
		(layer "In1.Cu")
	)
	(gr_line
		(start 166.541196 -10.124948)
		(end 167.176196 -10.124948)
		(stroke
			(width 0.254)
			(type default)
		)
		(layer "In1.Cu")
	)
	(gr_line
		(start 166.541196 -10.024872)
		(end 167.176196 -10.024872)
		(stroke
			(width 0.254)
			(type default)
		)
		(layer "In1.Cu")
	)
	(gr_line
		(start 166.541196 -8.185404)
		(end 166.541196 -5.924804)
		(stroke
			(width 0.254)
			(type default)
		)
		(layer "In1.Cu")
	)
	(gr_line
		(start 166.541196 -8.085328)
		(end 166.541196 -5.824728)
		(stroke
			(width 0.254)
			(type default)
		)
		(layer "In1.Cu")
	)
	(gr_line
		(start 166.541196 -8.033004)
		(end 167.176196 -8.033004)
		(stroke
			(width 0.508)
			(type default)
		)
		(layer "In1.Cu")
	)
	(gr_line
		(start 166.541196 -7.932928)
		(end 167.176196 -7.932928)
		(stroke
			(width 0.508)
			(type default)
		)
		(layer "In1.Cu")
	)
	(gr_line
		(start 166.541196 -5.924804)
		(end 167.176196 -5.924804)
		(stroke
			(width 0.254)
			(type default)
		)
		(layer "In1.Cu")
	)
	(gr_line
		(start 166.541196 -5.824728)
		(end 167.176196 -5.824728)
		(stroke
			(width 0.254)
			(type default)
		)
		(layer "In1.Cu")
	)
	(gr_line
		(start 166.541196 -3.98526)
		(end 166.541196 -1.72466)
		(stroke
			(width 0.254)
			(type default)
		)
		(layer "In1.Cu")
	)
	(gr_line
		(start 166.541196 -3.885184)
		(end 166.541196 -1.624584)
		(stroke
			(width 0.254)
			(type default)
		)
		(layer "In1.Cu")
	)
	(gr_line
		(start 166.541196 -3.83286)
		(end 167.176196 -3.83286)
		(stroke
			(width 0.508)
			(type default)
		)
		(layer "In1.Cu")
	)
	(gr_line
		(start 166.541196 -3.732784)
		(end 167.176196 -3.732784)
		(stroke
			(width 0.508)
			(type default)
		)
		(layer "In1.Cu")
	)
	(gr_line
		(start 166.541196 -1.72466)
		(end 167.176196 -1.72466)
		(stroke
			(width 0.254)
			(type default)
		)
		(layer "In1.Cu")
	)
	(gr_line
		(start 166.541196 -1.624584)
		(end 167.176196 -1.624584)
		(stroke
			(width 0.254)
			(type default)
		)
		(layer "In1.Cu")
	)
	(gr_line
		(start 166.566596 -12.080748)
		(end 167.201596 -12.080748)
		(stroke
			(width 0.508)
			(type default)
		)
		(layer "In1.Cu")
	)
	(gr_line
		(start 166.566596 -11.980672)
		(end 167.201596 -11.980672)
		(stroke
			(width 0.508)
			(type default)
		)
		(layer "In1.Cu")
	)
	(gr_line
		(start 166.566596 -7.880604)
		(end 167.201596 -7.880604)
		(stroke
			(width 0.508)
			(type default)
		)
		(layer "In1.Cu")
	)
	(gr_line
		(start 166.566596 -7.780528)
		(end 167.201596 -7.780528)
		(stroke
			(width 0.508)
			(type default)
		)
		(layer "In1.Cu")
	)
	(gr_line
		(start 166.566596 -3.68046)
		(end 167.201596 -3.68046)
		(stroke
			(width 0.508)
			(type default)
		)
		(layer "In1.Cu")
	)
	(gr_line
		(start 166.566596 -3.580384)
		(end 167.201596 -3.580384)
		(stroke
			(width 0.508)
			(type default)
		)
		(layer "In1.Cu")
	)
	(gr_line
		(start 166.591996 -12.360148)
		(end 167.226996 -12.360148)
		(stroke
			(width 0.508)
			(type default)
		)
		(layer "In1.Cu")
	)
	(gr_line
		(start 166.591996 -12.260072)
		(end 167.226996 -12.260072)
		(stroke
			(width 0.508)
			(type default)
		)
		(layer "In1.Cu")
	)
	(gr_line
		(start 166.591996 -9.947148)
		(end 167.430196 -9.947148)
		(stroke
			(width 0.2032)
			(type default)
		)
		(layer "In1.Cu")
	)
	(gr_line
		(start 166.591996 -9.847072)
		(end 167.430196 -9.847072)
		(stroke
			(width 0.2032)
			(type default)
		)
		(layer "In1.Cu")
	)
	(gr_line
		(start 166.591996 -8.160004)
		(end 167.226996 -8.160004)
		(stroke
			(width 0.508)
			(type default)
		)
		(layer "In1.Cu")
	)
	(gr_line
		(start 166.591996 -8.059928)
		(end 167.226996 -8.059928)
		(stroke
			(width 0.508)
			(type default)
		)
		(layer "In1.Cu")
	)
	(gr_line
		(start 166.591996 -5.747004)
		(end 167.430196 -5.747004)
		(stroke
			(width 0.2032)
			(type default)
		)
		(layer "In1.Cu")
	)
	(gr_line
		(start 166.591996 -5.646928)
		(end 167.430196 -5.646928)
		(stroke
			(width 0.2032)
			(type default)
		)
		(layer "In1.Cu")
	)
	(gr_line
		(start 166.591996 -3.95986)
		(end 167.226996 -3.95986)
		(stroke
			(width 0.508)
			(type default)
		)
		(layer "In1.Cu")
	)
	(gr_line
		(start 166.591996 -3.859784)
		(end 167.226996 -3.859784)
		(stroke
			(width 0.508)
			(type default)
		)
		(layer "In1.Cu")
	)
	(gr_line
		(start 166.591996 -1.54686)
		(end 167.430196 -1.54686)
		(stroke
			(width 0.2032)
			(type default)
		)
		(layer "In1.Cu")
	)
	(gr_line
		(start 166.591996 -1.446784)
		(end 167.430196 -1.446784)
		(stroke
			(width 0.2032)
			(type default)
		)
		(layer "In1.Cu")
	)
	(gr_line
		(start 166.617396 -12.360148)
		(end 166.617396 -10.175748)
		(stroke
			(width 0.254)
			(type default)
		)
		(layer "In1.Cu")
	)
	(gr_line
		(start 166.617396 -12.260072)
		(end 166.617396 -10.075672)
		(stroke
			(width 0.254)
			(type default)
		)
		(layer "In1.Cu")
	)
	(gr_line
		(start 166.617396 -10.175748)
		(end 167.099996 -10.175748)
		(stroke
			(width 0.254)
			(type default)
		)
		(layer "In1.Cu")
	)
	(gr_line
		(start 166.617396 -10.075672)
		(end 167.099996 -10.075672)
		(stroke
			(width 0.254)
			(type default)
		)
		(layer "In1.Cu")
	)
	(gr_line
		(start 166.617396 -9.997948)
		(end 167.353996 -9.997948)
		(stroke
			(width 0.254)
			(type default)
		)
		(layer "In1.Cu")
	)
	(gr_line
		(start 166.617396 -9.897872)
		(end 167.353996 -9.897872)
		(stroke
			(width 0.254)
			(type default)
		)
		(layer "In1.Cu")
	)
	(gr_line
		(start 166.617396 -8.160004)
		(end 166.617396 -5.975604)
		(stroke
			(width 0.254)
			(type default)
		)
		(layer "In1.Cu")
	)
	(gr_line
		(start 166.617396 -8.059928)
		(end 166.617396 -5.875528)
		(stroke
			(width 0.254)
			(type default)
		)
		(layer "In1.Cu")
	)
	(gr_line
		(start 166.617396 -5.975604)
		(end 167.099996 -5.975604)
		(stroke
			(width 0.254)
			(type default)
		)
		(layer "In1.Cu")
	)
	(gr_line
		(start 166.617396 -5.875528)
		(end 167.099996 -5.875528)
		(stroke
			(width 0.254)
			(type default)
		)
		(layer "In1.Cu")
	)
	(gr_line
		(start 166.617396 -5.797804)
		(end 167.353996 -5.797804)
		(stroke
			(width 0.254)
			(type default)
		)
		(layer "In1.Cu")
	)
	(gr_line
		(start 166.617396 -5.697728)
		(end 167.353996 -5.697728)
		(stroke
			(width 0.254)
			(type default)
		)
		(layer "In1.Cu")
	)
	(gr_line
		(start 166.617396 -3.95986)
		(end 166.617396 -1.77546)
		(stroke
			(width 0.254)
			(type default)
		)
		(layer "In1.Cu")
	)
	(gr_line
		(start 166.617396 -3.859784)
		(end 166.617396 -1.675384)
		(stroke
			(width 0.254)
			(type default)
		)
		(layer "In1.Cu")
	)
	(gr_line
		(start 166.617396 -1.77546)
		(end 167.099996 -1.77546)
		(stroke
			(width 0.254)
			(type default)
		)
		(layer "In1.Cu")
	)
	(gr_line
		(start 166.617396 -1.675384)
		(end 167.099996 -1.675384)
		(stroke
			(width 0.254)
			(type default)
		)
		(layer "In1.Cu")
	)
	(gr_line
		(start 166.617396 -1.59766)
		(end 167.353996 -1.59766)
		(stroke
			(width 0.254)
			(type default)
		)
		(layer "In1.Cu")
	)
	(gr_line
		(start 166.617396 -1.497584)
		(end 167.353996 -1.497584)
		(stroke
			(width 0.254)
			(type default)
		)
		(layer "In1.Cu")
	)
	(gr_line
		(start 166.635938 -10.110978)
		(end 167.270938 -10.110978)
		(stroke
			(width 0.508)
			(type default)
		)
		(layer "In1.Cu")
	)
	(gr_line
		(start 166.635938 -10.010902)
		(end 167.270938 -10.010902)
		(stroke
			(width 0.508)
			(type default)
		)
		(layer "In1.Cu")
	)
	(gr_line
		(start 166.635938 -5.910834)
		(end 167.270938 -5.910834)
		(stroke
			(width 0.508)
			(type default)
		)
		(layer "In1.Cu")
	)
	(gr_line
		(start 166.635938 -5.810758)
		(end 167.270938 -5.810758)
		(stroke
			(width 0.508)
			(type default)
		)
		(layer "In1.Cu")
	)
	(gr_line
		(start 166.635938 -1.71069)
		(end 167.270938 -1.71069)
		(stroke
			(width 0.508)
			(type default)
		)
		(layer "In1.Cu")
	)
	(gr_line
		(start 166.635938 -1.610614)
		(end 167.270938 -1.610614)
		(stroke
			(width 0.508)
			(type default)
		)
		(layer "In1.Cu")
	)
	(gr_line
		(start 166.642796 -12.360148)
		(end 167.277796 -12.360148)
		(stroke
			(width 0.508)
			(type default)
		)
		(layer "In1.Cu")
	)
	(gr_line
		(start 166.642796 -12.260072)
		(end 167.277796 -12.260072)
		(stroke
			(width 0.508)
			(type default)
		)
		(layer "In1.Cu")
	)
	(gr_line
		(start 166.642796 -12.233148)
		(end 166.642796 -10.251948)
		(stroke
			(width 0.762)
			(type default)
		)
		(layer "In1.Cu")
	)
	(gr_line
		(start 166.642796 -12.133072)
		(end 166.642796 -10.151872)
		(stroke
			(width 0.762)
			(type default)
		)
		(layer "In1.Cu")
	)
	(gr_line
		(start 166.642796 -10.251948)
		(end 167.277796 -10.251948)
		(stroke
			(width 0.508)
			(type default)
		)
		(layer "In1.Cu")
	)
	(gr_line
		(start 166.642796 -10.151872)
		(end 167.277796 -10.151872)
		(stroke
			(width 0.508)
			(type default)
		)
		(layer "In1.Cu")
	)
	(gr_line
		(start 166.642796 -8.160004)
		(end 167.277796 -8.160004)
		(stroke
			(width 0.508)
			(type default)
		)
		(layer "In1.Cu")
	)
	(gr_line
		(start 166.642796 -8.059928)
		(end 167.277796 -8.059928)
		(stroke
			(width 0.508)
			(type default)
		)
		(layer "In1.Cu")
	)
	(gr_line
		(start 166.642796 -8.033004)
		(end 166.642796 -6.051804)
		(stroke
			(width 0.762)
			(type default)
		)
		(layer "In1.Cu")
	)
	(gr_line
		(start 166.642796 -7.932928)
		(end 166.642796 -5.951728)
		(stroke
			(width 0.762)
			(type default)
		)
		(layer "In1.Cu")
	)
	(gr_line
		(start 166.642796 -6.051804)
		(end 167.277796 -6.051804)
		(stroke
			(width 0.508)
			(type default)
		)
		(layer "In1.Cu")
	)
	(gr_line
		(start 166.642796 -5.951728)
		(end 167.277796 -5.951728)
		(stroke
			(width 0.508)
			(type default)
		)
		(layer "In1.Cu")
	)
	(gr_line
		(start 166.642796 -3.95986)
		(end 167.277796 -3.95986)
		(stroke
			(width 0.508)
			(type default)
		)
		(layer "In1.Cu")
	)
	(gr_line
		(start 166.642796 -3.859784)
		(end 167.277796 -3.859784)
		(stroke
			(width 0.508)
			(type default)
		)
		(layer "In1.Cu")
	)
	(gr_line
		(start 166.642796 -3.83286)
		(end 166.642796 -1.85166)
		(stroke
			(width 0.762)
			(type default)
		)
		(layer "In1.Cu")
	)
	(gr_line
		(start 166.642796 -3.732784)
		(end 166.642796 -1.751584)
		(stroke
			(width 0.762)
			(type default)
		)
		(layer "In1.Cu")
	)
	(gr_line
		(start 166.642796 -1.85166)
		(end 167.277796 -1.85166)
		(stroke
			(width 0.508)
			(type default)
		)
		(layer "In1.Cu")
	)
	(gr_line
		(start 166.642796 -1.751584)
		(end 167.277796 -1.751584)
		(stroke
			(width 0.508)
			(type default)
		)
		(layer "In1.Cu")
	)
	(gr_line
		(start 166.693596 -12.283948)
		(end 166.693596 -10.251948)
		(stroke
			(width 0.254)
			(type default)
		)
		(layer "In1.Cu")
	)
	(gr_line
		(start 166.693596 -12.183872)
		(end 166.693596 -10.151872)
		(stroke
			(width 0.254)
			(type default)
		)
		(layer "In1.Cu")
	)
	(gr_line
		(start 166.693596 -10.251948)
		(end 167.023796 -10.251948)
		(stroke
			(width 0.254)
			(type default)
		)
		(layer "In1.Cu")
	)
	(gr_line
		(start 166.693596 -10.151872)
		(end 167.023796 -10.151872)
		(stroke
			(width 0.254)
			(type default)
		)
		(layer "In1.Cu")
	)
	(gr_line
		(start 166.693596 -8.083804)
		(end 166.693596 -6.051804)
		(stroke
			(width 0.254)
			(type default)
		)
		(layer "In1.Cu")
	)
	(gr_line
		(start 166.693596 -7.983728)
		(end 166.693596 -5.951728)
		(stroke
			(width 0.254)
			(type default)
		)
		(layer "In1.Cu")
	)
	(gr_line
		(start 166.693596 -6.051804)
		(end 167.023796 -6.051804)
		(stroke
			(width 0.254)
			(type default)
		)
		(layer "In1.Cu")
	)
	(gr_line
		(start 166.693596 -5.951728)
		(end 167.023796 -5.951728)
		(stroke
			(width 0.254)
			(type default)
		)
		(layer "In1.Cu")
	)
	(gr_line
		(start 166.693596 -3.88366)
		(end 166.693596 -1.85166)
		(stroke
			(width 0.254)
			(type default)
		)
		(layer "In1.Cu")
	)
	(gr_line
		(start 166.693596 -3.783584)
		(end 166.693596 -1.751584)
		(stroke
			(width 0.254)
			(type default)
		)
		(layer "In1.Cu")
	)
	(gr_line
		(start 166.693596 -1.85166)
		(end 167.023796 -1.85166)
		(stroke
			(width 0.254)
			(type default)
		)
		(layer "In1.Cu")
	)
	(gr_line
		(start 166.693596 -1.751584)
		(end 167.023796 -1.751584)
		(stroke
			(width 0.254)
			(type default)
		)
		(layer "In1.Cu")
	)
	(gr_line
		(start 166.795196 -12.207748)
		(end 166.795196 -10.404348)
		(stroke
			(width 0.254)
			(type default)
		)
		(layer "In1.Cu")
	)
	(gr_line
		(start 166.795196 -12.207748)
		(end 166.795196 -10.226548)
		(stroke
			(width 0.762)
			(type default)
		)
		(layer "In1.Cu")
	)
	(gr_line
		(start 166.795196 -12.107672)
		(end 166.795196 -10.304272)
		(stroke
			(width 0.254)
			(type default)
		)
		(layer "In1.Cu")
	)
	(gr_line
		(start 166.795196 -12.107672)
		(end 166.795196 -10.126472)
		(stroke
			(width 0.762)
			(type default)
		)
		(layer "In1.Cu")
	)
	(gr_line
		(start 166.795196 -10.404348)
		(end 166.896796 -10.404348)
		(stroke
			(width 0.254)
			(type default)
		)
		(layer "In1.Cu")
	)
	(gr_line
		(start 166.795196 -10.304272)
		(end 166.896796 -10.304272)
		(stroke
			(width 0.254)
			(type default)
		)
		(layer "In1.Cu")
	)
	(gr_line
		(start 166.795196 -8.007604)
		(end 166.795196 -6.204204)
		(stroke
			(width 0.254)
			(type default)
		)
		(layer "In1.Cu")
	)
	(gr_line
		(start 166.795196 -8.007604)
		(end 166.795196 -6.026404)
		(stroke
			(width 0.762)
			(type default)
		)
		(layer "In1.Cu")
	)
	(gr_line
		(start 166.795196 -7.907528)
		(end 166.795196 -6.104128)
		(stroke
			(width 0.254)
			(type default)
		)
		(layer "In1.Cu")
	)
	(gr_line
		(start 166.795196 -7.907528)
		(end 166.795196 -5.926328)
		(stroke
			(width 0.762)
			(type default)
		)
		(layer "In1.Cu")
	)
	(gr_line
		(start 166.795196 -6.204204)
		(end 166.896796 -6.204204)
		(stroke
			(width 0.254)
			(type default)
		)
		(layer "In1.Cu")
	)
	(gr_line
		(start 166.795196 -6.104128)
		(end 166.896796 -6.104128)
		(stroke
			(width 0.254)
			(type default)
		)
		(layer "In1.Cu")
	)
	(gr_line
		(start 166.795196 -3.80746)
		(end 166.795196 -2.00406)
		(stroke
			(width 0.254)
			(type default)
		)
		(layer "In1.Cu")
	)
	(gr_line
		(start 166.795196 -3.80746)
		(end 166.795196 -1.82626)
		(stroke
			(width 0.762)
			(type default)
		)
		(layer "In1.Cu")
	)
	(gr_line
		(start 166.795196 -3.707384)
		(end 166.795196 -1.903984)
		(stroke
			(width 0.254)
			(type default)
		)
		(layer "In1.Cu")
	)
	(gr_line
		(start 166.795196 -3.707384)
		(end 166.795196 -1.726184)
		(stroke
			(width 0.762)
			(type default)
		)
		(layer "In1.Cu")
	)
	(gr_line
		(start 166.795196 -2.00406)
		(end 166.896796 -2.00406)
		(stroke
			(width 0.254)
			(type default)
		)
		(layer "In1.Cu")
	)
	(gr_line
		(start 166.795196 -1.903984)
		(end 166.896796 -1.903984)
		(stroke
			(width 0.254)
			(type default)
		)
		(layer "In1.Cu")
	)
	(gr_line
		(start 166.896796 -12.309348)
		(end 166.845996 -12.309348)
		(stroke
			(width 0.254)
			(type default)
		)
		(layer "In1.Cu")
	)
	(gr_line
		(start 166.896796 -12.209272)
		(end 166.845996 -12.209272)
		(stroke
			(width 0.254)
			(type default)
		)
		(layer "In1.Cu")
	)
	(gr_line
		(start 166.896796 -10.404348)
		(end 166.896796 -12.309348)
		(stroke
			(width 0.254)
			(type default)
		)
		(layer "In1.Cu")
	)
	(gr_line
		(start 166.896796 -10.304272)
		(end 166.896796 -12.209272)
		(stroke
			(width 0.254)
			(type default)
		)
		(layer "In1.Cu")
	)
	(gr_line
		(start 166.896796 -8.109204)
		(end 166.845996 -8.109204)
		(stroke
			(width 0.254)
			(type default)
		)
		(layer "In1.Cu")
	)
	(gr_line
		(start 166.896796 -8.009128)
		(end 166.845996 -8.009128)
		(stroke
			(width 0.254)
			(type default)
		)
		(layer "In1.Cu")
	)
	(gr_line
		(start 166.896796 -6.204204)
		(end 166.896796 -8.109204)
		(stroke
			(width 0.254)
			(type default)
		)
		(layer "In1.Cu")
	)
	(gr_line
		(start 166.896796 -6.104128)
		(end 166.896796 -8.009128)
		(stroke
			(width 0.254)
			(type default)
		)
		(layer "In1.Cu")
	)
	(gr_line
		(start 166.896796 -3.90906)
		(end 166.845996 -3.90906)
		(stroke
			(width 0.254)
			(type default)
		)
		(layer "In1.Cu")
	)
	(gr_line
		(start 166.896796 -3.808984)
		(end 166.845996 -3.808984)
		(stroke
			(width 0.254)
			(type default)
		)
		(layer "In1.Cu")
	)
	(gr_line
		(start 166.896796 -2.00406)
		(end 166.896796 -3.90906)
		(stroke
			(width 0.254)
			(type default)
		)
		(layer "In1.Cu")
	)
	(gr_line
		(start 166.896796 -1.903984)
		(end 166.896796 -3.808984)
		(stroke
			(width 0.254)
			(type default)
		)
		(layer "In1.Cu")
	)
	(gr_line
		(start 166.947596 -12.233148)
		(end 166.947596 -10.251948)
		(stroke
			(width 0.762)
			(type default)
		)
		(layer "In1.Cu")
	)
	(gr_line
		(start 166.947596 -12.133072)
		(end 166.947596 -10.151872)
		(stroke
			(width 0.762)
			(type default)
		)
		(layer "In1.Cu")
	)
	(gr_line
		(start 166.947596 -8.033004)
		(end 166.947596 -6.051804)
		(stroke
			(width 0.762)
			(type default)
		)
		(layer "In1.Cu")
	)
	(gr_line
		(start 166.947596 -7.932928)
		(end 166.947596 -5.951728)
		(stroke
			(width 0.762)
			(type default)
		)
		(layer "In1.Cu")
	)
	(gr_line
		(start 166.947596 -3.83286)
		(end 166.947596 -1.85166)
		(stroke
			(width 0.762)
			(type default)
		)
		(layer "In1.Cu")
	)
	(gr_line
		(start 166.947596 -3.732784)
		(end 166.947596 -1.751584)
		(stroke
			(width 0.762)
			(type default)
		)
		(layer "In1.Cu")
	)
	(gr_line
		(start 167.023796 -12.207748)
		(end 166.795196 -12.207748)
		(stroke
			(width 0.254)
			(type default)
		)
		(layer "In1.Cu")
	)
	(gr_line
		(start 167.023796 -12.107672)
		(end 166.795196 -12.107672)
		(stroke
			(width 0.254)
			(type default)
		)
		(layer "In1.Cu")
	)
	(gr_line
		(start 167.023796 -10.251948)
		(end 167.023796 -12.207748)
		(stroke
			(width 0.254)
			(type default)
		)
		(layer "In1.Cu")
	)
	(gr_line
		(start 167.023796 -10.151872)
		(end 167.023796 -12.107672)
		(stroke
			(width 0.254)
			(type default)
		)
		(layer "In1.Cu")
	)
	(gr_line
		(start 167.023796 -8.007604)
		(end 166.795196 -8.007604)
		(stroke
			(width 0.254)
			(type default)
		)
		(layer "In1.Cu")
	)
	(gr_line
		(start 167.023796 -7.907528)
		(end 166.795196 -7.907528)
		(stroke
			(width 0.254)
			(type default)
		)
		(layer "In1.Cu")
	)
	(gr_line
		(start 167.023796 -6.051804)
		(end 167.023796 -8.007604)
		(stroke
			(width 0.254)
			(type default)
		)
		(layer "In1.Cu")
	)
	(gr_line
		(start 167.023796 -5.951728)
		(end 167.023796 -7.907528)
		(stroke
			(width 0.254)
			(type default)
		)
		(layer "In1.Cu")
	)
	(gr_line
		(start 167.023796 -3.80746)
		(end 166.795196 -3.80746)
		(stroke
			(width 0.254)
			(type default)
		)
		(layer "In1.Cu")
	)
	(gr_line
		(start 167.023796 -3.707384)
		(end 166.795196 -3.707384)
		(stroke
			(width 0.254)
			(type default)
		)
		(layer "In1.Cu")
	)
	(gr_line
		(start 167.023796 -1.85166)
		(end 167.023796 -3.80746)
		(stroke
			(width 0.254)
			(type default)
		)
		(layer "In1.Cu")
	)
	(gr_line
		(start 167.023796 -1.751584)
		(end 167.023796 -3.707384)
		(stroke
			(width 0.254)
			(type default)
		)
		(layer "In1.Cu")
	)
	(gr_line
		(start 167.074596 -12.563348)
		(end 167.074596 -12.512548)
		(stroke
			(width 0.1016)
			(type default)
		)
		(layer "In1.Cu")
	)
	(gr_line
		(start 167.074596 -12.563348)
		(end 167.480996 -12.563348)
		(stroke
			(width 0.1016)
			(type default)
		)
		(layer "In1.Cu")
	)
	(gr_line
		(start 167.074596 -12.512548)
		(end 166.312596 -12.512548)
		(stroke
			(width 0.1016)
			(type default)
		)
		(layer "In1.Cu")
	)
	(gr_line
		(start 167.074596 -12.463272)
		(end 167.074596 -12.412472)
		(stroke
			(width 0.1016)
			(type default)
		)
		(layer "In1.Cu")
	)
	(gr_line
		(start 167.074596 -12.463272)
		(end 167.480996 -12.463272)
		(stroke
			(width 0.1016)
			(type default)
		)
		(layer "In1.Cu")
	)
	(gr_line
		(start 167.074596 -12.412472)
		(end 166.312596 -12.412472)
		(stroke
			(width 0.1016)
			(type default)
		)
		(layer "In1.Cu")
	)
	(gr_line
		(start 167.074596 -12.233148)
		(end 167.074596 -10.251948)
		(stroke
			(width 0.762)
			(type default)
		)
		(layer "In1.Cu")
	)
	(gr_line
		(start 167.074596 -12.133072)
		(end 167.074596 -10.151872)
		(stroke
			(width 0.762)
			(type default)
		)
		(layer "In1.Cu")
	)
	(gr_line
		(start 167.074596 -8.363204)
		(end 167.074596 -8.312404)
		(stroke
			(width 0.1016)
			(type default)
		)
		(layer "In1.Cu")
	)
	(gr_line
		(start 167.074596 -8.363204)
		(end 167.480996 -8.363204)
		(stroke
			(width 0.1016)
			(type default)
		)
		(layer "In1.Cu")
	)
	(gr_line
		(start 167.074596 -8.312404)
		(end 166.312596 -8.312404)
		(stroke
			(width 0.1016)
			(type default)
		)
		(layer "In1.Cu")
	)
	(gr_line
		(start 167.074596 -8.263128)
		(end 167.074596 -8.212328)
		(stroke
			(width 0.1016)
			(type default)
		)
		(layer "In1.Cu")
	)
	(gr_line
		(start 167.074596 -8.263128)
		(end 167.480996 -8.263128)
		(stroke
			(width 0.1016)
			(type default)
		)
		(layer "In1.Cu")
	)
	(gr_line
		(start 167.074596 -8.212328)
		(end 166.312596 -8.212328)
		(stroke
			(width 0.1016)
			(type default)
		)
		(layer "In1.Cu")
	)
	(gr_line
		(start 167.074596 -8.033004)
		(end 167.074596 -6.051804)
		(stroke
			(width 0.762)
			(type default)
		)
		(layer "In1.Cu")
	)
	(gr_line
		(start 167.074596 -7.932928)
		(end 167.074596 -5.951728)
		(stroke
			(width 0.762)
			(type default)
		)
		(layer "In1.Cu")
	)
	(gr_line
		(start 167.074596 -4.16306)
		(end 167.074596 -4.11226)
		(stroke
			(width 0.1016)
			(type default)
		)
		(layer "In1.Cu")
	)
	(gr_line
		(start 167.074596 -4.16306)
		(end 167.480996 -4.16306)
		(stroke
			(width 0.1016)
			(type default)
		)
		(layer "In1.Cu")
	)
	(gr_line
		(start 167.074596 -4.11226)
		(end 166.312596 -4.11226)
		(stroke
			(width 0.1016)
			(type default)
		)
		(layer "In1.Cu")
	)
	(gr_line
		(start 167.074596 -4.062984)
		(end 167.074596 -4.012184)
		(stroke
			(width 0.1016)
			(type default)
		)
		(layer "In1.Cu")
	)
	(gr_line
		(start 167.074596 -4.062984)
		(end 167.480996 -4.062984)
		(stroke
			(width 0.1016)
			(type default)
		)
		(layer "In1.Cu")
	)
	(gr_line
		(start 167.074596 -4.012184)
		(end 166.312596 -4.012184)
		(stroke
			(width 0.1016)
			(type default)
		)
		(layer "In1.Cu")
	)
	(gr_line
		(start 167.074596 -3.83286)
		(end 167.074596 -1.85166)
		(stroke
			(width 0.762)
			(type default)
		)
		(layer "In1.Cu")
	)
	(gr_line
		(start 167.074596 -3.732784)
		(end 167.074596 -1.751584)
		(stroke
			(width 0.762)
			(type default)
		)
		(layer "In1.Cu")
	)
	(gr_line
		(start 167.099996 -12.283948)
		(end 166.693596 -12.283948)
		(stroke
			(width 0.254)
			(type default)
		)
		(layer "In1.Cu")
	)
	(gr_line
		(start 167.099996 -12.183872)
		(end 166.693596 -12.183872)
		(stroke
			(width 0.254)
			(type default)
		)
		(layer "In1.Cu")
	)
	(gr_line
		(start 167.099996 -10.175748)
		(end 167.099996 -12.283948)
		(stroke
			(width 0.254)
			(type default)
		)
		(layer "In1.Cu")
	)
	(gr_line
		(start 167.099996 -10.075672)
		(end 167.099996 -12.183872)
		(stroke
			(width 0.254)
			(type default)
		)
		(layer "In1.Cu")
	)
	(gr_line
		(start 167.099996 -8.083804)
		(end 166.693596 -8.083804)
		(stroke
			(width 0.254)
			(type default)
		)
		(layer "In1.Cu")
	)
	(gr_line
		(start 167.099996 -7.983728)
		(end 166.693596 -7.983728)
		(stroke
			(width 0.254)
			(type default)
		)
		(layer "In1.Cu")
	)
	(gr_line
		(start 167.099996 -5.975604)
		(end 167.099996 -8.083804)
		(stroke
			(width 0.254)
			(type default)
		)
		(layer "In1.Cu")
	)
	(gr_line
		(start 167.099996 -5.875528)
		(end 167.099996 -7.983728)
		(stroke
			(width 0.254)
			(type default)
		)
		(layer "In1.Cu")
	)
	(gr_line
		(start 167.099996 -3.88366)
		(end 166.693596 -3.88366)
		(stroke
			(width 0.254)
			(type default)
		)
		(layer "In1.Cu")
	)
	(gr_line
		(start 167.099996 -3.783584)
		(end 166.693596 -3.783584)
		(stroke
			(width 0.254)
			(type default)
		)
		(layer "In1.Cu")
	)
	(gr_line
		(start 167.099996 -1.77546)
		(end 167.099996 -3.88366)
		(stroke
			(width 0.254)
			(type default)
		)
		(layer "In1.Cu")
	)
	(gr_line
		(start 167.099996 -1.675384)
		(end 167.099996 -3.783584)
		(stroke
			(width 0.254)
			(type default)
		)
		(layer "In1.Cu")
	)
	(gr_line
		(start 167.150796 -12.233148)
		(end 167.150796 -10.251948)
		(stroke
			(width 0.762)
			(type default)
		)
		(layer "In1.Cu")
	)
	(gr_line
		(start 167.150796 -12.133072)
		(end 167.150796 -10.151872)
		(stroke
			(width 0.762)
			(type default)
		)
		(layer "In1.Cu")
	)
	(gr_line
		(start 167.150796 -8.033004)
		(end 167.150796 -6.051804)
		(stroke
			(width 0.762)
			(type default)
		)
		(layer "In1.Cu")
	)
	(gr_line
		(start 167.150796 -7.932928)
		(end 167.150796 -5.951728)
		(stroke
			(width 0.762)
			(type default)
		)
		(layer "In1.Cu")
	)
	(gr_line
		(start 167.150796 -3.83286)
		(end 167.150796 -1.85166)
		(stroke
			(width 0.762)
			(type default)
		)
		(layer "In1.Cu")
	)
	(gr_line
		(start 167.150796 -3.732784)
		(end 167.150796 -1.751584)
		(stroke
			(width 0.762)
			(type default)
		)
		(layer "In1.Cu")
	)
	(gr_line
		(start 167.176196 -12.360148)
		(end 166.617396 -12.360148)
		(stroke
			(width 0.254)
			(type default)
		)
		(layer "In1.Cu")
	)
	(gr_line
		(start 167.176196 -12.260072)
		(end 166.617396 -12.260072)
		(stroke
			(width 0.254)
			(type default)
		)
		(layer "In1.Cu")
	)
	(gr_line
		(start 167.176196 -10.124948)
		(end 167.176196 -12.360148)
		(stroke
			(width 0.254)
			(type default)
		)
		(layer "In1.Cu")
	)
	(gr_line
		(start 167.176196 -10.024872)
		(end 167.176196 -12.260072)
		(stroke
			(width 0.254)
			(type default)
		)
		(layer "In1.Cu")
	)
	(gr_line
		(start 167.176196 -8.160004)
		(end 166.617396 -8.160004)
		(stroke
			(width 0.254)
			(type default)
		)
		(layer "In1.Cu")
	)
	(gr_line
		(start 167.176196 -8.059928)
		(end 166.617396 -8.059928)
		(stroke
			(width 0.254)
			(type default)
		)
		(layer "In1.Cu")
	)
	(gr_line
		(start 167.176196 -5.924804)
		(end 167.176196 -8.160004)
		(stroke
			(width 0.254)
			(type default)
		)
		(layer "In1.Cu")
	)
	(gr_line
		(start 167.176196 -5.824728)
		(end 167.176196 -8.059928)
		(stroke
			(width 0.254)
			(type default)
		)
		(layer "In1.Cu")
	)
	(gr_line
		(start 167.176196 -3.95986)
		(end 166.617396 -3.95986)
		(stroke
			(width 0.254)
			(type default)
		)
		(layer "In1.Cu")
	)
	(gr_line
		(start 167.176196 -3.859784)
		(end 166.617396 -3.859784)
		(stroke
			(width 0.254)
			(type default)
		)
		(layer "In1.Cu")
	)
	(gr_line
		(start 167.176196 -1.72466)
		(end 167.176196 -3.95986)
		(stroke
			(width 0.254)
			(type default)
		)
		(layer "In1.Cu")
	)
	(gr_line
		(start 167.176196 -1.624584)
		(end 167.176196 -3.859784)
		(stroke
			(width 0.254)
			(type default)
		)
		(layer "In1.Cu")
	)
	(gr_line
		(start 167.252396 -12.385548)
		(end 166.541196 -12.385548)
		(stroke
			(width 0.254)
			(type default)
		)
		(layer "In1.Cu")
	)
	(gr_line
		(start 167.252396 -12.285472)
		(end 166.541196 -12.285472)
		(stroke
			(width 0.254)
			(type default)
		)
		(layer "In1.Cu")
	)
	(gr_line
		(start 167.252396 -10.048748)
		(end 167.252396 -12.385548)
		(stroke
			(width 0.254)
			(type default)
		)
		(layer "In1.Cu")
	)
	(gr_line
		(start 167.252396 -9.948672)
		(end 167.252396 -12.285472)
		(stroke
			(width 0.254)
			(type default)
		)
		(layer "In1.Cu")
	)
	(gr_line
		(start 167.252396 -8.185404)
		(end 166.541196 -8.185404)
		(stroke
			(width 0.254)
			(type default)
		)
		(layer "In1.Cu")
	)
	(gr_line
		(start 167.252396 -8.085328)
		(end 166.541196 -8.085328)
		(stroke
			(width 0.254)
			(type default)
		)
		(layer "In1.Cu")
	)
	(gr_line
		(start 167.252396 -5.848604)
		(end 167.252396 -8.185404)
		(stroke
			(width 0.254)
			(type default)
		)
		(layer "In1.Cu")
	)
	(gr_line
		(start 167.252396 -5.748528)
		(end 167.252396 -8.085328)
		(stroke
			(width 0.254)
			(type default)
		)
		(layer "In1.Cu")
	)
	(gr_line
		(start 167.252396 -3.98526)
		(end 166.541196 -3.98526)
		(stroke
			(width 0.254)
			(type default)
		)
		(layer "In1.Cu")
	)
	(gr_line
		(start 167.252396 -3.885184)
		(end 166.541196 -3.885184)
		(stroke
			(width 0.254)
			(type default)
		)
		(layer "In1.Cu")
	)
	(gr_line
		(start 167.252396 -1.64846)
		(end 167.252396 -3.98526)
		(stroke
			(width 0.254)
			(type default)
		)
		(layer "In1.Cu")
	)
	(gr_line
		(start 167.252396 -1.548384)
		(end 167.252396 -3.885184)
		(stroke
			(width 0.254)
			(type default)
		)
		(layer "In1.Cu")
	)
	(gr_line
		(start 167.277796 -12.512548)
		(end 166.287196 -12.512548)
		(stroke
			(width 0.1016)
			(type default)
		)
		(layer "In1.Cu")
	)
	(gr_line
		(start 167.277796 -12.436348)
		(end 166.464996 -12.436348)
		(stroke
			(width 0.254)
			(type default)
		)
		(layer "In1.Cu")
	)
	(gr_line
		(start 167.277796 -12.412472)
		(end 166.287196 -12.412472)
		(stroke
			(width 0.1016)
			(type default)
		)
		(layer "In1.Cu")
	)
	(gr_line
		(start 167.277796 -12.336272)
		(end 166.464996 -12.336272)
		(stroke
			(width 0.254)
			(type default)
		)
		(layer "In1.Cu")
	)
	(gr_line
		(start 167.277796 -10.023348)
		(end 167.277796 -12.436348)
		(stroke
			(width 0.254)
			(type default)
		)
		(layer "In1.Cu")
	)
	(gr_line
		(start 167.277796 -9.923272)
		(end 167.277796 -12.336272)
		(stroke
			(width 0.254)
			(type default)
		)
		(layer "In1.Cu")
	)
	(gr_line
		(start 167.277796 -8.312404)
		(end 166.287196 -8.312404)
		(stroke
			(width 0.1016)
			(type default)
		)
		(layer "In1.Cu")
	)
	(gr_line
		(start 167.277796 -8.236204)
		(end 166.464996 -8.236204)
		(stroke
			(width 0.254)
			(type default)
		)
		(layer "In1.Cu")
	)
	(gr_line
		(start 167.277796 -8.212328)
		(end 166.287196 -8.212328)
		(stroke
			(width 0.1016)
			(type default)
		)
		(layer "In1.Cu")
	)
	(gr_line
		(start 167.277796 -8.136128)
		(end 166.464996 -8.136128)
		(stroke
			(width 0.254)
			(type default)
		)
		(layer "In1.Cu")
	)
	(gr_line
		(start 167.277796 -5.823204)
		(end 167.277796 -8.236204)
		(stroke
			(width 0.254)
			(type default)
		)
		(layer "In1.Cu")
	)
	(gr_line
		(start 167.277796 -5.723128)
		(end 167.277796 -8.136128)
		(stroke
			(width 0.254)
			(type default)
		)
		(layer "In1.Cu")
	)
	(gr_line
		(start 167.277796 -4.11226)
		(end 166.287196 -4.11226)
		(stroke
			(width 0.1016)
			(type default)
		)
		(layer "In1.Cu")
	)
	(gr_line
		(start 167.277796 -4.03606)
		(end 166.464996 -4.03606)
		(stroke
			(width 0.254)
			(type default)
		)
		(layer "In1.Cu")
	)
	(gr_line
		(start 167.277796 -4.012184)
		(end 166.287196 -4.012184)
		(stroke
			(width 0.1016)
			(type default)
		)
		(layer "In1.Cu")
	)
	(gr_line
		(start 167.277796 -3.935984)
		(end 166.464996 -3.935984)
		(stroke
			(width 0.254)
			(type default)
		)
		(layer "In1.Cu")
	)
	(gr_line
		(start 167.277796 -1.62306)
		(end 167.277796 -4.03606)
		(stroke
			(width 0.254)
			(type default)
		)
		(layer "In1.Cu")
	)
	(gr_line
		(start 167.277796 -1.522984)
		(end 167.277796 -3.935984)
		(stroke
			(width 0.254)
			(type default)
		)
		(layer "In1.Cu")
	)
	(gr_line
		(start 167.303196 -12.461748)
		(end 166.439596 -12.461748)
		(stroke
			(width 0.254)
			(type default)
		)
		(layer "In1.Cu")
	)
	(gr_line
		(start 167.303196 -12.361672)
		(end 166.439596 -12.361672)
		(stroke
			(width 0.254)
			(type default)
		)
		(layer "In1.Cu")
	)
	(gr_line
		(start 167.303196 -9.997948)
		(end 167.303196 -12.461748)
		(stroke
			(width 0.254)
			(type default)
		)
		(layer "In1.Cu")
	)
	(gr_line
		(start 167.303196 -9.897872)
		(end 167.303196 -12.361672)
		(stroke
			(width 0.254)
			(type default)
		)
		(layer "In1.Cu")
	)
	(gr_line
		(start 167.303196 -8.261604)
		(end 166.439596 -8.261604)
		(stroke
			(width 0.254)
			(type default)
		)
		(layer "In1.Cu")
	)
	(gr_line
		(start 167.303196 -8.161528)
		(end 166.439596 -8.161528)
		(stroke
			(width 0.254)
			(type default)
		)
		(layer "In1.Cu")
	)
	(gr_line
		(start 167.303196 -5.797804)
		(end 167.303196 -8.261604)
		(stroke
			(width 0.254)
			(type default)
		)
		(layer "In1.Cu")
	)
	(gr_line
		(start 167.303196 -5.697728)
		(end 167.303196 -8.161528)
		(stroke
			(width 0.254)
			(type default)
		)
		(layer "In1.Cu")
	)
	(gr_line
		(start 167.303196 -4.06146)
		(end 166.439596 -4.06146)
		(stroke
			(width 0.254)
			(type default)
		)
		(layer "In1.Cu")
	)
	(gr_line
		(start 167.303196 -3.961384)
		(end 166.439596 -3.961384)
		(stroke
			(width 0.254)
			(type default)
		)
		(layer "In1.Cu")
	)
	(gr_line
		(start 167.303196 -1.59766)
		(end 167.303196 -4.06146)
		(stroke
			(width 0.254)
			(type default)
		)
		(layer "In1.Cu")
	)
	(gr_line
		(start 167.303196 -1.497584)
		(end 167.303196 -3.961384)
		(stroke
			(width 0.254)
			(type default)
		)
		(layer "In1.Cu")
	)
	(gr_line
		(start 167.353996 -12.487148)
		(end 166.414196 -12.487148)
		(stroke
			(width 0.254)
			(type default)
		)
		(layer "In1.Cu")
	)
	(gr_line
		(start 167.353996 -12.387072)
		(end 166.414196 -12.387072)
		(stroke
			(width 0.254)
			(type default)
		)
		(layer "In1.Cu")
	)
	(gr_line
		(start 167.353996 -9.997948)
		(end 167.353996 -12.487148)
		(stroke
			(width 0.254)
			(type default)
		)
		(layer "In1.Cu")
	)
	(gr_line
		(start 167.353996 -9.897872)
		(end 167.353996 -12.387072)
		(stroke
			(width 0.254)
			(type default)
		)
		(layer "In1.Cu")
	)
	(gr_line
		(start 167.353996 -8.287004)
		(end 166.414196 -8.287004)
		(stroke
			(width 0.254)
			(type default)
		)
		(layer "In1.Cu")
	)
	(gr_line
		(start 167.353996 -8.186928)
		(end 166.414196 -8.186928)
		(stroke
			(width 0.254)
			(type default)
		)
		(layer "In1.Cu")
	)
	(gr_line
		(start 167.353996 -5.797804)
		(end 167.353996 -8.287004)
		(stroke
			(width 0.254)
			(type default)
		)
		(layer "In1.Cu")
	)
	(gr_line
		(start 167.353996 -5.697728)
		(end 167.353996 -8.186928)
		(stroke
			(width 0.254)
			(type default)
		)
		(layer "In1.Cu")
	)
	(gr_line
		(start 167.353996 -4.08686)
		(end 166.414196 -4.08686)
		(stroke
			(width 0.254)
			(type default)
		)
		(layer "In1.Cu")
	)
	(gr_line
		(start 167.353996 -3.986784)
		(end 166.414196 -3.986784)
		(stroke
			(width 0.254)
			(type default)
		)
		(layer "In1.Cu")
	)
	(gr_line
		(start 167.353996 -1.59766)
		(end 167.353996 -4.08686)
		(stroke
			(width 0.254)
			(type default)
		)
		(layer "In1.Cu")
	)
	(gr_line
		(start 167.353996 -1.497584)
		(end 167.353996 -3.986784)
		(stroke
			(width 0.254)
			(type default)
		)
		(layer "In1.Cu")
	)
	(gr_line
		(start 167.379396 -12.487148)
		(end 166.414196 -12.487148)
		(stroke
			(width 0.2032)
			(type default)
		)
		(layer "In1.Cu")
	)
	(gr_line
		(start 167.379396 -12.387072)
		(end 166.414196 -12.387072)
		(stroke
			(width 0.2032)
			(type default)
		)
		(layer "In1.Cu")
	)
	(gr_line
		(start 167.379396 -9.947148)
		(end 167.379396 -12.487148)
		(stroke
			(width 0.2032)
			(type default)
		)
		(layer "In1.Cu")
	)
	(gr_line
		(start 167.379396 -9.847072)
		(end 167.379396 -12.387072)
		(stroke
			(width 0.2032)
			(type default)
		)
		(layer "In1.Cu")
	)
	(gr_line
		(start 167.379396 -8.287004)
		(end 166.414196 -8.287004)
		(stroke
			(width 0.2032)
			(type default)
		)
		(layer "In1.Cu")
	)
	(gr_line
		(start 167.379396 -8.186928)
		(end 166.414196 -8.186928)
		(stroke
			(width 0.2032)
			(type default)
		)
		(layer "In1.Cu")
	)
	(gr_line
		(start 167.379396 -5.747004)
		(end 167.379396 -8.287004)
		(stroke
			(width 0.2032)
			(type default)
		)
		(layer "In1.Cu")
	)
	(gr_line
		(start 167.379396 -5.646928)
		(end 167.379396 -8.186928)
		(stroke
			(width 0.2032)
			(type default)
		)
		(layer "In1.Cu")
	)
	(gr_line
		(start 167.379396 -4.08686)
		(end 166.414196 -4.08686)
		(stroke
			(width 0.2032)
			(type default)
		)
		(layer "In1.Cu")
	)
	(gr_line
		(start 167.379396 -3.986784)
		(end 166.414196 -3.986784)
		(stroke
			(width 0.2032)
			(type default)
		)
		(layer "In1.Cu")
	)
	(gr_line
		(start 167.379396 -1.54686)
		(end 167.379396 -4.08686)
		(stroke
			(width 0.2032)
			(type default)
		)
		(layer "In1.Cu")
	)
	(gr_line
		(start 167.379396 -1.446784)
		(end 167.379396 -3.986784)
		(stroke
			(width 0.2032)
			(type default)
		)
		(layer "In1.Cu")
	)
	(gr_line
		(start 167.430196 -12.512548)
		(end 166.363396 -12.512548)
		(stroke
			(width 0.2032)
			(type default)
		)
		(layer "In1.Cu")
	)
	(gr_line
		(start 167.430196 -12.412472)
		(end 166.363396 -12.412472)
		(stroke
			(width 0.2032)
			(type default)
		)
		(layer "In1.Cu")
	)
	(gr_line
		(start 167.430196 -9.947148)
		(end 167.430196 -12.512548)
		(stroke
			(width 0.2032)
			(type default)
		)
		(layer "In1.Cu")
	)
	(gr_line
		(start 167.430196 -9.847072)
		(end 167.430196 -12.412472)
		(stroke
			(width 0.2032)
			(type default)
		)
		(layer "In1.Cu")
	)
	(gr_line
		(start 167.430196 -8.312404)
		(end 166.363396 -8.312404)
		(stroke
			(width 0.2032)
			(type default)
		)
		(layer "In1.Cu")
	)
	(gr_line
		(start 167.430196 -8.212328)
		(end 166.363396 -8.212328)
		(stroke
			(width 0.2032)
			(type default)
		)
		(layer "In1.Cu")
	)
	(gr_line
		(start 167.430196 -5.747004)
		(end 167.430196 -8.312404)
		(stroke
			(width 0.2032)
			(type default)
		)
		(layer "In1.Cu")
	)
	(gr_line
		(start 167.430196 -5.646928)
		(end 167.430196 -8.212328)
		(stroke
			(width 0.2032)
			(type default)
		)
		(layer "In1.Cu")
	)
	(gr_line
		(start 167.430196 -4.11226)
		(end 166.363396 -4.11226)
		(stroke
			(width 0.2032)
			(type default)
		)
		(layer "In1.Cu")
	)
	(gr_line
		(start 167.430196 -4.012184)
		(end 166.363396 -4.012184)
		(stroke
			(width 0.2032)
			(type default)
		)
		(layer "In1.Cu")
	)
	(gr_line
		(start 167.430196 -1.54686)
		(end 167.430196 -4.11226)
		(stroke
			(width 0.2032)
			(type default)
		)
		(layer "In1.Cu")
	)
	(gr_line
		(start 167.430196 -1.446784)
		(end 167.430196 -4.012184)
		(stroke
			(width 0.2032)
			(type default)
		)
		(layer "In1.Cu")
	)
	(gr_line
		(start 167.455596 -12.512548)
		(end 166.337996 -12.512548)
		(stroke
			(width 0.1016)
			(type default)
		)
		(layer "In1.Cu")
	)
	(gr_line
		(start 167.455596 -12.412472)
		(end 166.337996 -12.412472)
		(stroke
			(width 0.1016)
			(type default)
		)
		(layer "In1.Cu")
	)
	(gr_line
		(start 167.455596 -9.921748)
		(end 167.455596 -12.512548)
		(stroke
			(width 0.1016)
			(type default)
		)
		(layer "In1.Cu")
	)
	(gr_line
		(start 167.455596 -9.821672)
		(end 167.455596 -12.412472)
		(stroke
			(width 0.1016)
			(type default)
		)
		(layer "In1.Cu")
	)
	(gr_line
		(start 167.455596 -8.312404)
		(end 166.337996 -8.312404)
		(stroke
			(width 0.1016)
			(type default)
		)
		(layer "In1.Cu")
	)
	(gr_line
		(start 167.455596 -8.212328)
		(end 166.337996 -8.212328)
		(stroke
			(width 0.1016)
			(type default)
		)
		(layer "In1.Cu")
	)
	(gr_line
		(start 167.455596 -5.721604)
		(end 167.455596 -8.312404)
		(stroke
			(width 0.1016)
			(type default)
		)
		(layer "In1.Cu")
	)
	(gr_line
		(start 167.455596 -5.621528)
		(end 167.455596 -8.212328)
		(stroke
			(width 0.1016)
			(type default)
		)
		(layer "In1.Cu")
	)
	(gr_line
		(start 167.455596 -4.11226)
		(end 166.337996 -4.11226)
		(stroke
			(width 0.1016)
			(type default)
		)
		(layer "In1.Cu")
	)
	(gr_line
		(start 167.455596 -4.012184)
		(end 166.337996 -4.012184)
		(stroke
			(width 0.1016)
			(type default)
		)
		(layer "In1.Cu")
	)
	(gr_line
		(start 167.455596 -1.52146)
		(end 167.455596 -4.11226)
		(stroke
			(width 0.1016)
			(type default)
		)
		(layer "In1.Cu")
	)
	(gr_line
		(start 167.455596 -1.421384)
		(end 167.455596 -4.012184)
		(stroke
			(width 0.1016)
			(type default)
		)
		(layer "In1.Cu")
	)
	(gr_line
		(start 167.480996 -12.563348)
		(end 167.074596 -12.563348)
		(stroke
			(width 0.1016)
			(type default)
		)
		(layer "In1.Cu")
	)
	(gr_line
		(start 167.480996 -12.563348)
		(end 167.480996 -9.896348)
		(stroke
			(width 0.1016)
			(type default)
		)
		(layer "In1.Cu")
	)
	(gr_line
		(start 167.480996 -12.463272)
		(end 167.074596 -12.463272)
		(stroke
			(width 0.1016)
			(type default)
		)
		(layer "In1.Cu")
	)
	(gr_line
		(start 167.480996 -12.463272)
		(end 167.480996 -9.796272)
		(stroke
			(width 0.1016)
			(type default)
		)
		(layer "In1.Cu")
	)
	(gr_line
		(start 167.480996 -9.896348)
		(end 166.287196 -9.896348)
		(stroke
			(width 0.1016)
			(type default)
		)
		(layer "In1.Cu")
	)
	(gr_line
		(start 167.480996 -9.896348)
		(end 167.480996 -12.563348)
		(stroke
			(width 0.1016)
			(type default)
		)
		(layer "In1.Cu")
	)
	(gr_line
		(start 167.480996 -9.796272)
		(end 166.287196 -9.796272)
		(stroke
			(width 0.1016)
			(type default)
		)
		(layer "In1.Cu")
	)
	(gr_line
		(start 167.480996 -9.796272)
		(end 167.480996 -12.463272)
		(stroke
			(width 0.1016)
			(type default)
		)
		(layer "In1.Cu")
	)
	(gr_line
		(start 167.480996 -8.363204)
		(end 167.074596 -8.363204)
		(stroke
			(width 0.1016)
			(type default)
		)
		(layer "In1.Cu")
	)
	(gr_line
		(start 167.480996 -8.363204)
		(end 167.480996 -5.696204)
		(stroke
			(width 0.1016)
			(type default)
		)
		(layer "In1.Cu")
	)
	(gr_line
		(start 167.480996 -8.263128)
		(end 167.074596 -8.263128)
		(stroke
			(width 0.1016)
			(type default)
		)
		(layer "In1.Cu")
	)
	(gr_line
		(start 167.480996 -8.263128)
		(end 167.480996 -5.596128)
		(stroke
			(width 0.1016)
			(type default)
		)
		(layer "In1.Cu")
	)
	(gr_line
		(start 167.480996 -5.696204)
		(end 166.287196 -5.696204)
		(stroke
			(width 0.1016)
			(type default)
		)
		(layer "In1.Cu")
	)
	(gr_line
		(start 167.480996 -5.696204)
		(end 167.480996 -8.363204)
		(stroke
			(width 0.1016)
			(type default)
		)
		(layer "In1.Cu")
	)
	(gr_line
		(start 167.480996 -5.596128)
		(end 166.287196 -5.596128)
		(stroke
			(width 0.1016)
			(type default)
		)
		(layer "In1.Cu")
	)
	(gr_line
		(start 167.480996 -5.596128)
		(end 167.480996 -8.263128)
		(stroke
			(width 0.1016)
			(type default)
		)
		(layer "In1.Cu")
	)
	(gr_line
		(start 167.480996 -4.16306)
		(end 167.074596 -4.16306)
		(stroke
			(width 0.1016)
			(type default)
		)
		(layer "In1.Cu")
	)
	(gr_line
		(start 167.480996 -4.16306)
		(end 167.480996 -1.49606)
		(stroke
			(width 0.1016)
			(type default)
		)
		(layer "In1.Cu")
	)
	(gr_line
		(start 167.480996 -4.062984)
		(end 167.074596 -4.062984)
		(stroke
			(width 0.1016)
			(type default)
		)
		(layer "In1.Cu")
	)
	(gr_line
		(start 167.480996 -4.062984)
		(end 167.480996 -1.395984)
		(stroke
			(width 0.1016)
			(type default)
		)
		(layer "In1.Cu")
	)
	(gr_line
		(start 167.480996 -1.49606)
		(end 166.287196 -1.49606)
		(stroke
			(width 0.1016)
			(type default)
		)
		(layer "In1.Cu")
	)
	(gr_line
		(start 167.480996 -1.49606)
		(end 167.480996 -4.16306)
		(stroke
			(width 0.1016)
			(type default)
		)
		(layer "In1.Cu")
	)
	(gr_line
		(start 167.480996 -1.395984)
		(end 166.287196 -1.395984)
		(stroke
			(width 0.1016)
			(type default)
		)
		(layer "In1.Cu")
	)
	(gr_line
		(start 167.480996 -1.395984)
		(end 167.480996 -4.062984)
		(stroke
			(width 0.1016)
			(type default)
		)
		(layer "In1.Cu")
	)
	(gr_line
		(start 168.0972 -29.337)
		(end 168.9354 -29.337)
		(stroke
			(width 0.1016)
			(type default)
		)
		(layer "In1.Cu")
	)
	(gr_line
		(start 168.0972 -27.4828)
		(end 168.0972 -29.337)
		(stroke
			(width 0.1016)
			(type default)
		)
		(layer "In1.Cu")
	)
	(gr_line
		(start 168.148 -29.2354)
		(end 168.148 -27.559)
		(stroke
			(width 0.2032)
			(type default)
		)
		(layer "In1.Cu")
	)
	(gr_line
		(start 168.148 -27.559)
		(end 169.2148 -27.559)
		(stroke
			(width 0.2032)
			(type default)
		)
		(layer "In1.Cu")
	)
	(gr_line
		(start 168.1734 -29.2608)
		(end 169.164 -29.2608)
		(stroke
			(width 0.2032)
			(type default)
		)
		(layer "In1.Cu")
	)
	(gr_line
		(start 168.1734 -29.2354)
		(end 168.1734 -29.2608)
		(stroke
			(width 0.2032)
			(type default)
		)
		(layer "In1.Cu")
	)
	(gr_line
		(start 168.2242 -29.1846)
		(end 169.164 -29.1846)
		(stroke
			(width 0.2032)
			(type default)
		)
		(layer "In1.Cu")
	)
	(gr_line
		(start 168.2242 -27.6098)
		(end 168.2242 -29.1846)
		(stroke
			(width 0.2032)
			(type default)
		)
		(layer "In1.Cu")
	)
	(gr_line
		(start 168.287192 -13.8176)
		(end 169.074592 -13.8176)
		(stroke
			(width 0.1016)
			(type default)
		)
		(layer "In1.Cu")
	)
	(gr_line
		(start 168.287192 -13.7668)
		(end 168.287192 -11.1506)
		(stroke
			(width 0.1016)
			(type default)
		)
		(layer "In1.Cu")
	)
	(gr_line
		(start 168.287192 -11.1506)
		(end 168.287192 -13.8176)
		(stroke
			(width 0.1016)
			(type default)
		)
		(layer "In1.Cu")
	)
	(gr_line
		(start 168.287192 -11.1506)
		(end 169.480992 -11.1506)
		(stroke
			(width 0.1016)
			(type default)
		)
		(layer "In1.Cu")
	)
	(gr_line
		(start 168.287192 -9.617456)
		(end 169.074592 -9.617456)
		(stroke
			(width 0.1016)
			(type default)
		)
		(layer "In1.Cu")
	)
	(gr_line
		(start 168.287192 -9.566656)
		(end 168.287192 -6.950456)
		(stroke
			(width 0.1016)
			(type default)
		)
		(layer "In1.Cu")
	)
	(gr_line
		(start 168.287192 -6.950456)
		(end 168.287192 -9.617456)
		(stroke
			(width 0.1016)
			(type default)
		)
		(layer "In1.Cu")
	)
	(gr_line
		(start 168.287192 -6.950456)
		(end 169.480992 -6.950456)
		(stroke
			(width 0.1016)
			(type default)
		)
		(layer "In1.Cu")
	)
	(gr_line
		(start 168.3004 -29.1084)
		(end 168.3004 -27.7622)
		(stroke
			(width 0.508)
			(type default)
		)
		(layer "In1.Cu")
	)
	(gr_line
		(start 168.312592 -13.7668)
		(end 168.312592 -11.176)
		(stroke
			(width 0.1016)
			(type default)
		)
		(layer "In1.Cu")
	)
	(gr_line
		(start 168.312592 -11.176)
		(end 169.455592 -11.176)
		(stroke
			(width 0.1016)
			(type default)
		)
		(layer "In1.Cu")
	)
	(gr_line
		(start 168.312592 -9.566656)
		(end 168.312592 -6.975856)
		(stroke
			(width 0.1016)
			(type default)
		)
		(layer "In1.Cu")
	)
	(gr_line
		(start 168.312592 -6.975856)
		(end 169.455592 -6.975856)
		(stroke
			(width 0.1016)
			(type default)
		)
		(layer "In1.Cu")
	)
	(gr_line
		(start 168.3258 -29.1084)
		(end 168.9862 -29.1084)
		(stroke
			(width 0.508)
			(type default)
		)
		(layer "In1.Cu")
	)
	(gr_line
		(start 168.3258 -29.083)
		(end 168.3258 -27.7368)
		(stroke
			(width 0.508)
			(type default)
		)
		(layer "In1.Cu")
	)
	(gr_line
		(start 168.3258 -27.7114)
		(end 168.9608 -27.7114)
		(stroke
			(width 0.508)
			(type default)
		)
		(layer "In1.Cu")
	)
	(gr_line
		(start 168.337992 -13.7668)
		(end 168.337992 -11.2014)
		(stroke
			(width 0.1016)
			(type default)
		)
		(layer "In1.Cu")
	)
	(gr_line
		(start 168.337992 -11.2014)
		(end 168.591992 -11.2014)
		(stroke
			(width 0.1016)
			(type default)
		)
		(layer "In1.Cu")
	)
	(gr_line
		(start 168.337992 -9.566656)
		(end 168.337992 -7.001256)
		(stroke
			(width 0.1016)
			(type default)
		)
		(layer "In1.Cu")
	)
	(gr_line
		(start 168.337992 -7.001256)
		(end 168.591992 -7.001256)
		(stroke
			(width 0.1016)
			(type default)
		)
		(layer "In1.Cu")
	)
	(gr_line
		(start 168.3512 -29.083)
		(end 168.3512 -27.7368)
		(stroke
			(width 0.508)
			(type default)
		)
		(layer "In1.Cu")
	)
	(gr_line
		(start 168.363392 -13.7668)
		(end 168.363392 -11.2014)
		(stroke
			(width 0.2032)
			(type default)
		)
		(layer "In1.Cu")
	)
	(gr_line
		(start 168.363392 -11.2014)
		(end 169.379392 -11.2014)
		(stroke
			(width 0.2032)
			(type default)
		)
		(layer "In1.Cu")
	)
	(gr_line
		(start 168.363392 -9.566656)
		(end 168.363392 -7.001256)
		(stroke
			(width 0.2032)
			(type default)
		)
		(layer "In1.Cu")
	)
	(gr_line
		(start 168.363392 -7.001256)
		(end 169.379392 -7.001256)
		(stroke
			(width 0.2032)
			(type default)
		)
		(layer "In1.Cu")
	)
	(gr_line
		(start 168.3766 -29.083)
		(end 168.3766 -27.7368)
		(stroke
			(width 0.508)
			(type default)
		)
		(layer "In1.Cu")
	)
	(gr_line
		(start 168.414192 -13.7414)
		(end 168.414192 -11.2522)
		(stroke
			(width 0.2032)
			(type default)
		)
		(layer "In1.Cu")
	)
	(gr_line
		(start 168.414192 -13.7414)
		(end 168.414192 -11.2522)
		(stroke
			(width 0.254)
			(type default)
		)
		(layer "In1.Cu")
	)
	(gr_line
		(start 168.414192 -11.2522)
		(end 168.617392 -11.2522)
		(stroke
			(width 0.2032)
			(type default)
		)
		(layer "In1.Cu")
	)
	(gr_line
		(start 168.414192 -11.2522)
		(end 169.303192 -11.2522)
		(stroke
			(width 0.254)
			(type default)
		)
		(layer "In1.Cu")
	)
	(gr_line
		(start 168.414192 -9.541256)
		(end 168.414192 -7.052056)
		(stroke
			(width 0.2032)
			(type default)
		)
		(layer "In1.Cu")
	)
	(gr_line
		(start 168.414192 -9.541256)
		(end 168.414192 -7.052056)
		(stroke
			(width 0.254)
			(type default)
		)
		(layer "In1.Cu")
	)
	(gr_line
		(start 168.414192 -7.052056)
		(end 168.617392 -7.052056)
		(stroke
			(width 0.2032)
			(type default)
		)
		(layer "In1.Cu")
	)
	(gr_line
		(start 168.414192 -7.052056)
		(end 169.303192 -7.052056)
		(stroke
			(width 0.254)
			(type default)
		)
		(layer "In1.Cu")
	)
	(gr_line
		(start 168.4274 -29.1084)
		(end 168.4274 -27.7622)
		(stroke
			(width 0.508)
			(type default)
		)
		(layer "In1.Cu")
	)
	(gr_line
		(start 168.4274 -29.083)
		(end 168.4274 -27.7368)
		(stroke
			(width 0.508)
			(type default)
		)
		(layer "In1.Cu")
	)
	(gr_line
		(start 168.439592 -13.716)
		(end 168.439592 -11.2776)
		(stroke
			(width 0.254)
			(type default)
		)
		(layer "In1.Cu")
	)
	(gr_line
		(start 168.439592 -11.2776)
		(end 169.277792 -11.2776)
		(stroke
			(width 0.254)
			(type default)
		)
		(layer "In1.Cu")
	)
	(gr_line
		(start 168.439592 -9.515856)
		(end 168.439592 -7.077456)
		(stroke
			(width 0.254)
			(type default)
		)
		(layer "In1.Cu")
	)
	(gr_line
		(start 168.439592 -7.077456)
		(end 169.277792 -7.077456)
		(stroke
			(width 0.254)
			(type default)
		)
		(layer "In1.Cu")
	)
	(gr_line
		(start 168.464992 -13.6906)
		(end 168.464992 -11.303)
		(stroke
			(width 0.254)
			(type default)
		)
		(layer "In1.Cu")
	)
	(gr_line
		(start 168.464992 -11.303)
		(end 169.252392 -11.303)
		(stroke
			(width 0.254)
			(type default)
		)
		(layer "In1.Cu")
	)
	(gr_line
		(start 168.464992 -9.490456)
		(end 168.464992 -7.102856)
		(stroke
			(width 0.254)
			(type default)
		)
		(layer "In1.Cu")
	)
	(gr_line
		(start 168.464992 -7.102856)
		(end 169.252392 -7.102856)
		(stroke
			(width 0.254)
			(type default)
		)
		(layer "In1.Cu")
	)
	(gr_line
		(start 168.4782 -29.083)
		(end 168.4782 -27.7368)
		(stroke
			(width 0.508)
			(type default)
		)
		(layer "In1.Cu")
	)
	(gr_line
		(start 168.490392 -13.6144)
		(end 169.125392 -13.6144)
		(stroke
			(width 0.508)
			(type default)
		)
		(layer "In1.Cu")
	)
	(gr_line
		(start 168.490392 -11.43)
		(end 169.125392 -11.43)
		(stroke
			(width 0.508)
			(type default)
		)
		(layer "In1.Cu")
	)
	(gr_line
		(start 168.490392 -11.3792)
		(end 169.125392 -11.3792)
		(stroke
			(width 0.508)
			(type default)
		)
		(layer "In1.Cu")
	)
	(gr_line
		(start 168.490392 -9.414256)
		(end 169.125392 -9.414256)
		(stroke
			(width 0.508)
			(type default)
		)
		(layer "In1.Cu")
	)
	(gr_line
		(start 168.490392 -7.229856)
		(end 169.125392 -7.229856)
		(stroke
			(width 0.508)
			(type default)
		)
		(layer "In1.Cu")
	)
	(gr_line
		(start 168.490392 -7.179056)
		(end 169.125392 -7.179056)
		(stroke
			(width 0.508)
			(type default)
		)
		(layer "In1.Cu")
	)
	(gr_line
		(start 168.49725 -26.826972)
		(end 169.33545 -26.826972)
		(stroke
			(width 0.1016)
			(type default)
		)
		(layer "In1.Cu")
	)
	(gr_line
		(start 168.49725 -24.972772)
		(end 168.49725 -26.826972)
		(stroke
			(width 0.1016)
			(type default)
		)
		(layer "In1.Cu")
	)
	(gr_line
		(start 168.5036 -29.0576)
		(end 168.5036 -27.7114)
		(stroke
			(width 0.508)
			(type default)
		)
		(layer "In1.Cu")
	)
	(gr_line
		(start 168.515792 -11.684)
		(end 169.150792 -11.684)
		(stroke
			(width 0.508)
			(type default)
		)
		(layer "In1.Cu")
	)
	(gr_line
		(start 168.515792 -7.483856)
		(end 169.150792 -7.483856)
		(stroke
			(width 0.508)
			(type default)
		)
		(layer "In1.Cu")
	)
	(gr_line
		(start 168.529 -29.083)
		(end 168.529 -27.7368)
		(stroke
			(width 0.508)
			(type default)
		)
		(layer "In1.Cu")
	)
	(gr_line
		(start 168.541192 -13.6398)
		(end 168.541192 -11.3792)
		(stroke
			(width 0.254)
			(type default)
		)
		(layer "In1.Cu")
	)
	(gr_line
		(start 168.541192 -13.4874)
		(end 169.176192 -13.4874)
		(stroke
			(width 0.508)
			(type default)
		)
		(layer "In1.Cu")
	)
	(gr_line
		(start 168.541192 -11.3792)
		(end 169.176192 -11.3792)
		(stroke
			(width 0.254)
			(type default)
		)
		(layer "In1.Cu")
	)
	(gr_line
		(start 168.541192 -9.439656)
		(end 168.541192 -7.179056)
		(stroke
			(width 0.254)
			(type default)
		)
		(layer "In1.Cu")
	)
	(gr_line
		(start 168.541192 -9.287256)
		(end 169.176192 -9.287256)
		(stroke
			(width 0.508)
			(type default)
		)
		(layer "In1.Cu")
	)
	(gr_line
		(start 168.541192 -7.179056)
		(end 169.176192 -7.179056)
		(stroke
			(width 0.254)
			(type default)
		)
		(layer "In1.Cu")
	)
	(gr_line
		(start 168.54805 -26.725372)
		(end 168.54805 -25.048972)
		(stroke
			(width 0.2032)
			(type default)
		)
		(layer "In1.Cu")
	)
	(gr_line
		(start 168.54805 -25.048972)
		(end 169.61485 -25.048972)
		(stroke
			(width 0.2032)
			(type default)
		)
		(layer "In1.Cu")
	)
	(gr_line
		(start 168.5544 -29.083)
		(end 168.5544 -27.7368)
		(stroke
			(width 0.508)
			(type default)
		)
		(layer "In1.Cu")
	)
	(gr_line
		(start 168.566592 -13.335)
		(end 169.201592 -13.335)
		(stroke
			(width 0.508)
			(type default)
		)
		(layer "In1.Cu")
	)
	(gr_line
		(start 168.566592 -9.134856)
		(end 169.201592 -9.134856)
		(stroke
			(width 0.508)
			(type default)
		)
		(layer "In1.Cu")
	)
	(gr_line
		(start 168.57345 -26.750772)
		(end 169.56405 -26.750772)
		(stroke
			(width 0.2032)
			(type default)
		)
		(layer "In1.Cu")
	)
	(gr_line
		(start 168.57345 -26.725372)
		(end 168.57345 -26.750772)
		(stroke
			(width 0.2032)
			(type default)
		)
		(layer "In1.Cu")
	)
	(gr_line
		(start 168.5798 -29.083)
		(end 168.5798 -27.7368)
		(stroke
			(width 0.508)
			(type default)
		)
		(layer "In1.Cu")
	)
	(gr_line
		(start 168.591992 -13.6144)
		(end 169.226992 -13.6144)
		(stroke
			(width 0.508)
			(type default)
		)
		(layer "In1.Cu")
	)
	(gr_line
		(start 168.591992 -11.2014)
		(end 169.430192 -11.2014)
		(stroke
			(width 0.2032)
			(type default)
		)
		(layer "In1.Cu")
	)
	(gr_line
		(start 168.591992 -9.414256)
		(end 169.226992 -9.414256)
		(stroke
			(width 0.508)
			(type default)
		)
		(layer "In1.Cu")
	)
	(gr_line
		(start 168.591992 -7.001256)
		(end 169.430192 -7.001256)
		(stroke
			(width 0.2032)
			(type default)
		)
		(layer "In1.Cu")
	)
	(gr_line
		(start 168.617392 -13.6144)
		(end 168.617392 -11.43)
		(stroke
			(width 0.254)
			(type default)
		)
		(layer "In1.Cu")
	)
	(gr_line
		(start 168.617392 -11.43)
		(end 169.099992 -11.43)
		(stroke
			(width 0.254)
			(type default)
		)
		(layer "In1.Cu")
	)
	(gr_line
		(start 168.617392 -11.2522)
		(end 169.353992 -11.2522)
		(stroke
			(width 0.254)
			(type default)
		)
		(layer "In1.Cu")
	)
	(gr_line
		(start 168.617392 -9.414256)
		(end 168.617392 -7.229856)
		(stroke
			(width 0.254)
			(type default)
		)
		(layer "In1.Cu")
	)
	(gr_line
		(start 168.617392 -7.229856)
		(end 169.099992 -7.229856)
		(stroke
			(width 0.254)
			(type default)
		)
		(layer "In1.Cu")
	)
	(gr_line
		(start 168.617392 -7.052056)
		(end 169.353992 -7.052056)
		(stroke
			(width 0.254)
			(type default)
		)
		(layer "In1.Cu")
	)
	(gr_line
		(start 168.62425 -26.674572)
		(end 169.56405 -26.674572)
		(stroke
			(width 0.2032)
			(type default)
		)
		(layer "In1.Cu")
	)
	(gr_line
		(start 168.62425 -25.099772)
		(end 168.62425 -26.674572)
		(stroke
			(width 0.2032)
			(type default)
		)
		(layer "In1.Cu")
	)
	(gr_line
		(start 168.6306 -29.083)
		(end 168.6306 -27.7368)
		(stroke
			(width 0.508)
			(type default)
		)
		(layer "In1.Cu")
	)
	(gr_line
		(start 168.635934 -11.36523)
		(end 169.270934 -11.36523)
		(stroke
			(width 0.508)
			(type default)
		)
		(layer "In1.Cu")
	)
	(gr_line
		(start 168.635934 -7.165086)
		(end 169.270934 -7.165086)
		(stroke
			(width 0.508)
			(type default)
		)
		(layer "In1.Cu")
	)
	(gr_line
		(start 168.642792 -13.6144)
		(end 169.277792 -13.6144)
		(stroke
			(width 0.508)
			(type default)
		)
		(layer "In1.Cu")
	)
	(gr_line
		(start 168.642792 -13.4874)
		(end 168.642792 -11.5062)
		(stroke
			(width 0.762)
			(type default)
		)
		(layer "In1.Cu")
	)
	(gr_line
		(start 168.642792 -11.5062)
		(end 169.277792 -11.5062)
		(stroke
			(width 0.508)
			(type default)
		)
		(layer "In1.Cu")
	)
	(gr_line
		(start 168.642792 -9.414256)
		(end 169.277792 -9.414256)
		(stroke
			(width 0.508)
			(type default)
		)
		(layer "In1.Cu")
	)
	(gr_line
		(start 168.642792 -9.287256)
		(end 168.642792 -7.306056)
		(stroke
			(width 0.762)
			(type default)
		)
		(layer "In1.Cu")
	)
	(gr_line
		(start 168.642792 -7.306056)
		(end 169.277792 -7.306056)
		(stroke
			(width 0.508)
			(type default)
		)
		(layer "In1.Cu")
	)
	(gr_line
		(start 168.656 -29.083)
		(end 168.656 -27.7368)
		(stroke
			(width 0.508)
			(type default)
		)
		(layer "In1.Cu")
	)
	(gr_line
		(start 168.6814 -29.083)
		(end 168.6814 -27.7368)
		(stroke
			(width 0.508)
			(type default)
		)
		(layer "In1.Cu")
	)
	(gr_line
		(start 168.693592 -13.5382)
		(end 168.693592 -11.5062)
		(stroke
			(width 0.254)
			(type default)
		)
		(layer "In1.Cu")
	)
	(gr_line
		(start 168.693592 -11.5062)
		(end 169.023792 -11.5062)
		(stroke
			(width 0.254)
			(type default)
		)
		(layer "In1.Cu")
	)
	(gr_line
		(start 168.693592 -9.338056)
		(end 168.693592 -7.306056)
		(stroke
			(width 0.254)
			(type default)
		)
		(layer "In1.Cu")
	)
	(gr_line
		(start 168.693592 -7.306056)
		(end 169.023792 -7.306056)
		(stroke
			(width 0.254)
			(type default)
		)
		(layer "In1.Cu")
	)
	(gr_line
		(start 168.70045 -26.598372)
		(end 168.70045 -25.252172)
		(stroke
			(width 0.508)
			(type default)
		)
		(layer "In1.Cu")
	)
	(gr_line
		(start 168.7068 -29.083)
		(end 168.7068 -27.7368)
		(stroke
			(width 0.508)
			(type default)
		)
		(layer "In1.Cu")
	)
	(gr_line
		(start 168.72585 -26.598372)
		(end 169.38625 -26.598372)
		(stroke
			(width 0.508)
			(type default)
		)
		(layer "In1.Cu")
	)
	(gr_line
		(start 168.72585 -26.572972)
		(end 168.72585 -25.226772)
		(stroke
			(width 0.508)
			(type default)
		)
		(layer "In1.Cu")
	)
	(gr_line
		(start 168.72585 -25.201372)
		(end 169.36085 -25.201372)
		(stroke
			(width 0.508)
			(type default)
		)
		(layer "In1.Cu")
	)
	(gr_line
		(start 168.7322 -29.1084)
		(end 168.7322 -27.7622)
		(stroke
			(width 0.508)
			(type default)
		)
		(layer "In1.Cu")
	)
	(gr_line
		(start 168.73474 -18.5166)
		(end 167.46474 -18.5166)
		(stroke
			(width 0.7874)
			(type default)
		)
		(layer "In1.Cu")
	)
	(gr_line
		(start 168.75125 -26.572972)
		(end 168.75125 -25.226772)
		(stroke
			(width 0.508)
			(type default)
		)
		(layer "In1.Cu")
	)
	(gr_line
		(start 168.7576 -29.1084)
		(end 168.7576 -27.7622)
		(stroke
			(width 0.508)
			(type default)
		)
		(layer "In1.Cu")
	)
	(gr_line
		(start 168.7576 -29.083)
		(end 168.7576 -27.7368)
		(stroke
			(width 0.508)
			(type default)
		)
		(layer "In1.Cu")
	)
	(gr_line
		(start 168.77665 -26.572972)
		(end 168.77665 -25.226772)
		(stroke
			(width 0.508)
			(type default)
		)
		(layer "In1.Cu")
	)
	(gr_line
		(start 168.783 -29.083)
		(end 168.783 -27.7368)
		(stroke
			(width 0.508)
			(type default)
		)
		(layer "In1.Cu")
	)
	(gr_line
		(start 168.795192 -13.462)
		(end 168.795192 -11.6586)
		(stroke
			(width 0.254)
			(type default)
		)
		(layer "In1.Cu")
	)
	(gr_line
		(start 168.795192 -13.462)
		(end 168.795192 -11.4808)
		(stroke
			(width 0.762)
			(type default)
		)
		(layer "In1.Cu")
	)
	(gr_line
		(start 168.795192 -11.6586)
		(end 168.896792 -11.6586)
		(stroke
			(width 0.254)
			(type default)
		)
		(layer "In1.Cu")
	)
	(gr_line
		(start 168.795192 -9.261856)
		(end 168.795192 -7.458456)
		(stroke
			(width 0.254)
			(type default)
		)
		(layer "In1.Cu")
	)
	(gr_line
		(start 168.795192 -9.261856)
		(end 168.795192 -7.280656)
		(stroke
			(width 0.762)
			(type default)
		)
		(layer "In1.Cu")
	)
	(gr_line
		(start 168.795192 -7.458456)
		(end 168.896792 -7.458456)
		(stroke
			(width 0.254)
			(type default)
		)
		(layer "In1.Cu")
	)
	(gr_line
		(start 168.8084 -29.083)
		(end 168.8084 -27.7368)
		(stroke
			(width 0.508)
			(type default)
		)
		(layer "In1.Cu")
	)
	(gr_line
		(start 168.82745 -26.598372)
		(end 168.82745 -25.252172)
		(stroke
			(width 0.508)
			(type default)
		)
		(layer "In1.Cu")
	)
	(gr_line
		(start 168.82745 -26.572972)
		(end 168.82745 -25.226772)
		(stroke
			(width 0.508)
			(type default)
		)
		(layer "In1.Cu")
	)
	(gr_line
		(start 168.8338 -29.083)
		(end 168.8338 -27.7368)
		(stroke
			(width 0.508)
			(type default)
		)
		(layer "In1.Cu")
	)
	(gr_line
		(start 168.8592 -29.1084)
		(end 168.8592 -27.7622)
		(stroke
			(width 0.508)
			(type default)
		)
		(layer "In1.Cu")
	)
	(gr_line
		(start 168.8592 -29.083)
		(end 168.8592 -27.7368)
		(stroke
			(width 0.508)
			(type default)
		)
		(layer "In1.Cu")
	)
	(gr_line
		(start 168.87825 -26.572972)
		(end 168.87825 -25.226772)
		(stroke
			(width 0.508)
			(type default)
		)
		(layer "In1.Cu")
	)
	(gr_line
		(start 168.8846 -29.1084)
		(end 168.8846 -27.7622)
		(stroke
			(width 0.508)
			(type default)
		)
		(layer "In1.Cu")
	)
	(gr_line
		(start 168.8846 -29.083)
		(end 168.8846 -27.7368)
		(stroke
			(width 0.508)
			(type default)
		)
		(layer "In1.Cu")
	)
	(gr_line
		(start 168.896792 -13.5636)
		(end 168.845992 -13.5636)
		(stroke
			(width 0.254)
			(type default)
		)
		(layer "In1.Cu")
	)
	(gr_line
		(start 168.896792 -11.6586)
		(end 168.896792 -13.5636)
		(stroke
			(width 0.254)
			(type default)
		)
		(layer "In1.Cu")
	)
	(gr_line
		(start 168.896792 -9.363456)
		(end 168.845992 -9.363456)
		(stroke
			(width 0.254)
			(type default)
		)
		(layer "In1.Cu")
	)
	(gr_line
		(start 168.896792 -7.458456)
		(end 168.896792 -9.363456)
		(stroke
			(width 0.254)
			(type default)
		)
		(layer "In1.Cu")
	)
	(gr_line
		(start 168.90365 -26.547572)
		(end 168.90365 -25.201372)
		(stroke
			(width 0.508)
			(type default)
		)
		(layer "In1.Cu")
	)
	(gr_line
		(start 168.91 -29.1084)
		(end 168.91 -27.7622)
		(stroke
			(width 0.508)
			(type default)
		)
		(layer "In1.Cu")
	)
	(gr_line
		(start 168.92905 -26.572972)
		(end 168.92905 -25.226772)
		(stroke
			(width 0.508)
			(type default)
		)
		(layer "In1.Cu")
	)
	(gr_line
		(start 168.9354 -29.337)
		(end 169.2656 -29.337)
		(stroke
			(width 0.1016)
			(type default)
		)
		(layer "In1.Cu")
	)
	(gr_line
		(start 168.9354 -29.083)
		(end 168.9354 -27.7368)
		(stroke
			(width 0.508)
			(type default)
		)
		(layer "In1.Cu")
	)
	(gr_line
		(start 168.947592 -13.4874)
		(end 168.947592 -11.5062)
		(stroke
			(width 0.762)
			(type default)
		)
		(layer "In1.Cu")
	)
	(gr_line
		(start 168.947592 -9.287256)
		(end 168.947592 -7.306056)
		(stroke
			(width 0.762)
			(type default)
		)
		(layer "In1.Cu")
	)
	(gr_line
		(start 168.95445 -26.572972)
		(end 168.95445 -25.226772)
		(stroke
			(width 0.508)
			(type default)
		)
		(layer "In1.Cu")
	)
	(gr_line
		(start 168.9608 -29.1084)
		(end 168.9608 -27.7622)
		(stroke
			(width 0.508)
			(type default)
		)
		(layer "In1.Cu")
	)
	(gr_line
		(start 168.9608 -29.083)
		(end 168.9608 -27.7368)
		(stroke
			(width 0.508)
			(type default)
		)
		(layer "In1.Cu")
	)
	(gr_line
		(start 168.97985 -26.572972)
		(end 168.97985 -25.226772)
		(stroke
			(width 0.508)
			(type default)
		)
		(layer "In1.Cu")
	)
	(gr_line
		(start 168.9862 -29.1084)
		(end 168.9862 -27.7622)
		(stroke
			(width 0.508)
			(type default)
		)
		(layer "In1.Cu")
	)
	(gr_line
		(start 169.023792 -13.462)
		(end 168.795192 -13.462)
		(stroke
			(width 0.254)
			(type default)
		)
		(layer "In1.Cu")
	)
	(gr_line
		(start 169.023792 -11.5062)
		(end 169.023792 -13.462)
		(stroke
			(width 0.254)
			(type default)
		)
		(layer "In1.Cu")
	)
	(gr_line
		(start 169.023792 -9.261856)
		(end 168.795192 -9.261856)
		(stroke
			(width 0.254)
			(type default)
		)
		(layer "In1.Cu")
	)
	(gr_line
		(start 169.023792 -7.306056)
		(end 169.023792 -9.261856)
		(stroke
			(width 0.254)
			(type default)
		)
		(layer "In1.Cu")
	)
	(gr_line
		(start 169.03065 -26.572972)
		(end 169.03065 -25.226772)
		(stroke
			(width 0.508)
			(type default)
		)
		(layer "In1.Cu")
	)
	(gr_line
		(start 169.05605 -26.572972)
		(end 169.05605 -25.226772)
		(stroke
			(width 0.508)
			(type default)
		)
		(layer "In1.Cu")
	)
	(gr_line
		(start 169.0624 -29.1084)
		(end 169.0624 -27.7622)
		(stroke
			(width 0.508)
			(type default)
		)
		(layer "In1.Cu")
	)
	(gr_line
		(start 169.074592 -13.8176)
		(end 169.074592 -13.7668)
		(stroke
			(width 0.1016)
			(type default)
		)
		(layer "In1.Cu")
	)
	(gr_line
		(start 169.074592 -13.8176)
		(end 169.480992 -13.8176)
		(stroke
			(width 0.1016)
			(type default)
		)
		(layer "In1.Cu")
	)
	(gr_line
		(start 169.074592 -13.7668)
		(end 168.312592 -13.7668)
		(stroke
			(width 0.1016)
			(type default)
		)
		(layer "In1.Cu")
	)
	(gr_line
		(start 169.074592 -13.4874)
		(end 169.074592 -11.5062)
		(stroke
			(width 0.762)
			(type default)
		)
		(layer "In1.Cu")
	)
	(gr_line
		(start 169.074592 -9.617456)
		(end 169.074592 -9.566656)
		(stroke
			(width 0.1016)
			(type default)
		)
		(layer "In1.Cu")
	)
	(gr_line
		(start 169.074592 -9.617456)
		(end 169.480992 -9.617456)
		(stroke
			(width 0.1016)
			(type default)
		)
		(layer "In1.Cu")
	)
	(gr_line
		(start 169.074592 -9.566656)
		(end 168.312592 -9.566656)
		(stroke
			(width 0.1016)
			(type default)
		)
		(layer "In1.Cu")
	)
	(gr_line
		(start 169.074592 -9.287256)
		(end 169.074592 -7.306056)
		(stroke
			(width 0.762)
			(type default)
		)
		(layer "In1.Cu")
	)
	(gr_line
		(start 169.08145 -26.572972)
		(end 169.08145 -25.226772)
		(stroke
			(width 0.508)
			(type default)
		)
		(layer "In1.Cu")
	)
	(gr_line
		(start 169.099992 -13.5382)
		(end 168.693592 -13.5382)
		(stroke
			(width 0.254)
			(type default)
		)
		(layer "In1.Cu")
	)
	(gr_line
		(start 169.099992 -11.43)
		(end 169.099992 -13.5382)
		(stroke
			(width 0.254)
			(type default)
		)
		(layer "In1.Cu")
	)
	(gr_line
		(start 169.099992 -9.338056)
		(end 168.693592 -9.338056)
		(stroke
			(width 0.254)
			(type default)
		)
		(layer "In1.Cu")
	)
	(gr_line
		(start 169.099992 -7.229856)
		(end 169.099992 -9.338056)
		(stroke
			(width 0.254)
			(type default)
		)
		(layer "In1.Cu")
	)
	(gr_line
		(start 169.10685 -26.572972)
		(end 169.10685 -25.226772)
		(stroke
			(width 0.508)
			(type default)
		)
		(layer "In1.Cu")
	)
	(gr_line
		(start 169.13225 -26.598372)
		(end 169.13225 -25.252172)
		(stroke
			(width 0.508)
			(type default)
		)
		(layer "In1.Cu")
	)
	(gr_line
		(start 169.150792 -13.4874)
		(end 169.150792 -11.5062)
		(stroke
			(width 0.762)
			(type default)
		)
		(layer "In1.Cu")
	)
	(gr_line
		(start 169.150792 -9.287256)
		(end 169.150792 -7.306056)
		(stroke
			(width 0.762)
			(type default)
		)
		(layer "In1.Cu")
	)
	(gr_line
		(start 169.15765 -26.598372)
		(end 169.15765 -25.252172)
		(stroke
			(width 0.508)
			(type default)
		)
		(layer "In1.Cu")
	)
	(gr_line
		(start 169.15765 -26.572972)
		(end 169.15765 -25.226772)
		(stroke
			(width 0.508)
			(type default)
		)
		(layer "In1.Cu")
	)
	(gr_line
		(start 169.164 -29.2608)
		(end 169.164 -27.6098)
		(stroke
			(width 0.2032)
			(type default)
		)
		(layer "In1.Cu")
	)
	(gr_line
		(start 169.164 -29.2354)
		(end 168.148 -29.2354)
		(stroke
			(width 0.2032)
			(type default)
		)
		(layer "In1.Cu")
	)
	(gr_line
		(start 169.164 -29.1846)
		(end 169.164 -29.2354)
		(stroke
			(width 0.2032)
			(type default)
		)
		(layer "In1.Cu")
	)
	(gr_line
		(start 169.164 -27.6098)
		(end 168.2242 -27.6098)
		(stroke
			(width 0.2032)
			(type default)
		)
		(layer "In1.Cu")
	)
	(gr_line
		(start 169.176192 -13.6144)
		(end 168.617392 -13.6144)
		(stroke
			(width 0.254)
			(type default)
		)
		(layer "In1.Cu")
	)
	(gr_line
		(start 169.176192 -11.3792)
		(end 169.176192 -13.6144)
		(stroke
			(width 0.254)
			(type default)
		)
		(layer "In1.Cu")
	)
	(gr_line
		(start 169.176192 -9.414256)
		(end 168.617392 -9.414256)
		(stroke
			(width 0.254)
			(type default)
		)
		(layer "In1.Cu")
	)
	(gr_line
		(start 169.176192 -7.179056)
		(end 169.176192 -9.414256)
		(stroke
			(width 0.254)
			(type default)
		)
		(layer "In1.Cu")
	)
	(gr_line
		(start 169.18305 -26.572972)
		(end 169.18305 -25.226772)
		(stroke
			(width 0.508)
			(type default)
		)
		(layer "In1.Cu")
	)
	(gr_line
		(start 169.20845 -26.572972)
		(end 169.20845 -25.226772)
		(stroke
			(width 0.508)
			(type default)
		)
		(layer "In1.Cu")
	)
	(gr_line
		(start 169.2148 -29.2354)
		(end 168.1734 -29.2354)
		(stroke
			(width 0.2032)
			(type default)
		)
		(layer "In1.Cu")
	)
	(gr_line
		(start 169.2148 -27.559)
		(end 169.2148 -29.2354)
		(stroke
			(width 0.2032)
			(type default)
		)
		(layer "In1.Cu")
	)
	(gr_line
		(start 169.23385 -26.572972)
		(end 169.23385 -25.226772)
		(stroke
			(width 0.508)
			(type default)
		)
		(layer "In1.Cu")
	)
	(gr_line
		(start 169.252392 -13.6398)
		(end 168.541192 -13.6398)
		(stroke
			(width 0.254)
			(type default)
		)
		(layer "In1.Cu")
	)
	(gr_line
		(start 169.252392 -11.303)
		(end 169.252392 -13.6398)
		(stroke
			(width 0.254)
			(type default)
		)
		(layer "In1.Cu")
	)
	(gr_line
		(start 169.252392 -9.439656)
		(end 168.541192 -9.439656)
		(stroke
			(width 0.254)
			(type default)
		)
		(layer "In1.Cu")
	)
	(gr_line
		(start 169.252392 -7.102856)
		(end 169.252392 -9.439656)
		(stroke
			(width 0.254)
			(type default)
		)
		(layer "In1.Cu")
	)
	(gr_line
		(start 169.25925 -26.598372)
		(end 169.25925 -25.252172)
		(stroke
			(width 0.508)
			(type default)
		)
		(layer "In1.Cu")
	)
	(gr_line
		(start 169.25925 -26.572972)
		(end 169.25925 -25.226772)
		(stroke
			(width 0.508)
			(type default)
		)
		(layer "In1.Cu")
	)
	(gr_line
		(start 169.2656 -29.337)
		(end 169.2656 -27.4828)
		(stroke
			(width 0.1016)
			(type default)
		)
		(layer "In1.Cu")
	)
	(gr_line
		(start 169.2656 -27.4828)
		(end 168.0972 -27.4828)
		(stroke
			(width 0.1016)
			(type default)
		)
		(layer "In1.Cu")
	)
	(gr_line
		(start 169.277792 -13.7668)
		(end 168.287192 -13.7668)
		(stroke
			(width 0.1016)
			(type default)
		)
		(layer "In1.Cu")
	)
	(gr_line
		(start 169.277792 -13.6906)
		(end 168.464992 -13.6906)
		(stroke
			(width 0.254)
			(type default)
		)
		(layer "In1.Cu")
	)
	(gr_line
		(start 169.277792 -11.2776)
		(end 169.277792 -13.6906)
		(stroke
			(width 0.254)
			(type default)
		)
		(layer "In1.Cu")
	)
	(gr_line
		(start 169.277792 -9.566656)
		(end 168.287192 -9.566656)
		(stroke
			(width 0.1016)
			(type default)
		)
		(layer "In1.Cu")
	)
	(gr_line
		(start 169.277792 -9.490456)
		(end 168.464992 -9.490456)
		(stroke
			(width 0.254)
			(type default)
		)
		(layer "In1.Cu")
	)
	(gr_line
		(start 169.277792 -7.077456)
		(end 169.277792 -9.490456)
		(stroke
			(width 0.254)
			(type default)
		)
		(layer "In1.Cu")
	)
	(gr_line
		(start 169.28465 -26.598372)
		(end 169.28465 -25.252172)
		(stroke
			(width 0.508)
			(type default)
		)
		(layer "In1.Cu")
	)
	(gr_line
		(start 169.28465 -26.572972)
		(end 169.28465 -25.226772)
		(stroke
			(width 0.508)
			(type default)
		)
		(layer "In1.Cu")
	)
	(gr_line
		(start 169.303192 -13.716)
		(end 168.439592 -13.716)
		(stroke
			(width 0.254)
			(type default)
		)
		(layer "In1.Cu")
	)
	(gr_line
		(start 169.303192 -11.2522)
		(end 169.303192 -13.716)
		(stroke
			(width 0.254)
			(type default)
		)
		(layer "In1.Cu")
	)
	(gr_line
		(start 169.303192 -9.515856)
		(end 168.439592 -9.515856)
		(stroke
			(width 0.254)
			(type default)
		)
		(layer "In1.Cu")
	)
	(gr_line
		(start 169.303192 -7.052056)
		(end 169.303192 -9.515856)
		(stroke
			(width 0.254)
			(type default)
		)
		(layer "In1.Cu")
	)
	(gr_line
		(start 169.31005 -26.598372)
		(end 169.31005 -25.252172)
		(stroke
			(width 0.508)
			(type default)
		)
		(layer "In1.Cu")
	)
	(gr_line
		(start 169.319956 -30.734)
		(end 168.049956 -30.734)
		(stroke
			(width 0.7874)
			(type default)
		)
		(layer "In1.Cu")
	)
	(gr_line
		(start 169.33545 -26.826972)
		(end 169.66565 -26.826972)
		(stroke
			(width 0.1016)
			(type default)
		)
		(layer "In1.Cu")
	)
	(gr_line
		(start 169.33545 -26.572972)
		(end 169.33545 -25.226772)
		(stroke
			(width 0.508)
			(type default)
		)
		(layer "In1.Cu")
	)
	(gr_line
		(start 169.353992 -13.7414)
		(end 168.414192 -13.7414)
		(stroke
			(width 0.254)
			(type default)
		)
		(layer "In1.Cu")
	)
	(gr_line
		(start 169.353992 -11.2522)
		(end 169.353992 -13.7414)
		(stroke
			(width 0.254)
			(type default)
		)
		(layer "In1.Cu")
	)
	(gr_line
		(start 169.353992 -9.541256)
		(end 168.414192 -9.541256)
		(stroke
			(width 0.254)
			(type default)
		)
		(layer "In1.Cu")
	)
	(gr_line
		(start 169.353992 -7.052056)
		(end 169.353992 -9.541256)
		(stroke
			(width 0.254)
			(type default)
		)
		(layer "In1.Cu")
	)
	(gr_line
		(start 169.36085 -26.598372)
		(end 169.36085 -25.252172)
		(stroke
			(width 0.508)
			(type default)
		)
		(layer "In1.Cu")
	)
	(gr_line
		(start 169.36085 -26.572972)
		(end 169.36085 -25.226772)
		(stroke
			(width 0.508)
			(type default)
		)
		(layer "In1.Cu")
	)
	(gr_line
		(start 169.379392 -13.7414)
		(end 168.414192 -13.7414)
		(stroke
			(width 0.2032)
			(type default)
		)
		(layer "In1.Cu")
	)
	(gr_line
		(start 169.379392 -11.2014)
		(end 169.379392 -13.7414)
		(stroke
			(width 0.2032)
			(type default)
		)
		(layer "In1.Cu")
	)
	(gr_line
		(start 169.379392 -9.541256)
		(end 168.414192 -9.541256)
		(stroke
			(width 0.2032)
			(type default)
		)
		(layer "In1.Cu")
	)
	(gr_line
		(start 169.379392 -7.001256)
		(end 169.379392 -9.541256)
		(stroke
			(width 0.2032)
			(type default)
		)
		(layer "In1.Cu")
	)
	(gr_line
		(start 169.38625 -26.598372)
		(end 169.38625 -25.252172)
		(stroke
			(width 0.508)
			(type default)
		)
		(layer "In1.Cu")
	)
	(gr_line
		(start 169.430192 -13.7668)
		(end 168.363392 -13.7668)
		(stroke
			(width 0.2032)
			(type default)
		)
		(layer "In1.Cu")
	)
	(gr_line
		(start 169.430192 -11.2014)
		(end 169.430192 -13.7668)
		(stroke
			(width 0.2032)
			(type default)
		)
		(layer "In1.Cu")
	)
	(gr_line
		(start 169.430192 -9.566656)
		(end 168.363392 -9.566656)
		(stroke
			(width 0.2032)
			(type default)
		)
		(layer "In1.Cu")
	)
	(gr_line
		(start 169.430192 -7.001256)
		(end 169.430192 -9.566656)
		(stroke
			(width 0.2032)
			(type default)
		)
		(layer "In1.Cu")
	)
	(gr_line
		(start 169.455592 -13.7668)
		(end 168.337992 -13.7668)
		(stroke
			(width 0.1016)
			(type default)
		)
		(layer "In1.Cu")
	)
	(gr_line
		(start 169.455592 -11.176)
		(end 169.455592 -13.7668)
		(stroke
			(width 0.1016)
			(type default)
		)
		(layer "In1.Cu")
	)
	(gr_line
		(start 169.455592 -9.566656)
		(end 168.337992 -9.566656)
		(stroke
			(width 0.1016)
			(type default)
		)
		(layer "In1.Cu")
	)
	(gr_line
		(start 169.455592 -6.975856)
		(end 169.455592 -9.566656)
		(stroke
			(width 0.1016)
			(type default)
		)
		(layer "In1.Cu")
	)
	(gr_line
		(start 169.46245 -26.598372)
		(end 169.46245 -25.252172)
		(stroke
			(width 0.508)
			(type default)
		)
		(layer "In1.Cu")
	)
	(gr_line
		(start 169.480992 -13.8176)
		(end 169.074592 -13.8176)
		(stroke
			(width 0.1016)
			(type default)
		)
		(layer "In1.Cu")
	)
	(gr_line
		(start 169.480992 -13.8176)
		(end 169.480992 -11.1506)
		(stroke
			(width 0.1016)
			(type default)
		)
		(layer "In1.Cu")
	)
	(gr_line
		(start 169.480992 -11.1506)
		(end 168.287192 -11.1506)
		(stroke
			(width 0.1016)
			(type default)
		)
		(layer "In1.Cu")
	)
	(gr_line
		(start 169.480992 -11.1506)
		(end 169.480992 -13.8176)
		(stroke
			(width 0.1016)
			(type default)
		)
		(layer "In1.Cu")
	)
	(gr_line
		(start 169.480992 -9.617456)
		(end 169.074592 -9.617456)
		(stroke
			(width 0.1016)
			(type default)
		)
		(layer "In1.Cu")
	)
	(gr_line
		(start 169.480992 -9.617456)
		(end 169.480992 -6.950456)
		(stroke
			(width 0.1016)
			(type default)
		)
		(layer "In1.Cu")
	)
	(gr_line
		(start 169.480992 -6.950456)
		(end 168.287192 -6.950456)
		(stroke
			(width 0.1016)
			(type default)
		)
		(layer "In1.Cu")
	)
	(gr_line
		(start 169.480992 -6.950456)
		(end 169.480992 -9.617456)
		(stroke
			(width 0.1016)
			(type default)
		)
		(layer "In1.Cu")
	)
	(gr_line
		(start 169.56405 -26.750772)
		(end 169.56405 -25.099772)
		(stroke
			(width 0.2032)
			(type default)
		)
		(layer "In1.Cu")
	)
	(gr_line
		(start 169.56405 -26.725372)
		(end 168.54805 -26.725372)
		(stroke
			(width 0.2032)
			(type default)
		)
		(layer "In1.Cu")
	)
	(gr_line
		(start 169.56405 -26.674572)
		(end 169.56405 -26.725372)
		(stroke
			(width 0.2032)
			(type default)
		)
		(layer "In1.Cu")
	)
	(gr_line
		(start 169.56405 -25.099772)
		(end 168.62425 -25.099772)
		(stroke
			(width 0.2032)
			(type default)
		)
		(layer "In1.Cu")
	)
	(gr_line
		(start 169.61485 -26.725372)
		(end 168.57345 -26.725372)
		(stroke
			(width 0.2032)
			(type default)
		)
		(layer "In1.Cu")
	)
	(gr_line
		(start 169.61485 -25.048972)
		(end 169.61485 -26.725372)
		(stroke
			(width 0.2032)
			(type default)
		)
		(layer "In1.Cu")
	)
	(gr_line
		(start 169.66565 -26.826972)
		(end 169.66565 -24.972772)
		(stroke
			(width 0.1016)
			(type default)
		)
		(layer "In1.Cu")
	)
	(gr_line
		(start 169.66565 -24.972772)
		(end 168.49725 -24.972772)
		(stroke
			(width 0.1016)
			(type default)
		)
		(layer "In1.Cu")
	)
	(gr_line
		(start 170.287188 -12.563348)
		(end 171.074588 -12.563348)
		(stroke
			(width 0.1016)
			(type default)
		)
		(layer "In1.Cu")
	)
	(gr_line
		(start 170.287188 -12.512548)
		(end 170.287188 -9.896348)
		(stroke
			(width 0.1016)
			(type default)
		)
		(layer "In1.Cu")
	)
	(gr_line
		(start 170.287188 -12.463272)
		(end 171.074588 -12.463272)
		(stroke
			(width 0.1016)
			(type default)
		)
		(layer "In1.Cu")
	)
	(gr_line
		(start 170.287188 -12.412472)
		(end 170.287188 -9.796272)
		(stroke
			(width 0.1016)
			(type default)
		)
		(layer "In1.Cu")
	)
	(gr_line
		(start 170.287188 -9.896348)
		(end 170.287188 -12.563348)
		(stroke
			(width 0.1016)
			(type default)
		)
		(layer "In1.Cu")
	)
	(gr_line
		(start 170.287188 -9.896348)
		(end 171.480988 -9.896348)
		(stroke
			(width 0.1016)
			(type default)
		)
		(layer "In1.Cu")
	)
	(gr_line
		(start 170.287188 -9.796272)
		(end 170.287188 -12.463272)
		(stroke
			(width 0.1016)
			(type default)
		)
		(layer "In1.Cu")
	)
	(gr_line
		(start 170.287188 -9.796272)
		(end 171.480988 -9.796272)
		(stroke
			(width 0.1016)
			(type default)
		)
		(layer "In1.Cu")
	)
	(gr_line
		(start 170.287188 -8.363204)
		(end 171.074588 -8.363204)
		(stroke
			(width 0.1016)
			(type default)
		)
		(layer "In1.Cu")
	)
	(gr_line
		(start 170.287188 -8.312404)
		(end 170.287188 -5.696204)
		(stroke
			(width 0.1016)
			(type default)
		)
		(layer "In1.Cu")
	)
	(gr_line
		(start 170.287188 -8.263128)
		(end 171.074588 -8.263128)
		(stroke
			(width 0.1016)
			(type default)
		)
		(layer "In1.Cu")
	)
	(gr_line
		(start 170.287188 -8.212328)
		(end 170.287188 -5.596128)
		(stroke
			(width 0.1016)
			(type default)
		)
		(layer "In1.Cu")
	)
	(gr_line
		(start 170.287188 -5.696204)
		(end 170.287188 -8.363204)
		(stroke
			(width 0.1016)
			(type default)
		)
		(layer "In1.Cu")
	)
	(gr_line
		(start 170.287188 -5.696204)
		(end 171.480988 -5.696204)
		(stroke
			(width 0.1016)
			(type default)
		)
		(layer "In1.Cu")
	)
	(gr_line
		(start 170.287188 -5.596128)
		(end 170.287188 -8.263128)
		(stroke
			(width 0.1016)
			(type default)
		)
		(layer "In1.Cu")
	)
	(gr_line
		(start 170.287188 -5.596128)
		(end 171.480988 -5.596128)
		(stroke
			(width 0.1016)
			(type default)
		)
		(layer "In1.Cu")
	)
	(gr_line
		(start 170.312588 -12.512548)
		(end 170.312588 -9.921748)
		(stroke
			(width 0.1016)
			(type default)
		)
		(layer "In1.Cu")
	)
	(gr_line
		(start 170.312588 -12.412472)
		(end 170.312588 -9.821672)
		(stroke
			(width 0.1016)
			(type default)
		)
		(layer "In1.Cu")
	)
	(gr_line
		(start 170.312588 -9.921748)
		(end 171.455588 -9.921748)
		(stroke
			(width 0.1016)
			(type default)
		)
		(layer "In1.Cu")
	)
	(gr_line
		(start 170.312588 -9.821672)
		(end 171.455588 -9.821672)
		(stroke
			(width 0.1016)
			(type default)
		)
		(layer "In1.Cu")
	)
	(gr_line
		(start 170.312588 -8.312404)
		(end 170.312588 -5.721604)
		(stroke
			(width 0.1016)
			(type default)
		)
		(layer "In1.Cu")
	)
	(gr_line
		(start 170.312588 -8.212328)
		(end 170.312588 -5.621528)
		(stroke
			(width 0.1016)
			(type default)
		)
		(layer "In1.Cu")
	)
	(gr_line
		(start 170.312588 -5.721604)
		(end 171.455588 -5.721604)
		(stroke
			(width 0.1016)
			(type default)
		)
		(layer "In1.Cu")
	)
	(gr_line
		(start 170.312588 -5.621528)
		(end 171.455588 -5.621528)
		(stroke
			(width 0.1016)
			(type default)
		)
		(layer "In1.Cu")
	)
	(gr_line
		(start 170.337988 -12.512548)
		(end 170.337988 -9.947148)
		(stroke
			(width 0.1016)
			(type default)
		)
		(layer "In1.Cu")
	)
	(gr_line
		(start 170.337988 -12.412472)
		(end 170.337988 -9.847072)
		(stroke
			(width 0.1016)
			(type default)
		)
		(layer "In1.Cu")
	)
	(gr_line
		(start 170.337988 -9.947148)
		(end 170.591988 -9.947148)
		(stroke
			(width 0.1016)
			(type default)
		)
		(layer "In1.Cu")
	)
	(gr_line
		(start 170.337988 -9.847072)
		(end 170.591988 -9.847072)
		(stroke
			(width 0.1016)
			(type default)
		)
		(layer "In1.Cu")
	)
	(gr_line
		(start 170.337988 -8.312404)
		(end 170.337988 -5.747004)
		(stroke
			(width 0.1016)
			(type default)
		)
		(layer "In1.Cu")
	)
	(gr_line
		(start 170.337988 -8.212328)
		(end 170.337988 -5.646928)
		(stroke
			(width 0.1016)
			(type default)
		)
		(layer "In1.Cu")
	)
	(gr_line
		(start 170.337988 -5.747004)
		(end 170.591988 -5.747004)
		(stroke
			(width 0.1016)
			(type default)
		)
		(layer "In1.Cu")
	)
	(gr_line
		(start 170.337988 -5.646928)
		(end 170.591988 -5.646928)
		(stroke
			(width 0.1016)
			(type default)
		)
		(layer "In1.Cu")
	)
	(gr_line
		(start 170.363388 -12.512548)
		(end 170.363388 -9.947148)
		(stroke
			(width 0.2032)
			(type default)
		)
		(layer "In1.Cu")
	)
	(gr_line
		(start 170.363388 -12.412472)
		(end 170.363388 -9.847072)
		(stroke
			(width 0.2032)
			(type default)
		)
		(layer "In1.Cu")
	)
	(gr_line
		(start 170.363388 -9.947148)
		(end 171.379388 -9.947148)
		(stroke
			(width 0.2032)
			(type default)
		)
		(layer "In1.Cu")
	)
	(gr_line
		(start 170.363388 -9.847072)
		(end 171.379388 -9.847072)
		(stroke
			(width 0.2032)
			(type default)
		)
		(layer "In1.Cu")
	)
	(gr_line
		(start 170.363388 -8.312404)
		(end 170.363388 -5.747004)
		(stroke
			(width 0.2032)
			(type default)
		)
		(layer "In1.Cu")
	)
	(gr_line
		(start 170.363388 -8.212328)
		(end 170.363388 -5.646928)
		(stroke
			(width 0.2032)
			(type default)
		)
		(layer "In1.Cu")
	)
	(gr_line
		(start 170.363388 -5.747004)
		(end 171.379388 -5.747004)
		(stroke
			(width 0.2032)
			(type default)
		)
		(layer "In1.Cu")
	)
	(gr_line
		(start 170.363388 -5.646928)
		(end 171.379388 -5.646928)
		(stroke
			(width 0.2032)
			(type default)
		)
		(layer "In1.Cu")
	)
	(gr_line
		(start 170.414188 -12.487148)
		(end 170.414188 -9.997948)
		(stroke
			(width 0.2032)
			(type default)
		)
		(layer "In1.Cu")
	)
	(gr_line
		(start 170.414188 -12.487148)
		(end 170.414188 -9.997948)
		(stroke
			(width 0.254)
			(type default)
		)
		(layer "In1.Cu")
	)
	(gr_line
		(start 170.414188 -12.387072)
		(end 170.414188 -9.897872)
		(stroke
			(width 0.2032)
			(type default)
		)
		(layer "In1.Cu")
	)
	(gr_line
		(start 170.414188 -12.387072)
		(end 170.414188 -9.897872)
		(stroke
			(width 0.254)
			(type default)
		)
		(layer "In1.Cu")
	)
	(gr_line
		(start 170.414188 -9.997948)
		(end 170.617388 -9.997948)
		(stroke
			(width 0.2032)
			(type default)
		)
		(layer "In1.Cu")
	)
	(gr_line
		(start 170.414188 -9.997948)
		(end 171.303188 -9.997948)
		(stroke
			(width 0.254)
			(type default)
		)
		(layer "In1.Cu")
	)
	(gr_line
		(start 170.414188 -9.897872)
		(end 170.617388 -9.897872)
		(stroke
			(width 0.2032)
			(type default)
		)
		(layer "In1.Cu")
	)
	(gr_line
		(start 170.414188 -9.897872)
		(end 171.303188 -9.897872)
		(stroke
			(width 0.254)
			(type default)
		)
		(layer "In1.Cu")
	)
	(gr_line
		(start 170.414188 -8.287004)
		(end 170.414188 -5.797804)
		(stroke
			(width 0.2032)
			(type default)
		)
		(layer "In1.Cu")
	)
	(gr_line
		(start 170.414188 -8.287004)
		(end 170.414188 -5.797804)
		(stroke
			(width 0.254)
			(type default)
		)
		(layer "In1.Cu")
	)
	(gr_line
		(start 170.414188 -8.186928)
		(end 170.414188 -5.697728)
		(stroke
			(width 0.2032)
			(type default)
		)
		(layer "In1.Cu")
	)
	(gr_line
		(start 170.414188 -8.186928)
		(end 170.414188 -5.697728)
		(stroke
			(width 0.254)
			(type default)
		)
		(layer "In1.Cu")
	)
	(gr_line
		(start 170.414188 -5.797804)
		(end 170.617388 -5.797804)
		(stroke
			(width 0.2032)
			(type default)
		)
		(layer "In1.Cu")
	)
	(gr_line
		(start 170.414188 -5.797804)
		(end 171.303188 -5.797804)
		(stroke
			(width 0.254)
			(type default)
		)
		(layer "In1.Cu")
	)
	(gr_line
		(start 170.414188 -5.697728)
		(end 170.617388 -5.697728)
		(stroke
			(width 0.2032)
			(type default)
		)
		(layer "In1.Cu")
	)
	(gr_line
		(start 170.414188 -5.697728)
		(end 171.303188 -5.697728)
		(stroke
			(width 0.254)
			(type default)
		)
		(layer "In1.Cu")
	)
	(gr_line
		(start 170.439588 -12.461748)
		(end 170.439588 -10.023348)
		(stroke
			(width 0.254)
			(type default)
		)
		(layer "In1.Cu")
	)
	(gr_line
		(start 170.439588 -12.361672)
		(end 170.439588 -9.923272)
		(stroke
			(width 0.254)
			(type default)
		)
		(layer "In1.Cu")
	)
	(gr_line
		(start 170.439588 -10.023348)
		(end 171.277788 -10.023348)
		(stroke
			(width 0.254)
			(type default)
		)
		(layer "In1.Cu")
	)
	(gr_line
		(start 170.439588 -9.923272)
		(end 171.277788 -9.923272)
		(stroke
			(width 0.254)
			(type default)
		)
		(layer "In1.Cu")
	)
	(gr_line
		(start 170.439588 -8.261604)
		(end 170.439588 -5.823204)
		(stroke
			(width 0.254)
			(type default)
		)
		(layer "In1.Cu")
	)
	(gr_line
		(start 170.439588 -8.161528)
		(end 170.439588 -5.723128)
		(stroke
			(width 0.254)
			(type default)
		)
		(layer "In1.Cu")
	)
	(gr_line
		(start 170.439588 -5.823204)
		(end 171.277788 -5.823204)
		(stroke
			(width 0.254)
			(type default)
		)
		(layer "In1.Cu")
	)
	(gr_line
		(start 170.439588 -5.723128)
		(end 171.277788 -5.723128)
		(stroke
			(width 0.254)
			(type default)
		)
		(layer "In1.Cu")
	)
	(gr_line
		(start 170.464988 -12.436348)
		(end 170.464988 -10.048748)
		(stroke
			(width 0.254)
			(type default)
		)
		(layer "In1.Cu")
	)
	(gr_line
		(start 170.464988 -12.336272)
		(end 170.464988 -9.948672)
		(stroke
			(width 0.254)
			(type default)
		)
		(layer "In1.Cu")
	)
	(gr_line
		(start 170.464988 -10.048748)
		(end 171.252388 -10.048748)
		(stroke
			(width 0.254)
			(type default)
		)
		(layer "In1.Cu")
	)
	(gr_line
		(start 170.464988 -9.948672)
		(end 171.252388 -9.948672)
		(stroke
			(width 0.254)
			(type default)
		)
		(layer "In1.Cu")
	)
	(gr_line
		(start 170.464988 -8.236204)
		(end 170.464988 -5.848604)
		(stroke
			(width 0.254)
			(type default)
		)
		(layer "In1.Cu")
	)
	(gr_line
		(start 170.464988 -8.136128)
		(end 170.464988 -5.748528)
		(stroke
			(width 0.254)
			(type default)
		)
		(layer "In1.Cu")
	)
	(gr_line
		(start 170.464988 -5.848604)
		(end 171.252388 -5.848604)
		(stroke
			(width 0.254)
			(type default)
		)
		(layer "In1.Cu")
	)
	(gr_line
		(start 170.464988 -5.748528)
		(end 171.252388 -5.748528)
		(stroke
			(width 0.254)
			(type default)
		)
		(layer "In1.Cu")
	)
	(gr_line
		(start 170.490388 -12.360148)
		(end 171.125388 -12.360148)
		(stroke
			(width 0.508)
			(type default)
		)
		(layer "In1.Cu")
	)
	(gr_line
		(start 170.490388 -12.260072)
		(end 171.125388 -12.260072)
		(stroke
			(width 0.508)
			(type default)
		)
		(layer "In1.Cu")
	)
	(gr_line
		(start 170.490388 -10.175748)
		(end 171.125388 -10.175748)
		(stroke
			(width 0.508)
			(type default)
		)
		(layer "In1.Cu")
	)
	(gr_line
		(start 170.490388 -10.124948)
		(end 171.125388 -10.124948)
		(stroke
			(width 0.508)
			(type default)
		)
		(layer "In1.Cu")
	)
	(gr_line
		(start 170.490388 -10.075672)
		(end 171.125388 -10.075672)
		(stroke
			(width 0.508)
			(type default)
		)
		(layer "In1.Cu")
	)
	(gr_line
		(start 170.490388 -10.024872)
		(end 171.125388 -10.024872)
		(stroke
			(width 0.508)
			(type default)
		)
		(layer "In1.Cu")
	)
	(gr_line
		(start 170.490388 -8.160004)
		(end 171.125388 -8.160004)
		(stroke
			(width 0.508)
			(type default)
		)
		(layer "In1.Cu")
	)
	(gr_line
		(start 170.490388 -8.059928)
		(end 171.125388 -8.059928)
		(stroke
			(width 0.508)
			(type default)
		)
		(layer "In1.Cu")
	)
	(gr_line
		(start 170.490388 -5.975604)
		(end 171.125388 -5.975604)
		(stroke
			(width 0.508)
			(type default)
		)
		(layer "In1.Cu")
	)
	(gr_line
		(start 170.490388 -5.924804)
		(end 171.125388 -5.924804)
		(stroke
			(width 0.508)
			(type default)
		)
		(layer "In1.Cu")
	)
	(gr_line
		(start 170.490388 -5.875528)
		(end 171.125388 -5.875528)
		(stroke
			(width 0.508)
			(type default)
		)
		(layer "In1.Cu")
	)
	(gr_line
		(start 170.490388 -5.824728)
		(end 171.125388 -5.824728)
		(stroke
			(width 0.508)
			(type default)
		)
		(layer "In1.Cu")
	)
	(gr_line
		(start 170.497246 -29.337)
		(end 171.335446 -29.337)
		(stroke
			(width 0.1016)
			(type default)
		)
		(layer "In1.Cu")
	)
	(gr_line
		(start 170.497246 -27.4828)
		(end 170.497246 -29.337)
		(stroke
			(width 0.1016)
			(type default)
		)
		(layer "In1.Cu")
	)
	(gr_line
		(start 170.515788 -10.429748)
		(end 171.150788 -10.429748)
		(stroke
			(width 0.508)
			(type default)
		)
		(layer "In1.Cu")
	)
	(gr_line
		(start 170.515788 -10.329672)
		(end 171.150788 -10.329672)
		(stroke
			(width 0.508)
			(type default)
		)
		(layer "In1.Cu")
	)
	(gr_line
		(start 170.515788 -6.229604)
		(end 171.150788 -6.229604)
		(stroke
			(width 0.508)
			(type default)
		)
		(layer "In1.Cu")
	)
	(gr_line
		(start 170.515788 -6.129528)
		(end 171.150788 -6.129528)
		(stroke
			(width 0.508)
			(type default)
		)
		(layer "In1.Cu")
	)
	(gr_line
		(start 170.541188 -12.385548)
		(end 170.541188 -10.124948)
		(stroke
			(width 0.254)
			(type default)
		)
		(layer "In1.Cu")
	)
	(gr_line
		(start 170.541188 -12.285472)
		(end 170.541188 -10.024872)
		(stroke
			(width 0.254)
			(type default)
		)
		(layer "In1.Cu")
	)
	(gr_line
		(start 170.541188 -12.233148)
		(end 171.176188 -12.233148)
		(stroke
			(width 0.508)
			(type default)
		)
		(layer "In1.Cu")
	)
	(gr_line
		(start 170.541188 -12.133072)
		(end 171.176188 -12.133072)
		(stroke
			(width 0.508)
			(type default)
		)
		(layer "In1.Cu")
	)
	(gr_line
		(start 170.541188 -10.124948)
		(end 171.176188 -10.124948)
		(stroke
			(width 0.254)
			(type default)
		)
		(layer "In1.Cu")
	)
	(gr_line
		(start 170.541188 -10.024872)
		(end 171.176188 -10.024872)
		(stroke
			(width 0.254)
			(type default)
		)
		(layer "In1.Cu")
	)
	(gr_line
		(start 170.541188 -8.185404)
		(end 170.541188 -5.924804)
		(stroke
			(width 0.254)
			(type default)
		)
		(layer "In1.Cu")
	)
	(gr_line
		(start 170.541188 -8.085328)
		(end 170.541188 -5.824728)
		(stroke
			(width 0.254)
			(type default)
		)
		(layer "In1.Cu")
	)
	(gr_line
		(start 170.541188 -8.033004)
		(end 171.176188 -8.033004)
		(stroke
			(width 0.508)
			(type default)
		)
		(layer "In1.Cu")
	)
	(gr_line
		(start 170.541188 -7.932928)
		(end 171.176188 -7.932928)
		(stroke
			(width 0.508)
			(type default)
		)
		(layer "In1.Cu")
	)
	(gr_line
		(start 170.541188 -5.924804)
		(end 171.176188 -5.924804)
		(stroke
			(width 0.254)
			(type default)
		)
		(layer "In1.Cu")
	)
	(gr_line
		(start 170.541188 -5.824728)
		(end 171.176188 -5.824728)
		(stroke
			(width 0.254)
			(type default)
		)
		(layer "In1.Cu")
	)
	(gr_line
		(start 170.548046 -29.2354)
		(end 170.548046 -27.559)
		(stroke
			(width 0.2032)
			(type default)
		)
		(layer "In1.Cu")
	)
	(gr_line
		(start 170.548046 -27.559)
		(end 171.614846 -27.559)
		(stroke
			(width 0.2032)
			(type default)
		)
		(layer "In1.Cu")
	)
	(gr_line
		(start 170.566588 -12.080748)
		(end 171.201588 -12.080748)
		(stroke
			(width 0.508)
			(type default)
		)
		(layer "In1.Cu")
	)
	(gr_line
		(start 170.566588 -11.980672)
		(end 171.201588 -11.980672)
		(stroke
			(width 0.508)
			(type default)
		)
		(layer "In1.Cu")
	)
	(gr_line
		(start 170.566588 -7.880604)
		(end 171.201588 -7.880604)
		(stroke
			(width 0.508)
			(type default)
		)
		(layer "In1.Cu")
	)
	(gr_line
		(start 170.566588 -7.780528)
		(end 171.201588 -7.780528)
		(stroke
			(width 0.508)
			(type default)
		)
		(layer "In1.Cu")
	)
	(gr_line
		(start 170.573446 -29.2608)
		(end 171.564046 -29.2608)
		(stroke
			(width 0.2032)
			(type default)
		)
		(layer "In1.Cu")
	)
	(gr_line
		(start 170.573446 -29.2354)
		(end 170.573446 -29.2608)
		(stroke
			(width 0.2032)
			(type default)
		)
		(layer "In1.Cu")
	)
	(gr_line
		(start 170.591988 -12.360148)
		(end 171.226988 -12.360148)
		(stroke
			(width 0.508)
			(type default)
		)
		(layer "In1.Cu")
	)
	(gr_line
		(start 170.591988 -12.260072)
		(end 171.226988 -12.260072)
		(stroke
			(width 0.508)
			(type default)
		)
		(layer "In1.Cu")
	)
	(gr_line
		(start 170.591988 -9.947148)
		(end 171.430188 -9.947148)
		(stroke
			(width 0.2032)
			(type default)
		)
		(layer "In1.Cu")
	)
	(gr_line
		(start 170.591988 -9.847072)
		(end 171.430188 -9.847072)
		(stroke
			(width 0.2032)
			(type default)
		)
		(layer "In1.Cu")
	)
	(gr_line
		(start 170.591988 -8.160004)
		(end 171.226988 -8.160004)
		(stroke
			(width 0.508)
			(type default)
		)
		(layer "In1.Cu")
	)
	(gr_line
		(start 170.591988 -8.059928)
		(end 171.226988 -8.059928)
		(stroke
			(width 0.508)
			(type default)
		)
		(layer "In1.Cu")
	)
	(gr_line
		(start 170.591988 -5.747004)
		(end 171.430188 -5.747004)
		(stroke
			(width 0.2032)
			(type default)
		)
		(layer "In1.Cu")
	)
	(gr_line
		(start 170.591988 -5.646928)
		(end 171.430188 -5.646928)
		(stroke
			(width 0.2032)
			(type default)
		)
		(layer "In1.Cu")
	)
	(gr_line
		(start 170.617388 -12.360148)
		(end 170.617388 -10.175748)
		(stroke
			(width 0.254)
			(type default)
		)
		(layer "In1.Cu")
	)
	(gr_line
		(start 170.617388 -12.260072)
		(end 170.617388 -10.075672)
		(stroke
			(width 0.254)
			(type default)
		)
		(layer "In1.Cu")
	)
	(gr_line
		(start 170.617388 -10.175748)
		(end 171.099988 -10.175748)
		(stroke
			(width 0.254)
			(type default)
		)
		(layer "In1.Cu")
	)
	(gr_line
		(start 170.617388 -10.075672)
		(end 171.099988 -10.075672)
		(stroke
			(width 0.254)
			(type default)
		)
		(layer "In1.Cu")
	)
	(gr_line
		(start 170.617388 -9.997948)
		(end 171.353988 -9.997948)
		(stroke
			(width 0.254)
			(type default)
		)
		(layer "In1.Cu")
	)
	(gr_line
		(start 170.617388 -9.897872)
		(end 171.353988 -9.897872)
		(stroke
			(width 0.254)
			(type default)
		)
		(layer "In1.Cu")
	)
	(gr_line
		(start 170.617388 -8.160004)
		(end 170.617388 -5.975604)
		(stroke
			(width 0.254)
			(type default)
		)
		(layer "In1.Cu")
	)
	(gr_line
		(start 170.617388 -8.059928)
		(end 170.617388 -5.875528)
		(stroke
			(width 0.254)
			(type default)
		)
		(layer "In1.Cu")
	)
	(gr_line
		(start 170.617388 -5.975604)
		(end 171.099988 -5.975604)
		(stroke
			(width 0.254)
			(type default)
		)
		(layer "In1.Cu")
	)
	(gr_line
		(start 170.617388 -5.875528)
		(end 171.099988 -5.875528)
		(stroke
			(width 0.254)
			(type default)
		)
		(layer "In1.Cu")
	)
	(gr_line
		(start 170.617388 -5.797804)
		(end 171.353988 -5.797804)
		(stroke
			(width 0.254)
			(type default)
		)
		(layer "In1.Cu")
	)
	(gr_line
		(start 170.617388 -5.697728)
		(end 171.353988 -5.697728)
		(stroke
			(width 0.254)
			(type default)
		)
		(layer "In1.Cu")
	)
	(gr_line
		(start 170.624246 -29.1846)
		(end 171.564046 -29.1846)
		(stroke
			(width 0.2032)
			(type default)
		)
		(layer "In1.Cu")
	)
	(gr_line
		(start 170.624246 -27.6098)
		(end 170.624246 -29.1846)
		(stroke
			(width 0.2032)
			(type default)
		)
		(layer "In1.Cu")
	)
	(gr_line
		(start 170.63593 -10.110978)
		(end 171.27093 -10.110978)
		(stroke
			(width 0.508)
			(type default)
		)
		(layer "In1.Cu")
	)
	(gr_line
		(start 170.63593 -10.010902)
		(end 171.27093 -10.010902)
		(stroke
			(width 0.508)
			(type default)
		)
		(layer "In1.Cu")
	)
	(gr_line
		(start 170.63593 -5.910834)
		(end 171.27093 -5.910834)
		(stroke
			(width 0.508)
			(type default)
		)
		(layer "In1.Cu")
	)
	(gr_line
		(start 170.63593 -5.810758)
		(end 171.27093 -5.810758)
		(stroke
			(width 0.508)
			(type default)
		)
		(layer "In1.Cu")
	)
	(gr_line
		(start 170.642788 -12.360148)
		(end 171.277788 -12.360148)
		(stroke
			(width 0.508)
			(type default)
		)
		(layer "In1.Cu")
	)
	(gr_line
		(start 170.642788 -12.260072)
		(end 171.277788 -12.260072)
		(stroke
			(width 0.508)
			(type default)
		)
		(layer "In1.Cu")
	)
	(gr_line
		(start 170.642788 -12.233148)
		(end 170.642788 -10.251948)
		(stroke
			(width 0.762)
			(type default)
		)
		(layer "In1.Cu")
	)
	(gr_line
		(start 170.642788 -12.133072)
		(end 170.642788 -10.151872)
		(stroke
			(width 0.762)
			(type default)
		)
		(layer "In1.Cu")
	)
	(gr_line
		(start 170.642788 -10.251948)
		(end 171.277788 -10.251948)
		(stroke
			(width 0.508)
			(type default)
		)
		(layer "In1.Cu")
	)
	(gr_line
		(start 170.642788 -10.151872)
		(end 171.277788 -10.151872)
		(stroke
			(width 0.508)
			(type default)
		)
		(layer "In1.Cu")
	)
	(gr_line
		(start 170.642788 -8.160004)
		(end 171.277788 -8.160004)
		(stroke
			(width 0.508)
			(type default)
		)
		(layer "In1.Cu")
	)
	(gr_line
		(start 170.642788 -8.059928)
		(end 171.277788 -8.059928)
		(stroke
			(width 0.508)
			(type default)
		)
		(layer "In1.Cu")
	)
	(gr_line
		(start 170.642788 -8.033004)
		(end 170.642788 -6.051804)
		(stroke
			(width 0.762)
			(type default)
		)
		(layer "In1.Cu")
	)
	(gr_line
		(start 170.642788 -7.932928)
		(end 170.642788 -5.951728)
		(stroke
			(width 0.762)
			(type default)
		)
		(layer "In1.Cu")
	)
	(gr_line
		(start 170.642788 -6.051804)
		(end 171.277788 -6.051804)
		(stroke
			(width 0.508)
			(type default)
		)
		(layer "In1.Cu")
	)
	(gr_line
		(start 170.642788 -5.951728)
		(end 171.277788 -5.951728)
		(stroke
			(width 0.508)
			(type default)
		)
		(layer "In1.Cu")
	)
	(gr_line
		(start 170.693588 -12.283948)
		(end 170.693588 -10.251948)
		(stroke
			(width 0.254)
			(type default)
		)
		(layer "In1.Cu")
	)
	(gr_line
		(start 170.693588 -12.183872)
		(end 170.693588 -10.151872)
		(stroke
			(width 0.254)
			(type default)
		)
		(layer "In1.Cu")
	)
	(gr_line
		(start 170.693588 -10.251948)
		(end 171.023788 -10.251948)
		(stroke
			(width 0.254)
			(type default)
		)
		(layer "In1.Cu")
	)
	(gr_line
		(start 170.693588 -10.151872)
		(end 171.023788 -10.151872)
		(stroke
			(width 0.254)
			(type default)
		)
		(layer "In1.Cu")
	)
	(gr_line
		(start 170.693588 -8.083804)
		(end 170.693588 -6.051804)
		(stroke
			(width 0.254)
			(type default)
		)
		(layer "In1.Cu")
	)
	(gr_line
		(start 170.693588 -7.983728)
		(end 170.693588 -5.951728)
		(stroke
			(width 0.254)
			(type default)
		)
		(layer "In1.Cu")
	)
	(gr_line
		(start 170.693588 -6.051804)
		(end 171.023788 -6.051804)
		(stroke
			(width 0.254)
			(type default)
		)
		(layer "In1.Cu")
	)
	(gr_line
		(start 170.693588 -5.951728)
		(end 171.023788 -5.951728)
		(stroke
			(width 0.254)
			(type default)
		)
		(layer "In1.Cu")
	)
	(gr_line
		(start 170.700446 -29.1084)
		(end 170.700446 -27.7622)
		(stroke
			(width 0.508)
			(type default)
		)
		(layer "In1.Cu")
	)
	(gr_line
		(start 170.725846 -29.1084)
		(end 171.386246 -29.1084)
		(stroke
			(width 0.508)
			(type default)
		)
		(layer "In1.Cu")
	)
	(gr_line
		(start 170.725846 -29.083)
		(end 170.725846 -27.7368)
		(stroke
			(width 0.508)
			(type default)
		)
		(layer "In1.Cu")
	)
	(gr_line
		(start 170.725846 -27.7114)
		(end 171.360846 -27.7114)
		(stroke
			(width 0.508)
			(type default)
		)
		(layer "In1.Cu")
	)
	(gr_line
		(start 170.751246 -29.083)
		(end 170.751246 -27.7368)
		(stroke
			(width 0.508)
			(type default)
		)
		(layer "In1.Cu")
	)
	(gr_line
		(start 170.776646 -29.083)
		(end 170.776646 -27.7368)
		(stroke
			(width 0.508)
			(type default)
		)
		(layer "In1.Cu")
	)
	(gr_line
		(start 170.795188 -12.207748)
		(end 170.795188 -10.404348)
		(stroke
			(width 0.254)
			(type default)
		)
		(layer "In1.Cu")
	)
	(gr_line
		(start 170.795188 -12.207748)
		(end 170.795188 -10.226548)
		(stroke
			(width 0.762)
			(type default)
		)
		(layer "In1.Cu")
	)
	(gr_line
		(start 170.795188 -12.107672)
		(end 170.795188 -10.304272)
		(stroke
			(width 0.254)
			(type default)
		)
		(layer "In1.Cu")
	)
	(gr_line
		(start 170.795188 -12.107672)
		(end 170.795188 -10.126472)
		(stroke
			(width 0.762)
			(type default)
		)
		(layer "In1.Cu")
	)
	(gr_line
		(start 170.795188 -10.404348)
		(end 170.896788 -10.404348)
		(stroke
			(width 0.254)
			(type default)
		)
		(layer "In1.Cu")
	)
	(gr_line
		(start 170.795188 -10.304272)
		(end 170.896788 -10.304272)
		(stroke
			(width 0.254)
			(type default)
		)
		(layer "In1.Cu")
	)
	(gr_line
		(start 170.795188 -8.007604)
		(end 170.795188 -6.204204)
		(stroke
			(width 0.254)
			(type default)
		)
		(layer "In1.Cu")
	)
	(gr_line
		(start 170.795188 -8.007604)
		(end 170.795188 -6.026404)
		(stroke
			(width 0.762)
			(type default)
		)
		(layer "In1.Cu")
	)
	(gr_line
		(start 170.795188 -7.907528)
		(end 170.795188 -6.104128)
		(stroke
			(width 0.254)
			(type default)
		)
		(layer "In1.Cu")
	)
	(gr_line
		(start 170.795188 -7.907528)
		(end 170.795188 -5.926328)
		(stroke
			(width 0.762)
			(type default)
		)
		(layer "In1.Cu")
	)
	(gr_line
		(start 170.795188 -6.204204)
		(end 170.896788 -6.204204)
		(stroke
			(width 0.254)
			(type default)
		)
		(layer "In1.Cu")
	)
	(gr_line
		(start 170.795188 -6.104128)
		(end 170.896788 -6.104128)
		(stroke
			(width 0.254)
			(type default)
		)
		(layer "In1.Cu")
	)
	(gr_line
		(start 170.827446 -29.1084)
		(end 170.827446 -27.7622)
		(stroke
			(width 0.508)
			(type default)
		)
		(layer "In1.Cu")
	)
	(gr_line
		(start 170.827446 -29.083)
		(end 170.827446 -27.7368)
		(stroke
			(width 0.508)
			(type default)
		)
		(layer "In1.Cu")
	)
	(gr_line
		(start 170.878246 -29.083)
		(end 170.878246 -27.7368)
		(stroke
			(width 0.508)
			(type default)
		)
		(layer "In1.Cu")
	)
	(gr_line
		(start 170.896788 -12.309348)
		(end 170.845988 -12.309348)
		(stroke
			(width 0.254)
			(type default)
		)
		(layer "In1.Cu")
	)
	(gr_line
		(start 170.896788 -12.209272)
		(end 170.845988 -12.209272)
		(stroke
			(width 0.254)
			(type default)
		)
		(layer "In1.Cu")
	)
	(gr_line
		(start 170.896788 -10.404348)
		(end 170.896788 -12.309348)
		(stroke
			(width 0.254)
			(type default)
		)
		(layer "In1.Cu")
	)
	(gr_line
		(start 170.896788 -10.304272)
		(end 170.896788 -12.209272)
		(stroke
			(width 0.254)
			(type default)
		)
		(layer "In1.Cu")
	)
	(gr_line
		(start 170.896788 -8.109204)
		(end 170.845988 -8.109204)
		(stroke
			(width 0.254)
			(type default)
		)
		(layer "In1.Cu")
	)
	(gr_line
		(start 170.896788 -8.009128)
		(end 170.845988 -8.009128)
		(stroke
			(width 0.254)
			(type default)
		)
		(layer "In1.Cu")
	)
	(gr_line
		(start 170.896788 -6.204204)
		(end 170.896788 -8.109204)
		(stroke
			(width 0.254)
			(type default)
		)
		(layer "In1.Cu")
	)
	(gr_line
		(start 170.896788 -6.104128)
		(end 170.896788 -8.009128)
		(stroke
			(width 0.254)
			(type default)
		)
		(layer "In1.Cu")
	)
	(gr_line
		(start 170.897296 -26.826972)
		(end 171.735496 -26.826972)
		(stroke
			(width 0.1016)
			(type default)
		)
		(layer "In1.Cu")
	)
	(gr_line
		(start 170.897296 -24.972772)
		(end 170.897296 -26.826972)
		(stroke
			(width 0.1016)
			(type default)
		)
		(layer "In1.Cu")
	)
	(gr_line
		(start 170.903646 -29.0576)
		(end 170.903646 -27.7114)
		(stroke
			(width 0.508)
			(type default)
		)
		(layer "In1.Cu")
	)
	(gr_line
		(start 170.929046 -29.083)
		(end 170.929046 -27.7368)
		(stroke
			(width 0.508)
			(type default)
		)
		(layer "In1.Cu")
	)
	(gr_line
		(start 170.947588 -12.233148)
		(end 170.947588 -10.251948)
		(stroke
			(width 0.762)
			(type default)
		)
		(layer "In1.Cu")
	)
	(gr_line
		(start 170.947588 -12.133072)
		(end 170.947588 -10.151872)
		(stroke
			(width 0.762)
			(type default)
		)
		(layer "In1.Cu")
	)
	(gr_line
		(start 170.947588 -8.033004)
		(end 170.947588 -6.051804)
		(stroke
			(width 0.762)
			(type default)
		)
		(layer "In1.Cu")
	)
	(gr_line
		(start 170.947588 -7.932928)
		(end 170.947588 -5.951728)
		(stroke
			(width 0.762)
			(type default)
		)
		(layer "In1.Cu")
	)
	(gr_line
		(start 170.948096 -26.725372)
		(end 170.948096 -25.048972)
		(stroke
			(width 0.2032)
			(type default)
		)
		(layer "In1.Cu")
	)
	(gr_line
		(start 170.948096 -25.048972)
		(end 172.014896 -25.048972)
		(stroke
			(width 0.2032)
			(type default)
		)
		(layer "In1.Cu")
	)
	(gr_line
		(start 170.954446 -29.083)
		(end 170.954446 -27.7368)
		(stroke
			(width 0.508)
			(type default)
		)
		(layer "In1.Cu")
	)
	(gr_line
		(start 170.973496 -26.750772)
		(end 171.964096 -26.750772)
		(stroke
			(width 0.2032)
			(type default)
		)
		(layer "In1.Cu")
	)
	(gr_line
		(start 170.973496 -26.725372)
		(end 170.973496 -26.750772)
		(stroke
			(width 0.2032)
			(type default)
		)
		(layer "In1.Cu")
	)
	(gr_line
		(start 170.979846 -29.083)
		(end 170.979846 -27.7368)
		(stroke
			(width 0.508)
			(type default)
		)
		(layer "In1.Cu")
	)
	(gr_line
		(start 171.023788 -12.207748)
		(end 170.795188 -12.207748)
		(stroke
			(width 0.254)
			(type default)
		)
		(layer "In1.Cu")
	)
	(gr_line
		(start 171.023788 -12.107672)
		(end 170.795188 -12.107672)
		(stroke
			(width 0.254)
			(type default)
		)
		(layer "In1.Cu")
	)
	(gr_line
		(start 171.023788 -10.251948)
		(end 171.023788 -12.207748)
		(stroke
			(width 0.254)
			(type default)
		)
		(layer "In1.Cu")
	)
	(gr_line
		(start 171.023788 -10.151872)
		(end 171.023788 -12.107672)
		(stroke
			(width 0.254)
			(type default)
		)
		(layer "In1.Cu")
	)
	(gr_line
		(start 171.023788 -8.007604)
		(end 170.795188 -8.007604)
		(stroke
			(width 0.254)
			(type default)
		)
		(layer "In1.Cu")
	)
	(gr_line
		(start 171.023788 -7.907528)
		(end 170.795188 -7.907528)
		(stroke
			(width 0.254)
			(type default)
		)
		(layer "In1.Cu")
	)
	(gr_line
		(start 171.023788 -6.051804)
		(end 171.023788 -8.007604)
		(stroke
			(width 0.254)
			(type default)
		)
		(layer "In1.Cu")
	)
	(gr_line
		(start 171.023788 -5.951728)
		(end 171.023788 -7.907528)
		(stroke
			(width 0.254)
			(type default)
		)
		(layer "In1.Cu")
	)
	(gr_line
		(start 171.024296 -26.674572)
		(end 171.964096 -26.674572)
		(stroke
			(width 0.2032)
			(type default)
		)
		(layer "In1.Cu")
	)
	(gr_line
		(start 171.024296 -25.099772)
		(end 171.024296 -26.674572)
		(stroke
			(width 0.2032)
			(type default)
		)
		(layer "In1.Cu")
	)
	(gr_line
		(start 171.030646 -29.083)
		(end 171.030646 -27.7368)
		(stroke
			(width 0.508)
			(type default)
		)
		(layer "In1.Cu")
	)
	(gr_line
		(start 171.056046 -29.083)
		(end 171.056046 -27.7368)
		(stroke
			(width 0.508)
			(type default)
		)
		(layer "In1.Cu")
	)
	(gr_line
		(start 171.074588 -12.563348)
		(end 171.074588 -12.512548)
		(stroke
			(width 0.1016)
			(type default)
		)
		(layer "In1.Cu")
	)
	(gr_line
		(start 171.074588 -12.563348)
		(end 171.480988 -12.563348)
		(stroke
			(width 0.1016)
			(type default)
		)
		(layer "In1.Cu")
	)
	(gr_line
		(start 171.074588 -12.512548)
		(end 170.312588 -12.512548)
		(stroke
			(width 0.1016)
			(type default)
		)
		(layer "In1.Cu")
	)
	(gr_line
		(start 171.074588 -12.463272)
		(end 171.074588 -12.412472)
		(stroke
			(width 0.1016)
			(type default)
		)
		(layer "In1.Cu")
	)
	(gr_line
		(start 171.074588 -12.463272)
		(end 171.480988 -12.463272)
		(stroke
			(width 0.1016)
			(type default)
		)
		(layer "In1.Cu")
	)
	(gr_line
		(start 171.074588 -12.412472)
		(end 170.312588 -12.412472)
		(stroke
			(width 0.1016)
			(type default)
		)
		(layer "In1.Cu")
	)
	(gr_line
		(start 171.074588 -12.233148)
		(end 171.074588 -10.251948)
		(stroke
			(width 0.762)
			(type default)
		)
		(layer "In1.Cu")
	)
	(gr_line
		(start 171.074588 -12.133072)
		(end 171.074588 -10.151872)
		(stroke
			(width 0.762)
			(type default)
		)
		(layer "In1.Cu")
	)
	(gr_line
		(start 171.074588 -8.363204)
		(end 171.074588 -8.312404)
		(stroke
			(width 0.1016)
			(type default)
		)
		(layer "In1.Cu")
	)
	(gr_line
		(start 171.074588 -8.363204)
		(end 171.480988 -8.363204)
		(stroke
			(width 0.1016)
			(type default)
		)
		(layer "In1.Cu")
	)
	(gr_line
		(start 171.074588 -8.312404)
		(end 170.312588 -8.312404)
		(stroke
			(width 0.1016)
			(type default)
		)
		(layer "In1.Cu")
	)
	(gr_line
		(start 171.074588 -8.263128)
		(end 171.074588 -8.212328)
		(stroke
			(width 0.1016)
			(type default)
		)
		(layer "In1.Cu")
	)
	(gr_line
		(start 171.074588 -8.263128)
		(end 171.480988 -8.263128)
		(stroke
			(width 0.1016)
			(type default)
		)
		(layer "In1.Cu")
	)
	(gr_line
		(start 171.074588 -8.212328)
		(end 170.312588 -8.212328)
		(stroke
			(width 0.1016)
			(type default)
		)
		(layer "In1.Cu")
	)
	(gr_line
		(start 171.074588 -8.033004)
		(end 171.074588 -6.051804)
		(stroke
			(width 0.762)
			(type default)
		)
		(layer "In1.Cu")
	)
	(gr_line
		(start 171.074588 -7.932928)
		(end 171.074588 -5.951728)
		(stroke
			(width 0.762)
			(type default)
		)
		(layer "In1.Cu")
	)
	(gr_line
		(start 171.081446 -29.083)
		(end 171.081446 -27.7368)
		(stroke
			(width 0.508)
			(type default)
		)
		(layer "In1.Cu")
	)
	(gr_line
		(start 171.099988 -12.283948)
		(end 170.693588 -12.283948)
		(stroke
			(width 0.254)
			(type default)
		)
		(layer "In1.Cu")
	)
	(gr_line
		(start 171.099988 -12.183872)
		(end 170.693588 -12.183872)
		(stroke
			(width 0.254)
			(type default)
		)
		(layer "In1.Cu")
	)
	(gr_line
		(start 171.099988 -10.175748)
		(end 171.099988 -12.283948)
		(stroke
			(width 0.254)
			(type default)
		)
		(layer "In1.Cu")
	)
	(gr_line
		(start 171.099988 -10.075672)
		(end 171.099988 -12.183872)
		(stroke
			(width 0.254)
			(type default)
		)
		(layer "In1.Cu")
	)
	(gr_line
		(start 171.099988 -8.083804)
		(end 170.693588 -8.083804)
		(stroke
			(width 0.254)
			(type default)
		)
		(layer "In1.Cu")
	)
	(gr_line
		(start 171.099988 -7.983728)
		(end 170.693588 -7.983728)
		(stroke
			(width 0.254)
			(type default)
		)
		(layer "In1.Cu")
	)
	(gr_line
		(start 171.099988 -5.975604)
		(end 171.099988 -8.083804)
		(stroke
			(width 0.254)
			(type default)
		)
		(layer "In1.Cu")
	)
	(gr_line
		(start 171.099988 -5.875528)
		(end 171.099988 -7.983728)
		(stroke
			(width 0.254)
			(type default)
		)
		(layer "In1.Cu")
	)
	(gr_line
		(start 171.100496 -26.598372)
		(end 171.100496 -25.252172)
		(stroke
			(width 0.508)
			(type default)
		)
		(layer "In1.Cu")
	)
	(gr_line
		(start 171.106846 -29.083)
		(end 171.106846 -27.7368)
		(stroke
			(width 0.508)
			(type default)
		)
		(layer "In1.Cu")
	)
	(gr_line
		(start 171.125896 -26.598372)
		(end 171.786296 -26.598372)
		(stroke
			(width 0.508)
			(type default)
		)
		(layer "In1.Cu")
	)
	(gr_line
		(start 171.125896 -26.572972)
		(end 171.125896 -25.226772)
		(stroke
			(width 0.508)
			(type default)
		)
		(layer "In1.Cu")
	)
	(gr_line
		(start 171.125896 -25.201372)
		(end 171.760896 -25.201372)
		(stroke
			(width 0.508)
			(type default)
		)
		(layer "In1.Cu")
	)
	(gr_line
		(start 171.132246 -29.1084)
		(end 171.132246 -27.7622)
		(stroke
			(width 0.508)
			(type default)
		)
		(layer "In1.Cu")
	)
	(gr_line
		(start 171.150788 -12.233148)
		(end 171.150788 -10.251948)
		(stroke
			(width 0.762)
			(type default)
		)
		(layer "In1.Cu")
	)
	(gr_line
		(start 171.150788 -12.133072)
		(end 171.150788 -10.151872)
		(stroke
			(width 0.762)
			(type default)
		)
		(layer "In1.Cu")
	)
	(gr_line
		(start 171.150788 -8.033004)
		(end 171.150788 -6.051804)
		(stroke
			(width 0.762)
			(type default)
		)
		(layer "In1.Cu")
	)
	(gr_line
		(start 171.150788 -7.932928)
		(end 171.150788 -5.951728)
		(stroke
			(width 0.762)
			(type default)
		)
		(layer "In1.Cu")
	)
	(gr_line
		(start 171.151296 -26.572972)
		(end 171.151296 -25.226772)
		(stroke
			(width 0.508)
			(type default)
		)
		(layer "In1.Cu")
	)
	(gr_line
		(start 171.157646 -29.1084)
		(end 171.157646 -27.7622)
		(stroke
			(width 0.508)
			(type default)
		)
		(layer "In1.Cu")
	)
	(gr_line
		(start 171.157646 -29.083)
		(end 171.157646 -27.7368)
		(stroke
			(width 0.508)
			(type default)
		)
		(layer "In1.Cu")
	)
	(gr_line
		(start 171.176188 -12.360148)
		(end 170.617388 -12.360148)
		(stroke
			(width 0.254)
			(type default)
		)
		(layer "In1.Cu")
	)
	(gr_line
		(start 171.176188 -12.260072)
		(end 170.617388 -12.260072)
		(stroke
			(width 0.254)
			(type default)
		)
		(layer "In1.Cu")
	)
	(gr_line
		(start 171.176188 -10.124948)
		(end 171.176188 -12.360148)
		(stroke
			(width 0.254)
			(type default)
		)
		(layer "In1.Cu")
	)
	(gr_line
		(start 171.176188 -10.024872)
		(end 171.176188 -12.260072)
		(stroke
			(width 0.254)
			(type default)
		)
		(layer "In1.Cu")
	)
	(gr_line
		(start 171.176188 -8.160004)
		(end 170.617388 -8.160004)
		(stroke
			(width 0.254)
			(type default)
		)
		(layer "In1.Cu")
	)
	(gr_line
		(start 171.176188 -8.059928)
		(end 170.617388 -8.059928)
		(stroke
			(width 0.254)
			(type default)
		)
		(layer "In1.Cu")
	)
	(gr_line
		(start 171.176188 -5.924804)
		(end 171.176188 -8.160004)
		(stroke
			(width 0.254)
			(type default)
		)
		(layer "In1.Cu")
	)
	(gr_line
		(start 171.176188 -5.824728)
		(end 171.176188 -8.059928)
		(stroke
			(width 0.254)
			(type default)
		)
		(layer "In1.Cu")
	)
	(gr_line
		(start 171.176696 -26.572972)
		(end 171.176696 -25.226772)
		(stroke
			(width 0.508)
			(type default)
		)
		(layer "In1.Cu")
	)
	(gr_line
		(start 171.183046 -29.083)
		(end 171.183046 -27.7368)
		(stroke
			(width 0.508)
			(type default)
		)
		(layer "In1.Cu")
	)
	(gr_line
		(start 171.208446 -29.083)
		(end 171.208446 -27.7368)
		(stroke
			(width 0.508)
			(type default)
		)
		(layer "In1.Cu")
	)
	(gr_line
		(start 171.227496 -26.598372)
		(end 171.227496 -25.252172)
		(stroke
			(width 0.508)
			(type default)
		)
		(layer "In1.Cu")
	)
	(gr_line
		(start 171.227496 -26.572972)
		(end 171.227496 -25.226772)
		(stroke
			(width 0.508)
			(type default)
		)
		(layer "In1.Cu")
	)
	(gr_line
		(start 171.233846 -29.083)
		(end 171.233846 -27.7368)
		(stroke
			(width 0.508)
			(type default)
		)
		(layer "In1.Cu")
	)
	(gr_line
		(start 171.252388 -12.385548)
		(end 170.541188 -12.385548)
		(stroke
			(width 0.254)
			(type default)
		)
		(layer "In1.Cu")
	)
	(gr_line
		(start 171.252388 -12.285472)
		(end 170.541188 -12.285472)
		(stroke
			(width 0.254)
			(type default)
		)
		(layer "In1.Cu")
	)
	(gr_line
		(start 171.252388 -10.048748)
		(end 171.252388 -12.385548)
		(stroke
			(width 0.254)
			(type default)
		)
		(layer "In1.Cu")
	)
	(gr_line
		(start 171.252388 -9.948672)
		(end 171.252388 -12.285472)
		(stroke
			(width 0.254)
			(type default)
		)
		(layer "In1.Cu")
	)
	(gr_line
		(start 171.252388 -8.185404)
		(end 170.541188 -8.185404)
		(stroke
			(width 0.254)
			(type default)
		)
		(layer "In1.Cu")
	)
	(gr_line
		(start 171.252388 -8.085328)
		(end 170.541188 -8.085328)
		(stroke
			(width 0.254)
			(type default)
		)
		(layer "In1.Cu")
	)
	(gr_line
		(start 171.252388 -5.848604)
		(end 171.252388 -8.185404)
		(stroke
			(width 0.254)
			(type default)
		)
		(layer "In1.Cu")
	)
	(gr_line
		(start 171.252388 -5.748528)
		(end 171.252388 -8.085328)
		(stroke
			(width 0.254)
			(type default)
		)
		(layer "In1.Cu")
	)
	(gr_line
		(start 171.259246 -29.1084)
		(end 171.259246 -27.7622)
		(stroke
			(width 0.508)
			(type default)
		)
		(layer "In1.Cu")
	)
	(gr_line
		(start 171.259246 -29.083)
		(end 171.259246 -27.7368)
		(stroke
			(width 0.508)
			(type default)
		)
		(layer "In1.Cu")
	)
	(gr_line
		(start 171.277788 -12.512548)
		(end 170.287188 -12.512548)
		(stroke
			(width 0.1016)
			(type default)
		)
		(layer "In1.Cu")
	)
	(gr_line
		(start 171.277788 -12.436348)
		(end 170.464988 -12.436348)
		(stroke
			(width 0.254)
			(type default)
		)
		(layer "In1.Cu")
	)
	(gr_line
		(start 171.277788 -12.412472)
		(end 170.287188 -12.412472)
		(stroke
			(width 0.1016)
			(type default)
		)
		(layer "In1.Cu")
	)
	(gr_line
		(start 171.277788 -12.336272)
		(end 170.464988 -12.336272)
		(stroke
			(width 0.254)
			(type default)
		)
		(layer "In1.Cu")
	)
	(gr_line
		(start 171.277788 -10.023348)
		(end 171.277788 -12.436348)
		(stroke
			(width 0.254)
			(type default)
		)
		(layer "In1.Cu")
	)
	(gr_line
		(start 171.277788 -9.923272)
		(end 171.277788 -12.336272)
		(stroke
			(width 0.254)
			(type default)
		)
		(layer "In1.Cu")
	)
	(gr_line
		(start 171.277788 -8.312404)
		(end 170.287188 -8.312404)
		(stroke
			(width 0.1016)
			(type default)
		)
		(layer "In1.Cu")
	)
	(gr_line
		(start 171.277788 -8.236204)
		(end 170.464988 -8.236204)
		(stroke
			(width 0.254)
			(type default)
		)
		(layer "In1.Cu")
	)
	(gr_line
		(start 171.277788 -8.212328)
		(end 170.287188 -8.212328)
		(stroke
			(width 0.1016)
			(type default)
		)
		(layer "In1.Cu")
	)
	(gr_line
		(start 171.277788 -8.136128)
		(end 170.464988 -8.136128)
		(stroke
			(width 0.254)
			(type default)
		)
		(layer "In1.Cu")
	)
	(gr_line
		(start 171.277788 -5.823204)
		(end 171.277788 -8.236204)
		(stroke
			(width 0.254)
			(type default)
		)
		(layer "In1.Cu")
	)
	(gr_line
		(start 171.277788 -5.723128)
		(end 171.277788 -8.136128)
		(stroke
			(width 0.254)
			(type default)
		)
		(layer "In1.Cu")
	)
	(gr_line
		(start 171.278296 -26.572972)
		(end 171.278296 -25.226772)
		(stroke
			(width 0.508)
			(type default)
		)
		(layer "In1.Cu")
	)
	(gr_line
		(start 171.284646 -29.1084)
		(end 171.284646 -27.7622)
		(stroke
			(width 0.508)
			(type default)
		)
		(layer "In1.Cu")
	)
	(gr_line
		(start 171.284646 -29.083)
		(end 171.284646 -27.7368)
		(stroke
			(width 0.508)
			(type default)
		)
		(layer "In1.Cu")
	)
	(gr_line
		(start 171.303188 -12.461748)
		(end 170.439588 -12.461748)
		(stroke
			(width 0.254)
			(type default)
		)
		(layer "In1.Cu")
	)
	(gr_line
		(start 171.303188 -12.361672)
		(end 170.439588 -12.361672)
		(stroke
			(width 0.254)
			(type default)
		)
		(layer "In1.Cu")
	)
	(gr_line
		(start 171.303188 -9.997948)
		(end 171.303188 -12.461748)
		(stroke
			(width 0.254)
			(type default)
		)
		(layer "In1.Cu")
	)
	(gr_line
		(start 171.303188 -9.897872)
		(end 171.303188 -12.361672)
		(stroke
			(width 0.254)
			(type default)
		)
		(layer "In1.Cu")
	)
	(gr_line
		(start 171.303188 -8.261604)
		(end 170.439588 -8.261604)
		(stroke
			(width 0.254)
			(type default)
		)
		(layer "In1.Cu")
	)
	(gr_line
		(start 171.303188 -8.161528)
		(end 170.439588 -8.161528)
		(stroke
			(width 0.254)
			(type default)
		)
		(layer "In1.Cu")
	)
	(gr_line
		(start 171.303188 -5.797804)
		(end 171.303188 -8.261604)
		(stroke
			(width 0.254)
			(type default)
		)
		(layer "In1.Cu")
	)
	(gr_line
		(start 171.303188 -5.697728)
		(end 171.303188 -8.161528)
		(stroke
			(width 0.254)
			(type default)
		)
		(layer "In1.Cu")
	)
	(gr_line
		(start 171.303696 -26.547572)
		(end 171.303696 -25.201372)
		(stroke
			(width 0.508)
			(type default)
		)
		(layer "In1.Cu")
	)
	(gr_line
		(start 171.310046 -29.1084)
		(end 171.310046 -27.7622)
		(stroke
			(width 0.508)
			(type default)
		)
		(layer "In1.Cu")
	)
	(gr_line
		(start 171.329096 -26.572972)
		(end 171.329096 -25.226772)
		(stroke
			(width 0.508)
			(type default)
		)
		(layer "In1.Cu")
	)
	(gr_line
		(start 171.335446 -29.337)
		(end 171.665646 -29.337)
		(stroke
			(width 0.1016)
			(type default)
		)
		(layer "In1.Cu")
	)
	(gr_line
		(start 171.335446 -29.083)
		(end 171.335446 -27.7368)
		(stroke
			(width 0.508)
			(type default)
		)
		(layer "In1.Cu")
	)
	(gr_line
		(start 171.353988 -12.487148)
		(end 170.414188 -12.487148)
		(stroke
			(width 0.254)
			(type default)
		)
		(layer "In1.Cu")
	)
	(gr_line
		(start 171.353988 -12.387072)
		(end 170.414188 -12.387072)
		(stroke
			(width 0.254)
			(type default)
		)
		(layer "In1.Cu")
	)
	(gr_line
		(start 171.353988 -9.997948)
		(end 171.353988 -12.487148)
		(stroke
			(width 0.254)
			(type default)
		)
		(layer "In1.Cu")
	)
	(gr_line
		(start 171.353988 -9.897872)
		(end 171.353988 -12.387072)
		(stroke
			(width 0.254)
			(type default)
		)
		(layer "In1.Cu")
	)
	(gr_line
		(start 171.353988 -8.287004)
		(end 170.414188 -8.287004)
		(stroke
			(width 0.254)
			(type default)
		)
		(layer "In1.Cu")
	)
	(gr_line
		(start 171.353988 -8.186928)
		(end 170.414188 -8.186928)
		(stroke
			(width 0.254)
			(type default)
		)
		(layer "In1.Cu")
	)
	(gr_line
		(start 171.353988 -5.797804)
		(end 171.353988 -8.287004)
		(stroke
			(width 0.254)
			(type default)
		)
		(layer "In1.Cu")
	)
	(gr_line
		(start 171.353988 -5.697728)
		(end 171.353988 -8.186928)
		(stroke
			(width 0.254)
			(type default)
		)
		(layer "In1.Cu")
	)
	(gr_line
		(start 171.354496 -26.572972)
		(end 171.354496 -25.226772)
		(stroke
			(width 0.508)
			(type default)
		)
		(layer "In1.Cu")
	)
	(gr_line
		(start 171.360846 -29.1084)
		(end 171.360846 -27.7622)
		(stroke
			(width 0.508)
			(type default)
		)
		(layer "In1.Cu")
	)
	(gr_line
		(start 171.360846 -29.083)
		(end 171.360846 -27.7368)
		(stroke
			(width 0.508)
			(type default)
		)
		(layer "In1.Cu")
	)
	(gr_line
		(start 171.379388 -12.487148)
		(end 170.414188 -12.487148)
		(stroke
			(width 0.2032)
			(type default)
		)
		(layer "In1.Cu")
	)
	(gr_line
		(start 171.379388 -12.387072)
		(end 170.414188 -12.387072)
		(stroke
			(width 0.2032)
			(type default)
		)
		(layer "In1.Cu")
	)
	(gr_line
		(start 171.379388 -9.947148)
		(end 171.379388 -12.487148)
		(stroke
			(width 0.2032)
			(type default)
		)
		(layer "In1.Cu")
	)
	(gr_line
		(start 171.379388 -9.847072)
		(end 171.379388 -12.387072)
		(stroke
			(width 0.2032)
			(type default)
		)
		(layer "In1.Cu")
	)
	(gr_line
		(start 171.379388 -8.287004)
		(end 170.414188 -8.287004)
		(stroke
			(width 0.2032)
			(type default)
		)
		(layer "In1.Cu")
	)
	(gr_line
		(start 171.379388 -8.186928)
		(end 170.414188 -8.186928)
		(stroke
			(width 0.2032)
			(type default)
		)
		(layer "In1.Cu")
	)
	(gr_line
		(start 171.379388 -5.747004)
		(end 171.379388 -8.287004)
		(stroke
			(width 0.2032)
			(type default)
		)
		(layer "In1.Cu")
	)
	(gr_line
		(start 171.379388 -5.646928)
		(end 171.379388 -8.186928)
		(stroke
			(width 0.2032)
			(type default)
		)
		(layer "In1.Cu")
	)
	(gr_line
		(start 171.379896 -26.572972)
		(end 171.379896 -25.226772)
		(stroke
			(width 0.508)
			(type default)
		)
		(layer "In1.Cu")
	)
	(gr_line
		(start 171.386246 -29.1084)
		(end 171.386246 -27.7622)
		(stroke
			(width 0.508)
			(type default)
		)
		(layer "In1.Cu")
	)
	(gr_line
		(start 171.430188 -12.512548)
		(end 170.363388 -12.512548)
		(stroke
			(width 0.2032)
			(type default)
		)
		(layer "In1.Cu")
	)
	(gr_line
		(start 171.430188 -12.412472)
		(end 170.363388 -12.412472)
		(stroke
			(width 0.2032)
			(type default)
		)
		(layer "In1.Cu")
	)
	(gr_line
		(start 171.430188 -9.947148)
		(end 171.430188 -12.512548)
		(stroke
			(width 0.2032)
			(type default)
		)
		(layer "In1.Cu")
	)
	(gr_line
		(start 171.430188 -9.847072)
		(end 171.430188 -12.412472)
		(stroke
			(width 0.2032)
			(type default)
		)
		(layer "In1.Cu")
	)
	(gr_line
		(start 171.430188 -8.312404)
		(end 170.363388 -8.312404)
		(stroke
			(width 0.2032)
			(type default)
		)
		(layer "In1.Cu")
	)
	(gr_line
		(start 171.430188 -8.212328)
		(end 170.363388 -8.212328)
		(stroke
			(width 0.2032)
			(type default)
		)
		(layer "In1.Cu")
	)
	(gr_line
		(start 171.430188 -5.747004)
		(end 171.430188 -8.312404)
		(stroke
			(width 0.2032)
			(type default)
		)
		(layer "In1.Cu")
	)
	(gr_line
		(start 171.430188 -5.646928)
		(end 171.430188 -8.212328)
		(stroke
			(width 0.2032)
			(type default)
		)
		(layer "In1.Cu")
	)
	(gr_line
		(start 171.430696 -26.572972)
		(end 171.430696 -25.226772)
		(stroke
			(width 0.508)
			(type default)
		)
		(layer "In1.Cu")
	)
	(gr_line
		(start 171.455588 -12.512548)
		(end 170.337988 -12.512548)
		(stroke
			(width 0.1016)
			(type default)
		)
		(layer "In1.Cu")
	)
	(gr_line
		(start 171.455588 -12.412472)
		(end 170.337988 -12.412472)
		(stroke
			(width 0.1016)
			(type default)
		)
		(layer "In1.Cu")
	)
	(gr_line
		(start 171.455588 -9.921748)
		(end 171.455588 -12.512548)
		(stroke
			(width 0.1016)
			(type default)
		)
		(layer "In1.Cu")
	)
	(gr_line
		(start 171.455588 -9.821672)
		(end 171.455588 -12.412472)
		(stroke
			(width 0.1016)
			(type default)
		)
		(layer "In1.Cu")
	)
	(gr_line
		(start 171.455588 -8.312404)
		(end 170.337988 -8.312404)
		(stroke
			(width 0.1016)
			(type default)
		)
		(layer "In1.Cu")
	)
	(gr_line
		(start 171.455588 -8.212328)
		(end 170.337988 -8.212328)
		(stroke
			(width 0.1016)
			(type default)
		)
		(layer "In1.Cu")
	)
	(gr_line
		(start 171.455588 -5.721604)
		(end 171.455588 -8.312404)
		(stroke
			(width 0.1016)
			(type default)
		)
		(layer "In1.Cu")
	)
	(gr_line
		(start 171.455588 -5.621528)
		(end 171.455588 -8.212328)
		(stroke
			(width 0.1016)
			(type default)
		)
		(layer "In1.Cu")
	)
	(gr_line
		(start 171.456096 -26.572972)
		(end 171.456096 -25.226772)
		(stroke
			(width 0.508)
			(type default)
		)
		(layer "In1.Cu")
	)
	(gr_line
		(start 171.462446 -29.1084)
		(end 171.462446 -27.7622)
		(stroke
			(width 0.508)
			(type default)
		)
		(layer "In1.Cu")
	)
	(gr_line
		(start 171.480988 -12.563348)
		(end 171.074588 -12.563348)
		(stroke
			(width 0.1016)
			(type default)
		)
		(layer "In1.Cu")
	)
	(gr_line
		(start 171.480988 -12.563348)
		(end 171.480988 -9.896348)
		(stroke
			(width 0.1016)
			(type default)
		)
		(layer "In1.Cu")
	)
	(gr_line
		(start 171.480988 -12.463272)
		(end 171.074588 -12.463272)
		(stroke
			(width 0.1016)
			(type default)
		)
		(layer "In1.Cu")
	)
	(gr_line
		(start 171.480988 -12.463272)
		(end 171.480988 -9.796272)
		(stroke
			(width 0.1016)
			(type default)
		)
		(layer "In1.Cu")
	)
	(gr_line
		(start 171.480988 -9.896348)
		(end 170.287188 -9.896348)
		(stroke
			(width 0.1016)
			(type default)
		)
		(layer "In1.Cu")
	)
	(gr_line
		(start 171.480988 -9.896348)
		(end 171.480988 -12.563348)
		(stroke
			(width 0.1016)
			(type default)
		)
		(layer "In1.Cu")
	)
	(gr_line
		(start 171.480988 -9.796272)
		(end 170.287188 -9.796272)
		(stroke
			(width 0.1016)
			(type default)
		)
		(layer "In1.Cu")
	)
	(gr_line
		(start 171.480988 -9.796272)
		(end 171.480988 -12.463272)
		(stroke
			(width 0.1016)
			(type default)
		)
		(layer "In1.Cu")
	)
	(gr_line
		(start 171.480988 -8.363204)
		(end 171.074588 -8.363204)
		(stroke
			(width 0.1016)
			(type default)
		)
		(layer "In1.Cu")
	)
	(gr_line
		(start 171.480988 -8.363204)
		(end 171.480988 -5.696204)
		(stroke
			(width 0.1016)
			(type default)
		)
		(layer "In1.Cu")
	)
	(gr_line
		(start 171.480988 -8.263128)
		(end 171.074588 -8.263128)
		(stroke
			(width 0.1016)
			(type default)
		)
		(layer "In1.Cu")
	)
	(gr_line
		(start 171.480988 -8.263128)
		(end 171.480988 -5.596128)
		(stroke
			(width 0.1016)
			(type default)
		)
		(layer "In1.Cu")
	)
	(gr_line
		(start 171.480988 -5.696204)
		(end 170.287188 -5.696204)
		(stroke
			(width 0.1016)
			(type default)
		)
		(layer "In1.Cu")
	)
	(gr_line
		(start 171.480988 -5.696204)
		(end 171.480988 -8.363204)
		(stroke
			(width 0.1016)
			(type default)
		)
		(layer "In1.Cu")
	)
	(gr_line
		(start 171.480988 -5.596128)
		(end 170.287188 -5.596128)
		(stroke
			(width 0.1016)
			(type default)
		)
		(layer "In1.Cu")
	)
	(gr_line
		(start 171.480988 -5.596128)
		(end 171.480988 -8.263128)
		(stroke
			(width 0.1016)
			(type default)
		)
		(layer "In1.Cu")
	)
	(gr_line
		(start 171.481496 -26.572972)
		(end 171.481496 -25.226772)
		(stroke
			(width 0.508)
			(type default)
		)
		(layer "In1.Cu")
	)
	(gr_line
		(start 171.506896 -26.572972)
		(end 171.506896 -25.226772)
		(stroke
			(width 0.508)
			(type default)
		)
		(layer "In1.Cu")
	)
	(gr_line
		(start 171.532296 -26.598372)
		(end 171.532296 -25.252172)
		(stroke
			(width 0.508)
			(type default)
		)
		(layer "In1.Cu")
	)
	(gr_line
		(start 171.557696 -26.598372)
		(end 171.557696 -25.252172)
		(stroke
			(width 0.508)
			(type default)
		)
		(layer "In1.Cu")
	)
	(gr_line
		(start 171.557696 -26.572972)
		(end 171.557696 -25.226772)
		(stroke
			(width 0.508)
			(type default)
		)
		(layer "In1.Cu")
	)
	(gr_line
		(start 171.564046 -29.2608)
		(end 171.564046 -27.6098)
		(stroke
			(width 0.2032)
			(type default)
		)
		(layer "In1.Cu")
	)
	(gr_line
		(start 171.564046 -29.2354)
		(end 170.548046 -29.2354)
		(stroke
			(width 0.2032)
			(type default)
		)
		(layer "In1.Cu")
	)
	(gr_line
		(start 171.564046 -29.1846)
		(end 171.564046 -29.2354)
		(stroke
			(width 0.2032)
			(type default)
		)
		(layer "In1.Cu")
	)
	(gr_line
		(start 171.564046 -27.6098)
		(end 170.624246 -27.6098)
		(stroke
			(width 0.2032)
			(type default)
		)
		(layer "In1.Cu")
	)
	(gr_line
		(start 171.583096 -26.572972)
		(end 171.583096 -25.226772)
		(stroke
			(width 0.508)
			(type default)
		)
		(layer "In1.Cu")
	)
	(gr_line
		(start 171.608496 -26.572972)
		(end 171.608496 -25.226772)
		(stroke
			(width 0.508)
			(type default)
		)
		(layer "In1.Cu")
	)
	(gr_line
		(start 171.614846 -29.2354)
		(end 170.573446 -29.2354)
		(stroke
			(width 0.2032)
			(type default)
		)
		(layer "In1.Cu")
	)
	(gr_line
		(start 171.614846 -27.559)
		(end 171.614846 -29.2354)
		(stroke
			(width 0.2032)
			(type default)
		)
		(layer "In1.Cu")
	)
	(gr_line
		(start 171.633896 -26.572972)
		(end 171.633896 -25.226772)
		(stroke
			(width 0.508)
			(type default)
		)
		(layer "In1.Cu")
	)
	(gr_line
		(start 171.659296 -26.598372)
		(end 171.659296 -25.252172)
		(stroke
			(width 0.508)
			(type default)
		)
		(layer "In1.Cu")
	)
	(gr_line
		(start 171.659296 -26.572972)
		(end 171.659296 -25.226772)
		(stroke
			(width 0.508)
			(type default)
		)
		(layer "In1.Cu")
	)
	(gr_line
		(start 171.665646 -29.337)
		(end 171.665646 -27.4828)
		(stroke
			(width 0.1016)
			(type default)
		)
		(layer "In1.Cu")
	)
	(gr_line
		(start 171.665646 -27.4828)
		(end 170.497246 -27.4828)
		(stroke
			(width 0.1016)
			(type default)
		)
		(layer "In1.Cu")
	)
	(gr_line
		(start 171.684696 -26.598372)
		(end 171.684696 -25.252172)
		(stroke
			(width 0.508)
			(type default)
		)
		(layer "In1.Cu")
	)
	(gr_line
		(start 171.684696 -26.572972)
		(end 171.684696 -25.226772)
		(stroke
			(width 0.508)
			(type default)
		)
		(layer "In1.Cu")
	)
	(gr_line
		(start 171.710096 -26.598372)
		(end 171.710096 -25.252172)
		(stroke
			(width 0.508)
			(type default)
		)
		(layer "In1.Cu")
	)
	(gr_line
		(start 171.720002 -31.98622)
		(end 170.450002 -31.98622)
		(stroke
			(width 0.7874)
			(type default)
		)
		(layer "In1.Cu")
	)
	(gr_line
		(start 171.735496 -26.826972)
		(end 172.065696 -26.826972)
		(stroke
			(width 0.1016)
			(type default)
		)
		(layer "In1.Cu")
	)
	(gr_line
		(start 171.735496 -26.572972)
		(end 171.735496 -25.226772)
		(stroke
			(width 0.508)
			(type default)
		)
		(layer "In1.Cu")
	)
	(gr_line
		(start 171.760896 -26.598372)
		(end 171.760896 -25.252172)
		(stroke
			(width 0.508)
			(type default)
		)
		(layer "In1.Cu")
	)
	(gr_line
		(start 171.760896 -26.572972)
		(end 171.760896 -25.226772)
		(stroke
			(width 0.508)
			(type default)
		)
		(layer "In1.Cu")
	)
	(gr_line
		(start 171.786296 -26.598372)
		(end 171.786296 -25.252172)
		(stroke
			(width 0.508)
			(type default)
		)
		(layer "In1.Cu")
	)
	(gr_line
		(start 171.862496 -26.598372)
		(end 171.862496 -25.252172)
		(stroke
			(width 0.508)
			(type default)
		)
		(layer "In1.Cu")
	)
	(gr_line
		(start 171.964096 -26.750772)
		(end 171.964096 -25.099772)
		(stroke
			(width 0.2032)
			(type default)
		)
		(layer "In1.Cu")
	)
	(gr_line
		(start 171.964096 -26.725372)
		(end 170.948096 -26.725372)
		(stroke
			(width 0.2032)
			(type default)
		)
		(layer "In1.Cu")
	)
	(gr_line
		(start 171.964096 -26.674572)
		(end 171.964096 -26.725372)
		(stroke
			(width 0.2032)
			(type default)
		)
		(layer "In1.Cu")
	)
	(gr_line
		(start 171.964096 -25.099772)
		(end 171.024296 -25.099772)
		(stroke
			(width 0.2032)
			(type default)
		)
		(layer "In1.Cu")
	)
	(gr_line
		(start 172.014896 -26.725372)
		(end 170.973496 -26.725372)
		(stroke
			(width 0.2032)
			(type default)
		)
		(layer "In1.Cu")
	)
	(gr_line
		(start 172.014896 -25.048972)
		(end 172.014896 -26.725372)
		(stroke
			(width 0.2032)
			(type default)
		)
		(layer "In1.Cu")
	)
	(gr_line
		(start 172.065696 -26.826972)
		(end 172.065696 -24.972772)
		(stroke
			(width 0.1016)
			(type default)
		)
		(layer "In1.Cu")
	)
	(gr_line
		(start 172.065696 -24.972772)
		(end 170.897296 -24.972772)
		(stroke
			(width 0.1016)
			(type default)
		)
		(layer "In1.Cu")
	)
	(gr_line
		(start 172.120052 -23.69566)
		(end 170.850052 -23.69566)
		(stroke
			(width 0.7874)
			(type default)
		)
		(layer "In1.Cu")
	)
	(gr_line
		(start 172.287184 -13.8176)
		(end 173.074584 -13.8176)
		(stroke
			(width 0.1016)
			(type default)
		)
		(layer "In1.Cu")
	)
	(gr_line
		(start 172.287184 -13.7668)
		(end 172.287184 -11.1506)
		(stroke
			(width 0.1016)
			(type default)
		)
		(layer "In1.Cu")
	)
	(gr_line
		(start 172.287184 -11.1506)
		(end 172.287184 -13.8176)
		(stroke
			(width 0.1016)
			(type default)
		)
		(layer "In1.Cu")
	)
	(gr_line
		(start 172.287184 -11.1506)
		(end 173.480984 -11.1506)
		(stroke
			(width 0.1016)
			(type default)
		)
		(layer "In1.Cu")
	)
	(gr_line
		(start 172.287184 -9.617456)
		(end 173.074584 -9.617456)
		(stroke
			(width 0.1016)
			(type default)
		)
		(layer "In1.Cu")
	)
	(gr_line
		(start 172.287184 -9.566656)
		(end 172.287184 -6.950456)
		(stroke
			(width 0.1016)
			(type default)
		)
		(layer "In1.Cu")
	)
	(gr_line
		(start 172.287184 -6.950456)
		(end 172.287184 -9.617456)
		(stroke
			(width 0.1016)
			(type default)
		)
		(layer "In1.Cu")
	)
	(gr_line
		(start 172.287184 -6.950456)
		(end 173.480984 -6.950456)
		(stroke
			(width 0.1016)
			(type default)
		)
		(layer "In1.Cu")
	)
	(gr_line
		(start 172.287184 -5.417312)
		(end 173.074584 -5.417312)
		(stroke
			(width 0.1016)
			(type default)
		)
		(layer "In1.Cu")
	)
	(gr_line
		(start 172.287184 -5.366512)
		(end 172.287184 -2.750312)
		(stroke
			(width 0.1016)
			(type default)
		)
		(layer "In1.Cu")
	)
	(gr_line
		(start 172.287184 -2.750312)
		(end 172.287184 -5.417312)
		(stroke
			(width 0.1016)
			(type default)
		)
		(layer "In1.Cu")
	)
	(gr_line
		(start 172.287184 -2.750312)
		(end 173.480984 -2.750312)
		(stroke
			(width 0.1016)
			(type default)
		)
		(layer "In1.Cu")
	)
	(gr_line
		(start 172.312584 -13.7668)
		(end 172.312584 -11.176)
		(stroke
			(width 0.1016)
			(type default)
		)
		(layer "In1.Cu")
	)
	(gr_line
		(start 172.312584 -11.176)
		(end 173.455584 -11.176)
		(stroke
			(width 0.1016)
			(type default)
		)
		(layer "In1.Cu")
	)
	(gr_line
		(start 172.312584 -9.566656)
		(end 172.312584 -6.975856)
		(stroke
			(width 0.1016)
			(type default)
		)
		(layer "In1.Cu")
	)
	(gr_line
		(start 172.312584 -6.975856)
		(end 173.455584 -6.975856)
		(stroke
			(width 0.1016)
			(type default)
		)
		(layer "In1.Cu")
	)
	(gr_line
		(start 172.312584 -5.366512)
		(end 172.312584 -2.775712)
		(stroke
			(width 0.1016)
			(type default)
		)
		(layer "In1.Cu")
	)
	(gr_line
		(start 172.312584 -2.775712)
		(end 173.455584 -2.775712)
		(stroke
			(width 0.1016)
			(type default)
		)
		(layer "In1.Cu")
	)
	(gr_line
		(start 172.337984 -13.7668)
		(end 172.337984 -11.2014)
		(stroke
			(width 0.1016)
			(type default)
		)
		(layer "In1.Cu")
	)
	(gr_line
		(start 172.337984 -11.2014)
		(end 172.591984 -11.2014)
		(stroke
			(width 0.1016)
			(type default)
		)
		(layer "In1.Cu")
	)
	(gr_line
		(start 172.337984 -9.566656)
		(end 172.337984 -7.001256)
		(stroke
			(width 0.1016)
			(type default)
		)
		(layer "In1.Cu")
	)
	(gr_line
		(start 172.337984 -7.001256)
		(end 172.591984 -7.001256)
		(stroke
			(width 0.1016)
			(type default)
		)
		(layer "In1.Cu")
	)
	(gr_line
		(start 172.337984 -5.366512)
		(end 172.337984 -2.801112)
		(stroke
			(width 0.1016)
			(type default)
		)
		(layer "In1.Cu")
	)
	(gr_line
		(start 172.337984 -2.801112)
		(end 172.591984 -2.801112)
		(stroke
			(width 0.1016)
			(type default)
		)
		(layer "In1.Cu")
	)
	(gr_line
		(start 172.363384 -13.7668)
		(end 172.363384 -11.2014)
		(stroke
			(width 0.2032)
			(type default)
		)
		(layer "In1.Cu")
	)
	(gr_line
		(start 172.363384 -11.2014)
		(end 173.379384 -11.2014)
		(stroke
			(width 0.2032)
			(type default)
		)
		(layer "In1.Cu")
	)
	(gr_line
		(start 172.363384 -9.566656)
		(end 172.363384 -7.001256)
		(stroke
			(width 0.2032)
			(type default)
		)
		(layer "In1.Cu")
	)
	(gr_line
		(start 172.363384 -7.001256)
		(end 173.379384 -7.001256)
		(stroke
			(width 0.2032)
			(type default)
		)
		(layer "In1.Cu")
	)
	(gr_line
		(start 172.363384 -5.366512)
		(end 172.363384 -2.801112)
		(stroke
			(width 0.2032)
			(type default)
		)
		(layer "In1.Cu")
	)
	(gr_line
		(start 172.363384 -2.801112)
		(end 173.379384 -2.801112)
		(stroke
			(width 0.2032)
			(type default)
		)
		(layer "In1.Cu")
	)
	(gr_line
		(start 172.414184 -13.7414)
		(end 172.414184 -11.2522)
		(stroke
			(width 0.2032)
			(type default)
		)
		(layer "In1.Cu")
	)
	(gr_line
		(start 172.414184 -13.7414)
		(end 172.414184 -11.2522)
		(stroke
			(width 0.254)
			(type default)
		)
		(layer "In1.Cu")
	)
	(gr_line
		(start 172.414184 -11.2522)
		(end 172.617384 -11.2522)
		(stroke
			(width 0.2032)
			(type default)
		)
		(layer "In1.Cu")
	)
	(gr_line
		(start 172.414184 -11.2522)
		(end 173.303184 -11.2522)
		(stroke
			(width 0.254)
			(type default)
		)
		(layer "In1.Cu")
	)
	(gr_line
		(start 172.414184 -9.541256)
		(end 172.414184 -7.052056)
		(stroke
			(width 0.2032)
			(type default)
		)
		(layer "In1.Cu")
	)
	(gr_line
		(start 172.414184 -9.541256)
		(end 172.414184 -7.052056)
		(stroke
			(width 0.254)
			(type default)
		)
		(layer "In1.Cu")
	)
	(gr_line
		(start 172.414184 -7.052056)
		(end 172.617384 -7.052056)
		(stroke
			(width 0.2032)
			(type default)
		)
		(layer "In1.Cu")
	)
	(gr_line
		(start 172.414184 -7.052056)
		(end 173.303184 -7.052056)
		(stroke
			(width 0.254)
			(type default)
		)
		(layer "In1.Cu")
	)
	(gr_line
		(start 172.414184 -5.341112)
		(end 172.414184 -2.851912)
		(stroke
			(width 0.2032)
			(type default)
		)
		(layer "In1.Cu")
	)
	(gr_line
		(start 172.414184 -5.341112)
		(end 172.414184 -2.851912)
		(stroke
			(width 0.254)
			(type default)
		)
		(layer "In1.Cu")
	)
	(gr_line
		(start 172.414184 -2.851912)
		(end 172.617384 -2.851912)
		(stroke
			(width 0.2032)
			(type default)
		)
		(layer "In1.Cu")
	)
	(gr_line
		(start 172.414184 -2.851912)
		(end 173.303184 -2.851912)
		(stroke
			(width 0.254)
			(type default)
		)
		(layer "In1.Cu")
	)
	(gr_line
		(start 172.439584 -13.716)
		(end 172.439584 -11.2776)
		(stroke
			(width 0.254)
			(type default)
		)
		(layer "In1.Cu")
	)
	(gr_line
		(start 172.439584 -11.2776)
		(end 173.277784 -11.2776)
		(stroke
			(width 0.254)
			(type default)
		)
		(layer "In1.Cu")
	)
	(gr_line
		(start 172.439584 -9.515856)
		(end 172.439584 -7.077456)
		(stroke
			(width 0.254)
			(type default)
		)
		(layer "In1.Cu")
	)
	(gr_line
		(start 172.439584 -7.077456)
		(end 173.277784 -7.077456)
		(stroke
			(width 0.254)
			(type default)
		)
		(layer "In1.Cu")
	)
	(gr_line
		(start 172.439584 -5.315712)
		(end 172.439584 -2.877312)
		(stroke
			(width 0.254)
			(type default)
		)
		(layer "In1.Cu")
	)
	(gr_line
		(start 172.439584 -2.877312)
		(end 173.277784 -2.877312)
		(stroke
			(width 0.254)
			(type default)
		)
		(layer "In1.Cu")
	)
	(gr_line
		(start 172.464984 -13.6906)
		(end 172.464984 -11.303)
		(stroke
			(width 0.254)
			(type default)
		)
		(layer "In1.Cu")
	)
	(gr_line
		(start 172.464984 -11.303)
		(end 173.252384 -11.303)
		(stroke
			(width 0.254)
			(type default)
		)
		(layer "In1.Cu")
	)
	(gr_line
		(start 172.464984 -9.490456)
		(end 172.464984 -7.102856)
		(stroke
			(width 0.254)
			(type default)
		)
		(layer "In1.Cu")
	)
	(gr_line
		(start 172.464984 -7.102856)
		(end 173.252384 -7.102856)
		(stroke
			(width 0.254)
			(type default)
		)
		(layer "In1.Cu")
	)
	(gr_line
		(start 172.464984 -5.290312)
		(end 172.464984 -2.902712)
		(stroke
			(width 0.254)
			(type default)
		)
		(layer "In1.Cu")
	)
	(gr_line
		(start 172.464984 -2.902712)
		(end 173.252384 -2.902712)
		(stroke
			(width 0.254)
			(type default)
		)
		(layer "In1.Cu")
	)
	(gr_line
		(start 172.490384 -13.6144)
		(end 173.125384 -13.6144)
		(stroke
			(width 0.508)
			(type default)
		)
		(layer "In1.Cu")
	)
	(gr_line
		(start 172.490384 -11.43)
		(end 173.125384 -11.43)
		(stroke
			(width 0.508)
			(type default)
		)
		(layer "In1.Cu")
	)
	(gr_line
		(start 172.490384 -11.3792)
		(end 173.125384 -11.3792)
		(stroke
			(width 0.508)
			(type default)
		)
		(layer "In1.Cu")
	)
	(gr_line
		(start 172.490384 -9.414256)
		(end 173.125384 -9.414256)
		(stroke
			(width 0.508)
			(type default)
		)
		(layer "In1.Cu")
	)
	(gr_line
		(start 172.490384 -7.229856)
		(end 173.125384 -7.229856)
		(stroke
			(width 0.508)
			(type default)
		)
		(layer "In1.Cu")
	)
	(gr_line
		(start 172.490384 -7.179056)
		(end 173.125384 -7.179056)
		(stroke
			(width 0.508)
			(type default)
		)
		(layer "In1.Cu")
	)
	(gr_line
		(start 172.490384 -5.214112)
		(end 173.125384 -5.214112)
		(stroke
			(width 0.508)
			(type default)
		)
		(layer "In1.Cu")
	)
	(gr_line
		(start 172.490384 -3.029712)
		(end 173.125384 -3.029712)
		(stroke
			(width 0.508)
			(type default)
		)
		(layer "In1.Cu")
	)
	(gr_line
		(start 172.490384 -2.978912)
		(end 173.125384 -2.978912)
		(stroke
			(width 0.508)
			(type default)
		)
		(layer "In1.Cu")
	)
	(gr_line
		(start 172.515784 -11.684)
		(end 173.150784 -11.684)
		(stroke
			(width 0.508)
			(type default)
		)
		(layer "In1.Cu")
	)
	(gr_line
		(start 172.515784 -7.483856)
		(end 173.150784 -7.483856)
		(stroke
			(width 0.508)
			(type default)
		)
		(layer "In1.Cu")
	)
	(gr_line
		(start 172.515784 -3.283712)
		(end 173.150784 -3.283712)
		(stroke
			(width 0.508)
			(type default)
		)
		(layer "In1.Cu")
	)
	(gr_line
		(start 172.541184 -13.6398)
		(end 172.541184 -11.3792)
		(stroke
			(width 0.254)
			(type default)
		)
		(layer "In1.Cu")
	)
	(gr_line
		(start 172.541184 -13.4874)
		(end 173.176184 -13.4874)
		(stroke
			(width 0.508)
			(type default)
		)
		(layer "In1.Cu")
	)
	(gr_line
		(start 172.541184 -11.3792)
		(end 173.176184 -11.3792)
		(stroke
			(width 0.254)
			(type default)
		)
		(layer "In1.Cu")
	)
	(gr_line
		(start 172.541184 -9.439656)
		(end 172.541184 -7.179056)
		(stroke
			(width 0.254)
			(type default)
		)
		(layer "In1.Cu")
	)
	(gr_line
		(start 172.541184 -9.287256)
		(end 173.176184 -9.287256)
		(stroke
			(width 0.508)
			(type default)
		)
		(layer "In1.Cu")
	)
	(gr_line
		(start 172.541184 -7.179056)
		(end 173.176184 -7.179056)
		(stroke
			(width 0.254)
			(type default)
		)
		(layer "In1.Cu")
	)
	(gr_line
		(start 172.541184 -5.239512)
		(end 172.541184 -2.978912)
		(stroke
			(width 0.254)
			(type default)
		)
		(layer "In1.Cu")
	)
	(gr_line
		(start 172.541184 -5.087112)
		(end 173.176184 -5.087112)
		(stroke
			(width 0.508)
			(type default)
		)
		(layer "In1.Cu")
	)
	(gr_line
		(start 172.541184 -2.978912)
		(end 173.176184 -2.978912)
		(stroke
			(width 0.254)
			(type default)
		)
		(layer "In1.Cu")
	)
	(gr_line
		(start 172.566584 -13.335)
		(end 173.201584 -13.335)
		(stroke
			(width 0.508)
			(type default)
		)
		(layer "In1.Cu")
	)
	(gr_line
		(start 172.566584 -9.134856)
		(end 173.201584 -9.134856)
		(stroke
			(width 0.508)
			(type default)
		)
		(layer "In1.Cu")
	)
	(gr_line
		(start 172.566584 -4.934712)
		(end 173.201584 -4.934712)
		(stroke
			(width 0.508)
			(type default)
		)
		(layer "In1.Cu")
	)
	(gr_line
		(start 172.591984 -13.6144)
		(end 173.226984 -13.6144)
		(stroke
			(width 0.508)
			(type default)
		)
		(layer "In1.Cu")
	)
	(gr_line
		(start 172.591984 -11.2014)
		(end 173.430184 -11.2014)
		(stroke
			(width 0.2032)
			(type default)
		)
		(layer "In1.Cu")
	)
	(gr_line
		(start 172.591984 -9.414256)
		(end 173.226984 -9.414256)
		(stroke
			(width 0.508)
			(type default)
		)
		(layer "In1.Cu")
	)
	(gr_line
		(start 172.591984 -7.001256)
		(end 173.430184 -7.001256)
		(stroke
			(width 0.2032)
			(type default)
		)
		(layer "In1.Cu")
	)
	(gr_line
		(start 172.591984 -5.214112)
		(end 173.226984 -5.214112)
		(stroke
			(width 0.508)
			(type default)
		)
		(layer "In1.Cu")
	)
	(gr_line
		(start 172.591984 -2.801112)
		(end 173.430184 -2.801112)
		(stroke
			(width 0.2032)
			(type default)
		)
		(layer "In1.Cu")
	)
	(gr_line
		(start 172.617384 -13.6144)
		(end 172.617384 -11.43)
		(stroke
			(width 0.254)
			(type default)
		)
		(layer "In1.Cu")
	)
	(gr_line
		(start 172.617384 -11.43)
		(end 173.099984 -11.43)
		(stroke
			(width 0.254)
			(type default)
		)
		(layer "In1.Cu")
	)
	(gr_line
		(start 172.617384 -11.2522)
		(end 173.353984 -11.2522)
		(stroke
			(width 0.254)
			(type default)
		)
		(layer "In1.Cu")
	)
	(gr_line
		(start 172.617384 -9.414256)
		(end 172.617384 -7.229856)
		(stroke
			(width 0.254)
			(type default)
		)
		(layer "In1.Cu")
	)
	(gr_line
		(start 172.617384 -7.229856)
		(end 173.099984 -7.229856)
		(stroke
			(width 0.254)
			(type default)
		)
		(layer "In1.Cu")
	)
	(gr_line
		(start 172.617384 -7.052056)
		(end 173.353984 -7.052056)
		(stroke
			(width 0.254)
			(type default)
		)
		(layer "In1.Cu")
	)
	(gr_line
		(start 172.617384 -5.214112)
		(end 172.617384 -3.029712)
		(stroke
			(width 0.254)
			(type default)
		)
		(layer "In1.Cu")
	)
	(gr_line
		(start 172.617384 -3.029712)
		(end 173.099984 -3.029712)
		(stroke
			(width 0.254)
			(type default)
		)
		(layer "In1.Cu")
	)
	(gr_line
		(start 172.617384 -2.851912)
		(end 173.353984 -2.851912)
		(stroke
			(width 0.254)
			(type default)
		)
		(layer "In1.Cu")
	)
	(gr_line
		(start 172.635926 -11.36523)
		(end 173.270926 -11.36523)
		(stroke
			(width 0.508)
			(type default)
		)
		(layer "In1.Cu")
	)
	(gr_line
		(start 172.635926 -7.165086)
		(end 173.270926 -7.165086)
		(stroke
			(width 0.508)
			(type default)
		)
		(layer "In1.Cu")
	)
	(gr_line
		(start 172.635926 -2.964942)
		(end 173.270926 -2.964942)
		(stroke
			(width 0.508)
			(type default)
		)
		(layer "In1.Cu")
	)
	(gr_line
		(start 172.642784 -13.6144)
		(end 173.277784 -13.6144)
		(stroke
			(width 0.508)
			(type default)
		)
		(layer "In1.Cu")
	)
	(gr_line
		(start 172.642784 -13.4874)
		(end 172.642784 -11.5062)
		(stroke
			(width 0.762)
			(type default)
		)
		(layer "In1.Cu")
	)
	(gr_line
		(start 172.642784 -11.5062)
		(end 173.277784 -11.5062)
		(stroke
			(width 0.508)
			(type default)
		)
		(layer "In1.Cu")
	)
	(gr_line
		(start 172.642784 -9.414256)
		(end 173.277784 -9.414256)
		(stroke
			(width 0.508)
			(type default)
		)
		(layer "In1.Cu")
	)
	(gr_line
		(start 172.642784 -9.287256)
		(end 172.642784 -7.306056)
		(stroke
			(width 0.762)
			(type default)
		)
		(layer "In1.Cu")
	)
	(gr_line
		(start 172.642784 -7.306056)
		(end 173.277784 -7.306056)
		(stroke
			(width 0.508)
			(type default)
		)
		(layer "In1.Cu")
	)
	(gr_line
		(start 172.642784 -5.214112)
		(end 173.277784 -5.214112)
		(stroke
			(width 0.508)
			(type default)
		)
		(layer "In1.Cu")
	)
	(gr_line
		(start 172.642784 -5.087112)
		(end 172.642784 -3.105912)
		(stroke
			(width 0.762)
			(type default)
		)
		(layer "In1.Cu")
	)
	(gr_line
		(start 172.642784 -3.105912)
		(end 173.277784 -3.105912)
		(stroke
			(width 0.508)
			(type default)
		)
		(layer "In1.Cu")
	)
	(gr_line
		(start 172.693584 -13.5382)
		(end 172.693584 -11.5062)
		(stroke
			(width 0.254)
			(type default)
		)
		(layer "In1.Cu")
	)
	(gr_line
		(start 172.693584 -11.5062)
		(end 173.023784 -11.5062)
		(stroke
			(width 0.254)
			(type default)
		)
		(layer "In1.Cu")
	)
	(gr_line
		(start 172.693584 -9.338056)
		(end 172.693584 -7.306056)
		(stroke
			(width 0.254)
			(type default)
		)
		(layer "In1.Cu")
	)
	(gr_line
		(start 172.693584 -7.306056)
		(end 173.023784 -7.306056)
		(stroke
			(width 0.254)
			(type default)
		)
		(layer "In1.Cu")
	)
	(gr_line
		(start 172.693584 -5.137912)
		(end 172.693584 -3.105912)
		(stroke
			(width 0.254)
			(type default)
		)
		(layer "In1.Cu")
	)
	(gr_line
		(start 172.693584 -3.105912)
		(end 173.023784 -3.105912)
		(stroke
			(width 0.254)
			(type default)
		)
		(layer "In1.Cu")
	)
	(gr_line
		(start 172.795184 -13.462)
		(end 172.795184 -11.6586)
		(stroke
			(width 0.254)
			(type default)
		)
		(layer "In1.Cu")
	)
	(gr_line
		(start 172.795184 -13.462)
		(end 172.795184 -11.4808)
		(stroke
			(width 0.762)
			(type default)
		)
		(layer "In1.Cu")
	)
	(gr_line
		(start 172.795184 -11.6586)
		(end 172.896784 -11.6586)
		(stroke
			(width 0.254)
			(type default)
		)
		(layer "In1.Cu")
	)
	(gr_line
		(start 172.795184 -9.261856)
		(end 172.795184 -7.458456)
		(stroke
			(width 0.254)
			(type default)
		)
		(layer "In1.Cu")
	)
	(gr_line
		(start 172.795184 -9.261856)
		(end 172.795184 -7.280656)
		(stroke
			(width 0.762)
			(type default)
		)
		(layer "In1.Cu")
	)
	(gr_line
		(start 172.795184 -7.458456)
		(end 172.896784 -7.458456)
		(stroke
			(width 0.254)
			(type default)
		)
		(layer "In1.Cu")
	)
	(gr_line
		(start 172.795184 -5.061712)
		(end 172.795184 -3.258312)
		(stroke
			(width 0.254)
			(type default)
		)
		(layer "In1.Cu")
	)
	(gr_line
		(start 172.795184 -5.061712)
		(end 172.795184 -3.080512)
		(stroke
			(width 0.762)
			(type default)
		)
		(layer "In1.Cu")
	)
	(gr_line
		(start 172.795184 -3.258312)
		(end 172.896784 -3.258312)
		(stroke
			(width 0.254)
			(type default)
		)
		(layer "In1.Cu")
	)
	(gr_line
		(start 172.896784 -13.5636)
		(end 172.845984 -13.5636)
		(stroke
			(width 0.254)
			(type default)
		)
		(layer "In1.Cu")
	)
	(gr_line
		(start 172.896784 -11.6586)
		(end 172.896784 -13.5636)
		(stroke
			(width 0.254)
			(type default)
		)
		(layer "In1.Cu")
	)
	(gr_line
		(start 172.896784 -9.363456)
		(end 172.845984 -9.363456)
		(stroke
			(width 0.254)
			(type default)
		)
		(layer "In1.Cu")
	)
	(gr_line
		(start 172.896784 -7.458456)
		(end 172.896784 -9.363456)
		(stroke
			(width 0.254)
			(type default)
		)
		(layer "In1.Cu")
	)
	(gr_line
		(start 172.896784 -5.163312)
		(end 172.845984 -5.163312)
		(stroke
			(width 0.254)
			(type default)
		)
		(layer "In1.Cu")
	)
	(gr_line
		(start 172.896784 -3.258312)
		(end 172.896784 -5.163312)
		(stroke
			(width 0.254)
			(type default)
		)
		(layer "In1.Cu")
	)
	(gr_line
		(start 172.897038 -29.337)
		(end 173.735238 -29.337)
		(stroke
			(width 0.1016)
			(type default)
		)
		(layer "In1.Cu")
	)
	(gr_line
		(start 172.897038 -27.4828)
		(end 172.897038 -29.337)
		(stroke
			(width 0.1016)
			(type default)
		)
		(layer "In1.Cu")
	)
	(gr_line
		(start 172.947584 -13.4874)
		(end 172.947584 -11.5062)
		(stroke
			(width 0.762)
			(type default)
		)
		(layer "In1.Cu")
	)
	(gr_line
		(start 172.947584 -9.287256)
		(end 172.947584 -7.306056)
		(stroke
			(width 0.762)
			(type default)
		)
		(layer "In1.Cu")
	)
	(gr_line
		(start 172.947584 -5.087112)
		(end 172.947584 -3.105912)
		(stroke
			(width 0.762)
			(type default)
		)
		(layer "In1.Cu")
	)
	(gr_line
		(start 172.947838 -29.2354)
		(end 172.947838 -27.559)
		(stroke
			(width 0.2032)
			(type default)
		)
		(layer "In1.Cu")
	)
	(gr_line
		(start 172.947838 -27.559)
		(end 174.014638 -27.559)
		(stroke
			(width 0.2032)
			(type default)
		)
		(layer "In1.Cu")
	)
	(gr_line
		(start 172.973238 -29.2608)
		(end 173.963838 -29.2608)
		(stroke
			(width 0.2032)
			(type default)
		)
		(layer "In1.Cu")
	)
	(gr_line
		(start 172.973238 -29.2354)
		(end 172.973238 -29.2608)
		(stroke
			(width 0.2032)
			(type default)
		)
		(layer "In1.Cu")
	)
	(gr_line
		(start 173.023784 -13.462)
		(end 172.795184 -13.462)
		(stroke
			(width 0.254)
			(type default)
		)
		(layer "In1.Cu")
	)
	(gr_line
		(start 173.023784 -11.5062)
		(end 173.023784 -13.462)
		(stroke
			(width 0.254)
			(type default)
		)
		(layer "In1.Cu")
	)
	(gr_line
		(start 173.023784 -9.261856)
		(end 172.795184 -9.261856)
		(stroke
			(width 0.254)
			(type default)
		)
		(layer "In1.Cu")
	)
	(gr_line
		(start 173.023784 -7.306056)
		(end 173.023784 -9.261856)
		(stroke
			(width 0.254)
			(type default)
		)
		(layer "In1.Cu")
	)
	(gr_line
		(start 173.023784 -5.061712)
		(end 172.795184 -5.061712)
		(stroke
			(width 0.254)
			(type default)
		)
		(layer "In1.Cu")
	)
	(gr_line
		(start 173.023784 -3.105912)
		(end 173.023784 -5.061712)
		(stroke
			(width 0.254)
			(type default)
		)
		(layer "In1.Cu")
	)
	(gr_line
		(start 173.024038 -29.1846)
		(end 173.963838 -29.1846)
		(stroke
			(width 0.2032)
			(type default)
		)
		(layer "In1.Cu")
	)
	(gr_line
		(start 173.024038 -27.6098)
		(end 173.024038 -29.1846)
		(stroke
			(width 0.2032)
			(type default)
		)
		(layer "In1.Cu")
	)
	(gr_line
		(start 173.074584 -13.8176)
		(end 173.074584 -13.7668)
		(stroke
			(width 0.1016)
			(type default)
		)
		(layer "In1.Cu")
	)
	(gr_line
		(start 173.074584 -13.8176)
		(end 173.480984 -13.8176)
		(stroke
			(width 0.1016)
			(type default)
		)
		(layer "In1.Cu")
	)
	(gr_line
		(start 173.074584 -13.7668)
		(end 172.312584 -13.7668)
		(stroke
			(width 0.1016)
			(type default)
		)
		(layer "In1.Cu")
	)
	(gr_line
		(start 173.074584 -13.4874)
		(end 173.074584 -11.5062)
		(stroke
			(width 0.762)
			(type default)
		)
		(layer "In1.Cu")
	)
	(gr_line
		(start 173.074584 -9.617456)
		(end 173.074584 -9.566656)
		(stroke
			(width 0.1016)
			(type default)
		)
		(layer "In1.Cu")
	)
	(gr_line
		(start 173.074584 -9.617456)
		(end 173.480984 -9.617456)
		(stroke
			(width 0.1016)
			(type default)
		)
		(layer "In1.Cu")
	)
	(gr_line
		(start 173.074584 -9.566656)
		(end 172.312584 -9.566656)
		(stroke
			(width 0.1016)
			(type default)
		)
		(layer "In1.Cu")
	)
	(gr_line
		(start 173.074584 -9.287256)
		(end 173.074584 -7.306056)
		(stroke
			(width 0.762)
			(type default)
		)
		(layer "In1.Cu")
	)
	(gr_line
		(start 173.074584 -5.417312)
		(end 173.074584 -5.366512)
		(stroke
			(width 0.1016)
			(type default)
		)
		(layer "In1.Cu")
	)
	(gr_line
		(start 173.074584 -5.417312)
		(end 173.480984 -5.417312)
		(stroke
			(width 0.1016)
			(type default)
		)
		(layer "In1.Cu")
	)
	(gr_line
		(start 173.074584 -5.366512)
		(end 172.312584 -5.366512)
		(stroke
			(width 0.1016)
			(type default)
		)
		(layer "In1.Cu")
	)
	(gr_line
		(start 173.074584 -5.087112)
		(end 173.074584 -3.105912)
		(stroke
			(width 0.762)
			(type default)
		)
		(layer "In1.Cu")
	)
	(gr_line
		(start 173.099984 -13.5382)
		(end 172.693584 -13.5382)
		(stroke
			(width 0.254)
			(type default)
		)
		(layer "In1.Cu")
	)
	(gr_line
		(start 173.099984 -11.43)
		(end 173.099984 -13.5382)
		(stroke
			(width 0.254)
			(type default)
		)
		(layer "In1.Cu")
	)
	(gr_line
		(start 173.099984 -9.338056)
		(end 172.693584 -9.338056)
		(stroke
			(width 0.254)
			(type default)
		)
		(layer "In1.Cu")
	)
	(gr_line
		(start 173.099984 -7.229856)
		(end 173.099984 -9.338056)
		(stroke
			(width 0.254)
			(type default)
		)
		(layer "In1.Cu")
	)
	(gr_line
		(start 173.099984 -5.137912)
		(end 172.693584 -5.137912)
		(stroke
			(width 0.254)
			(type default)
		)
		(layer "In1.Cu")
	)
	(gr_line
		(start 173.099984 -3.029712)
		(end 173.099984 -5.137912)
		(stroke
			(width 0.254)
			(type default)
		)
		(layer "In1.Cu")
	)
	(gr_line
		(start 173.100238 -29.1084)
		(end 173.100238 -27.7622)
		(stroke
			(width 0.508)
			(type default)
		)
		(layer "In1.Cu")
	)
	(gr_line
		(start 173.125638 -29.1084)
		(end 173.786038 -29.1084)
		(stroke
			(width 0.508)
			(type default)
		)
		(layer "In1.Cu")
	)
	(gr_line
		(start 173.125638 -29.083)
		(end 173.125638 -27.7368)
		(stroke
			(width 0.508)
			(type default)
		)
		(layer "In1.Cu")
	)
	(gr_line
		(start 173.125638 -27.7114)
		(end 173.760638 -27.7114)
		(stroke
			(width 0.508)
			(type default)
		)
		(layer "In1.Cu")
	)
	(gr_line
		(start 173.150784 -13.4874)
		(end 173.150784 -11.5062)
		(stroke
			(width 0.762)
			(type default)
		)
		(layer "In1.Cu")
	)
	(gr_line
		(start 173.150784 -9.287256)
		(end 173.150784 -7.306056)
		(stroke
			(width 0.762)
			(type default)
		)
		(layer "In1.Cu")
	)
	(gr_line
		(start 173.150784 -5.087112)
		(end 173.150784 -3.105912)
		(stroke
			(width 0.762)
			(type default)
		)
		(layer "In1.Cu")
	)
	(gr_line
		(start 173.151038 -29.083)
		(end 173.151038 -27.7368)
		(stroke
			(width 0.508)
			(type default)
		)
		(layer "In1.Cu")
	)
	(gr_line
		(start 173.176184 -13.6144)
		(end 172.617384 -13.6144)
		(stroke
			(width 0.254)
			(type default)
		)
		(layer "In1.Cu")
	)
	(gr_line
		(start 173.176184 -11.3792)
		(end 173.176184 -13.6144)
		(stroke
			(width 0.254)
			(type default)
		)
		(layer "In1.Cu")
	)
	(gr_line
		(start 173.176184 -9.414256)
		(end 172.617384 -9.414256)
		(stroke
			(width 0.254)
			(type default)
		)
		(layer "In1.Cu")
	)
	(gr_line
		(start 173.176184 -7.179056)
		(end 173.176184 -9.414256)
		(stroke
			(width 0.254)
			(type default)
		)
		(layer "In1.Cu")
	)
	(gr_line
		(start 173.176184 -5.214112)
		(end 172.617384 -5.214112)
		(stroke
			(width 0.254)
			(type default)
		)
		(layer "In1.Cu")
	)
	(gr_line
		(start 173.176184 -2.978912)
		(end 173.176184 -5.214112)
		(stroke
			(width 0.254)
			(type default)
		)
		(layer "In1.Cu")
	)
	(gr_line
		(start 173.176438 -29.083)
		(end 173.176438 -27.7368)
		(stroke
			(width 0.508)
			(type default)
		)
		(layer "In1.Cu")
	)
	(gr_line
		(start 173.227238 -29.1084)
		(end 173.227238 -27.7622)
		(stroke
			(width 0.508)
			(type default)
		)
		(layer "In1.Cu")
	)
	(gr_line
		(start 173.227238 -29.083)
		(end 173.227238 -27.7368)
		(stroke
			(width 0.508)
			(type default)
		)
		(layer "In1.Cu")
	)
	(gr_line
		(start 173.252384 -13.6398)
		(end 172.541184 -13.6398)
		(stroke
			(width 0.254)
			(type default)
		)
		(layer "In1.Cu")
	)
	(gr_line
		(start 173.252384 -11.303)
		(end 173.252384 -13.6398)
		(stroke
			(width 0.254)
			(type default)
		)
		(layer "In1.Cu")
	)
	(gr_line
		(start 173.252384 -9.439656)
		(end 172.541184 -9.439656)
		(stroke
			(width 0.254)
			(type default)
		)
		(layer "In1.Cu")
	)
	(gr_line
		(start 173.252384 -7.102856)
		(end 173.252384 -9.439656)
		(stroke
			(width 0.254)
			(type default)
		)
		(layer "In1.Cu")
	)
	(gr_line
		(start 173.252384 -5.239512)
		(end 172.541184 -5.239512)
		(stroke
			(width 0.254)
			(type default)
		)
		(layer "In1.Cu")
	)
	(gr_line
		(start 173.252384 -2.902712)
		(end 173.252384 -5.239512)
		(stroke
			(width 0.254)
			(type default)
		)
		(layer "In1.Cu")
	)
	(gr_line
		(start 173.277784 -13.7668)
		(end 172.287184 -13.7668)
		(stroke
			(width 0.1016)
			(type default)
		)
		(layer "In1.Cu")
	)
	(gr_line
		(start 173.277784 -13.6906)
		(end 172.464984 -13.6906)
		(stroke
			(width 0.254)
			(type default)
		)
		(layer "In1.Cu")
	)
	(gr_line
		(start 173.277784 -11.2776)
		(end 173.277784 -13.6906)
		(stroke
			(width 0.254)
			(type default)
		)
		(layer "In1.Cu")
	)
	(gr_line
		(start 173.277784 -9.566656)
		(end 172.287184 -9.566656)
		(stroke
			(width 0.1016)
			(type default)
		)
		(layer "In1.Cu")
	)
	(gr_line
		(start 173.277784 -9.490456)
		(end 172.464984 -9.490456)
		(stroke
			(width 0.254)
			(type default)
		)
		(layer "In1.Cu")
	)
	(gr_line
		(start 173.277784 -7.077456)
		(end 173.277784 -9.490456)
		(stroke
			(width 0.254)
			(type default)
		)
		(layer "In1.Cu")
	)
	(gr_line
		(start 173.277784 -5.366512)
		(end 172.287184 -5.366512)
		(stroke
			(width 0.1016)
			(type default)
		)
		(layer "In1.Cu")
	)
	(gr_line
		(start 173.277784 -5.290312)
		(end 172.464984 -5.290312)
		(stroke
			(width 0.254)
			(type default)
		)
		(layer "In1.Cu")
	)
	(gr_line
		(start 173.277784 -2.877312)
		(end 173.277784 -5.290312)
		(stroke
			(width 0.254)
			(type default)
		)
		(layer "In1.Cu")
	)
	(gr_line
		(start 173.278038 -29.083)
		(end 173.278038 -27.7368)
		(stroke
			(width 0.508)
			(type default)
		)
		(layer "In1.Cu")
	)
	(gr_line
		(start 173.297088 -26.826972)
		(end 174.135288 -26.826972)
		(stroke
			(width 0.1016)
			(type default)
		)
		(layer "In1.Cu")
	)
	(gr_line
		(start 173.297088 -24.972772)
		(end 173.297088 -26.826972)
		(stroke
			(width 0.1016)
			(type default)
		)
		(layer "In1.Cu")
	)
	(gr_line
		(start 173.303184 -13.716)
		(end 172.439584 -13.716)
		(stroke
			(width 0.254)
			(type default)
		)
		(layer "In1.Cu")
	)
	(gr_line
		(start 173.303184 -11.2522)
		(end 173.303184 -13.716)
		(stroke
			(width 0.254)
			(type default)
		)
		(layer "In1.Cu")
	)
	(gr_line
		(start 173.303184 -9.515856)
		(end 172.439584 -9.515856)
		(stroke
			(width 0.254)
			(type default)
		)
		(layer "In1.Cu")
	)
	(gr_line
		(start 173.303184 -7.052056)
		(end 173.303184 -9.515856)
		(stroke
			(width 0.254)
			(type default)
		)
		(layer "In1.Cu")
	)
	(gr_line
		(start 173.303184 -5.315712)
		(end 172.439584 -5.315712)
		(stroke
			(width 0.254)
			(type default)
		)
		(layer "In1.Cu")
	)
	(gr_line
		(start 173.303184 -2.851912)
		(end 173.303184 -5.315712)
		(stroke
			(width 0.254)
			(type default)
		)
		(layer "In1.Cu")
	)
	(gr_line
		(start 173.303438 -29.0576)
		(end 173.303438 -27.7114)
		(stroke
			(width 0.508)
			(type default)
		)
		(layer "In1.Cu")
	)
	(gr_line
		(start 173.328838 -29.083)
		(end 173.328838 -27.7368)
		(stroke
			(width 0.508)
			(type default)
		)
		(layer "In1.Cu")
	)
	(gr_line
		(start 173.347888 -26.725372)
		(end 173.347888 -25.048972)
		(stroke
			(width 0.2032)
			(type default)
		)
		(layer "In1.Cu")
	)
	(gr_line
		(start 173.347888 -25.048972)
		(end 174.414688 -25.048972)
		(stroke
			(width 0.2032)
			(type default)
		)
		(layer "In1.Cu")
	)
	(gr_line
		(start 173.353984 -13.7414)
		(end 172.414184 -13.7414)
		(stroke
			(width 0.254)
			(type default)
		)
		(layer "In1.Cu")
	)
	(gr_line
		(start 173.353984 -11.2522)
		(end 173.353984 -13.7414)
		(stroke
			(width 0.254)
			(type default)
		)
		(layer "In1.Cu")
	)
	(gr_line
		(start 173.353984 -9.541256)
		(end 172.414184 -9.541256)
		(stroke
			(width 0.254)
			(type default)
		)
		(layer "In1.Cu")
	)
	(gr_line
		(start 173.353984 -7.052056)
		(end 173.353984 -9.541256)
		(stroke
			(width 0.254)
			(type default)
		)
		(layer "In1.Cu")
	)
	(gr_line
		(start 173.353984 -5.341112)
		(end 172.414184 -5.341112)
		(stroke
			(width 0.254)
			(type default)
		)
		(layer "In1.Cu")
	)
	(gr_line
		(start 173.353984 -2.851912)
		(end 173.353984 -5.341112)
		(stroke
			(width 0.254)
			(type default)
		)
		(layer "In1.Cu")
	)
	(gr_line
		(start 173.354238 -29.083)
		(end 173.354238 -27.7368)
		(stroke
			(width 0.508)
			(type default)
		)
		(layer "In1.Cu")
	)
	(gr_line
		(start 173.373288 -26.750772)
		(end 174.363888 -26.750772)
		(stroke
			(width 0.2032)
			(type default)
		)
		(layer "In1.Cu")
	)
	(gr_line
		(start 173.373288 -26.725372)
		(end 173.373288 -26.750772)
		(stroke
			(width 0.2032)
			(type default)
		)
		(layer "In1.Cu")
	)
	(gr_line
		(start 173.379384 -13.7414)
		(end 172.414184 -13.7414)
		(stroke
			(width 0.2032)
			(type default)
		)
		(layer "In1.Cu")
	)
	(gr_line
		(start 173.379384 -11.2014)
		(end 173.379384 -13.7414)
		(stroke
			(width 0.2032)
			(type default)
		)
		(layer "In1.Cu")
	)
	(gr_line
		(start 173.379384 -9.541256)
		(end 172.414184 -9.541256)
		(stroke
			(width 0.2032)
			(type default)
		)
		(layer "In1.Cu")
	)
	(gr_line
		(start 173.379384 -7.001256)
		(end 173.379384 -9.541256)
		(stroke
			(width 0.2032)
			(type default)
		)
		(layer "In1.Cu")
	)
	(gr_line
		(start 173.379384 -5.341112)
		(end 172.414184 -5.341112)
		(stroke
			(width 0.2032)
			(type default)
		)
		(layer "In1.Cu")
	)
	(gr_line
		(start 173.379384 -2.801112)
		(end 173.379384 -5.341112)
		(stroke
			(width 0.2032)
			(type default)
		)
		(layer "In1.Cu")
	)
	(gr_line
		(start 173.379638 -29.083)
		(end 173.379638 -27.7368)
		(stroke
			(width 0.508)
			(type default)
		)
		(layer "In1.Cu")
	)
	(gr_line
		(start 173.424088 -26.674572)
		(end 174.363888 -26.674572)
		(stroke
			(width 0.2032)
			(type default)
		)
		(layer "In1.Cu")
	)
	(gr_line
		(start 173.424088 -25.099772)
		(end 173.424088 -26.674572)
		(stroke
			(width 0.2032)
			(type default)
		)
		(layer "In1.Cu")
	)
	(gr_line
		(start 173.430184 -13.7668)
		(end 172.363384 -13.7668)
		(stroke
			(width 0.2032)
			(type default)
		)
		(layer "In1.Cu")
	)
	(gr_line
		(start 173.430184 -11.2014)
		(end 173.430184 -13.7668)
		(stroke
			(width 0.2032)
			(type default)
		)
		(layer "In1.Cu")
	)
	(gr_line
		(start 173.430184 -9.566656)
		(end 172.363384 -9.566656)
		(stroke
			(width 0.2032)
			(type default)
		)
		(layer "In1.Cu")
	)
	(gr_line
		(start 173.430184 -7.001256)
		(end 173.430184 -9.566656)
		(stroke
			(width 0.2032)
			(type default)
		)
		(layer "In1.Cu")
	)
	(gr_line
		(start 173.430184 -5.366512)
		(end 172.363384 -5.366512)
		(stroke
			(width 0.2032)
			(type default)
		)
		(layer "In1.Cu")
	)
	(gr_line
		(start 173.430184 -2.801112)
		(end 173.430184 -5.366512)
		(stroke
			(width 0.2032)
			(type default)
		)
		(layer "In1.Cu")
	)
	(gr_line
		(start 173.430438 -29.083)
		(end 173.430438 -27.7368)
		(stroke
			(width 0.508)
			(type default)
		)
		(layer "In1.Cu")
	)
	(gr_line
		(start 173.455584 -13.7668)
		(end 172.337984 -13.7668)
		(stroke
			(width 0.1016)
			(type default)
		)
		(layer "In1.Cu")
	)
	(gr_line
		(start 173.455584 -11.176)
		(end 173.455584 -13.7668)
		(stroke
			(width 0.1016)
			(type default)
		)
		(layer "In1.Cu")
	)
	(gr_line
		(start 173.455584 -9.566656)
		(end 172.337984 -9.566656)
		(stroke
			(width 0.1016)
			(type default)
		)
		(layer "In1.Cu")
	)
	(gr_line
		(start 173.455584 -6.975856)
		(end 173.455584 -9.566656)
		(stroke
			(width 0.1016)
			(type default)
		)
		(layer "In1.Cu")
	)
	(gr_line
		(start 173.455584 -5.366512)
		(end 172.337984 -5.366512)
		(stroke
			(width 0.1016)
			(type default)
		)
		(layer "In1.Cu")
	)
	(gr_line
		(start 173.455584 -2.775712)
		(end 173.455584 -5.366512)
		(stroke
			(width 0.1016)
			(type default)
		)
		(layer "In1.Cu")
	)
	(gr_line
		(start 173.455838 -29.083)
		(end 173.455838 -27.7368)
		(stroke
			(width 0.508)
			(type default)
		)
		(layer "In1.Cu")
	)
	(gr_line
		(start 173.480984 -13.8176)
		(end 173.074584 -13.8176)
		(stroke
			(width 0.1016)
			(type default)
		)
		(layer "In1.Cu")
	)
	(gr_line
		(start 173.480984 -13.8176)
		(end 173.480984 -11.1506)
		(stroke
			(width 0.1016)
			(type default)
		)
		(layer "In1.Cu")
	)
	(gr_line
		(start 173.480984 -11.1506)
		(end 172.287184 -11.1506)
		(stroke
			(width 0.1016)
			(type default)
		)
		(layer "In1.Cu")
	)
	(gr_line
		(start 173.480984 -11.1506)
		(end 173.480984 -13.8176)
		(stroke
			(width 0.1016)
			(type default)
		)
		(layer "In1.Cu")
	)
	(gr_line
		(start 173.480984 -9.617456)
		(end 173.074584 -9.617456)
		(stroke
			(width 0.1016)
			(type default)
		)
		(layer "In1.Cu")
	)
	(gr_line
		(start 173.480984 -9.617456)
		(end 173.480984 -6.950456)
		(stroke
			(width 0.1016)
			(type default)
		)
		(layer "In1.Cu")
	)
	(gr_line
		(start 173.480984 -6.950456)
		(end 172.287184 -6.950456)
		(stroke
			(width 0.1016)
			(type default)
		)
		(layer "In1.Cu")
	)
	(gr_line
		(start 173.480984 -6.950456)
		(end 173.480984 -9.617456)
		(stroke
			(width 0.1016)
			(type default)
		)
		(layer "In1.Cu")
	)
	(gr_line
		(start 173.480984 -5.417312)
		(end 173.074584 -5.417312)
		(stroke
			(width 0.1016)
			(type default)
		)
		(layer "In1.Cu")
	)
	(gr_line
		(start 173.480984 -5.417312)
		(end 173.480984 -2.750312)
		(stroke
			(width 0.1016)
			(type default)
		)
		(layer "In1.Cu")
	)
	(gr_line
		(start 173.480984 -2.750312)
		(end 172.287184 -2.750312)
		(stroke
			(width 0.1016)
			(type default)
		)
		(layer "In1.Cu")
	)
	(gr_line
		(start 173.480984 -2.750312)
		(end 173.480984 -5.417312)
		(stroke
			(width 0.1016)
			(type default)
		)
		(layer "In1.Cu")
	)
	(gr_line
		(start 173.481238 -29.083)
		(end 173.481238 -27.7368)
		(stroke
			(width 0.508)
			(type default)
		)
		(layer "In1.Cu")
	)
	(gr_line
		(start 173.500288 -26.598372)
		(end 173.500288 -25.252172)
		(stroke
			(width 0.508)
			(type default)
		)
		(layer "In1.Cu")
	)
	(gr_line
		(start 173.506638 -29.083)
		(end 173.506638 -27.7368)
		(stroke
			(width 0.508)
			(type default)
		)
		(layer "In1.Cu")
	)
	(gr_line
		(start 173.525688 -26.598372)
		(end 174.186088 -26.598372)
		(stroke
			(width 0.508)
			(type default)
		)
		(layer "In1.Cu")
	)
	(gr_line
		(start 173.525688 -26.572972)
		(end 173.525688 -25.226772)
		(stroke
			(width 0.508)
			(type default)
		)
		(layer "In1.Cu")
	)
	(gr_line
		(start 173.525688 -25.201372)
		(end 174.160688 -25.201372)
		(stroke
			(width 0.508)
			(type default)
		)
		(layer "In1.Cu")
	)
	(gr_line
		(start 173.532038 -29.1084)
		(end 173.532038 -27.7622)
		(stroke
			(width 0.508)
			(type default)
		)
		(layer "In1.Cu")
	)
	(gr_line
		(start 173.551088 -26.572972)
		(end 173.551088 -25.226772)
		(stroke
			(width 0.508)
			(type default)
		)
		(layer "In1.Cu")
	)
	(gr_line
		(start 173.557438 -29.1084)
		(end 173.557438 -27.7622)
		(stroke
			(width 0.508)
			(type default)
		)
		(layer "In1.Cu")
	)
	(gr_line
		(start 173.557438 -29.083)
		(end 173.557438 -27.7368)
		(stroke
			(width 0.508)
			(type default)
		)
		(layer "In1.Cu")
	)
	(gr_line
		(start 173.576488 -26.572972)
		(end 173.576488 -25.226772)
		(stroke
			(width 0.508)
			(type default)
		)
		(layer "In1.Cu")
	)
	(gr_line
		(start 173.582838 -29.083)
		(end 173.582838 -27.7368)
		(stroke
			(width 0.508)
			(type default)
		)
		(layer "In1.Cu")
	)
	(gr_line
		(start 173.608238 -29.083)
		(end 173.608238 -27.7368)
		(stroke
			(width 0.508)
			(type default)
		)
		(layer "In1.Cu")
	)
	(gr_line
		(start 173.627288 -26.598372)
		(end 173.627288 -25.252172)
		(stroke
			(width 0.508)
			(type default)
		)
		(layer "In1.Cu")
	)
	(gr_line
		(start 173.627288 -26.572972)
		(end 173.627288 -25.226772)
		(stroke
			(width 0.508)
			(type default)
		)
		(layer "In1.Cu")
	)
	(gr_line
		(start 173.633638 -29.083)
		(end 173.633638 -27.7368)
		(stroke
			(width 0.508)
			(type default)
		)
		(layer "In1.Cu")
	)
	(gr_line
		(start 173.659038 -29.1084)
		(end 173.659038 -27.7622)
		(stroke
			(width 0.508)
			(type default)
		)
		(layer "In1.Cu")
	)
	(gr_line
		(start 173.659038 -29.083)
		(end 173.659038 -27.7368)
		(stroke
			(width 0.508)
			(type default)
		)
		(layer "In1.Cu")
	)
	(gr_line
		(start 173.678088 -26.572972)
		(end 173.678088 -25.226772)
		(stroke
			(width 0.508)
			(type default)
		)
		(layer "In1.Cu")
	)
	(gr_line
		(start 173.684438 -29.1084)
		(end 173.684438 -27.7622)
		(stroke
			(width 0.508)
			(type default)
		)
		(layer "In1.Cu")
	)
	(gr_line
		(start 173.684438 -29.083)
		(end 173.684438 -27.7368)
		(stroke
			(width 0.508)
			(type default)
		)
		(layer "In1.Cu")
	)
	(gr_line
		(start 173.703488 -26.547572)
		(end 173.703488 -25.201372)
		(stroke
			(width 0.508)
			(type default)
		)
		(layer "In1.Cu")
	)
	(gr_line
		(start 173.709838 -29.1084)
		(end 173.709838 -27.7622)
		(stroke
			(width 0.508)
			(type default)
		)
		(layer "In1.Cu")
	)
	(gr_line
		(start 173.728888 -26.572972)
		(end 173.728888 -25.226772)
		(stroke
			(width 0.508)
			(type default)
		)
		(layer "In1.Cu")
	)
	(gr_line
		(start 173.735238 -29.337)
		(end 174.065438 -29.337)
		(stroke
			(width 0.1016)
			(type default)
		)
		(layer "In1.Cu")
	)
	(gr_line
		(start 173.735238 -29.083)
		(end 173.735238 -27.7368)
		(stroke
			(width 0.508)
			(type default)
		)
		(layer "In1.Cu")
	)
	(gr_line
		(start 173.754288 -26.572972)
		(end 173.754288 -25.226772)
		(stroke
			(width 0.508)
			(type default)
		)
		(layer "In1.Cu")
	)
	(gr_line
		(start 173.760638 -29.1084)
		(end 173.760638 -27.7622)
		(stroke
			(width 0.508)
			(type default)
		)
		(layer "In1.Cu")
	)
	(gr_line
		(start 173.760638 -29.083)
		(end 173.760638 -27.7368)
		(stroke
			(width 0.508)
			(type default)
		)
		(layer "In1.Cu")
	)
	(gr_line
		(start 173.779688 -26.572972)
		(end 173.779688 -25.226772)
		(stroke
			(width 0.508)
			(type default)
		)
		(layer "In1.Cu")
	)
	(gr_line
		(start 173.786038 -29.1084)
		(end 173.786038 -27.7622)
		(stroke
			(width 0.508)
			(type default)
		)
		(layer "In1.Cu")
	)
	(gr_line
		(start 173.830488 -26.572972)
		(end 173.830488 -25.226772)
		(stroke
			(width 0.508)
			(type default)
		)
		(layer "In1.Cu")
	)
	(gr_line
		(start 173.855888 -26.572972)
		(end 173.855888 -25.226772)
		(stroke
			(width 0.508)
			(type default)
		)
		(layer "In1.Cu")
	)
	(gr_line
		(start 173.862238 -29.1084)
		(end 173.862238 -27.7622)
		(stroke
			(width 0.508)
			(type default)
		)
		(layer "In1.Cu")
	)
	(gr_line
		(start 173.881288 -26.572972)
		(end 173.881288 -25.226772)
		(stroke
			(width 0.508)
			(type default)
		)
		(layer "In1.Cu")
	)
	(gr_line
		(start 173.906688 -26.572972)
		(end 173.906688 -25.226772)
		(stroke
			(width 0.508)
			(type default)
		)
		(layer "In1.Cu")
	)
	(gr_line
		(start 173.932088 -26.598372)
		(end 173.932088 -25.252172)
		(stroke
			(width 0.508)
			(type default)
		)
		(layer "In1.Cu")
	)
	(gr_line
		(start 173.957488 -26.598372)
		(end 173.957488 -25.252172)
		(stroke
			(width 0.508)
			(type default)
		)
		(layer "In1.Cu")
	)
	(gr_line
		(start 173.957488 -26.572972)
		(end 173.957488 -25.226772)
		(stroke
			(width 0.508)
			(type default)
		)
		(layer "In1.Cu")
	)
	(gr_line
		(start 173.963838 -29.2608)
		(end 173.963838 -27.6098)
		(stroke
			(width 0.2032)
			(type default)
		)
		(layer "In1.Cu")
	)
	(gr_line
		(start 173.963838 -29.2354)
		(end 172.947838 -29.2354)
		(stroke
			(width 0.2032)
			(type default)
		)
		(layer "In1.Cu")
	)
	(gr_line
		(start 173.963838 -29.1846)
		(end 173.963838 -29.2354)
		(stroke
			(width 0.2032)
			(type default)
		)
		(layer "In1.Cu")
	)
	(gr_line
		(start 173.963838 -27.6098)
		(end 173.024038 -27.6098)
		(stroke
			(width 0.2032)
			(type default)
		)
		(layer "In1.Cu")
	)
	(gr_line
		(start 173.982888 -26.572972)
		(end 173.982888 -25.226772)
		(stroke
			(width 0.508)
			(type default)
		)
		(layer "In1.Cu")
	)
	(gr_line
		(start 174.008288 -26.572972)
		(end 174.008288 -25.226772)
		(stroke
			(width 0.508)
			(type default)
		)
		(layer "In1.Cu")
	)
	(gr_line
		(start 174.014638 -29.2354)
		(end 172.973238 -29.2354)
		(stroke
			(width 0.2032)
			(type default)
		)
		(layer "In1.Cu")
	)
	(gr_line
		(start 174.014638 -27.559)
		(end 174.014638 -29.2354)
		(stroke
			(width 0.2032)
			(type default)
		)
		(layer "In1.Cu")
	)
	(gr_line
		(start 174.033688 -26.572972)
		(end 174.033688 -25.226772)
		(stroke
			(width 0.508)
			(type default)
		)
		(layer "In1.Cu")
	)
	(gr_line
		(start 174.059088 -26.598372)
		(end 174.059088 -25.252172)
		(stroke
			(width 0.508)
			(type default)
		)
		(layer "In1.Cu")
	)
	(gr_line
		(start 174.059088 -26.572972)
		(end 174.059088 -25.226772)
		(stroke
			(width 0.508)
			(type default)
		)
		(layer "In1.Cu")
	)
	(gr_line
		(start 174.065438 -29.337)
		(end 174.065438 -27.4828)
		(stroke
			(width 0.1016)
			(type default)
		)
		(layer "In1.Cu")
	)
	(gr_line
		(start 174.065438 -27.4828)
		(end 172.897038 -27.4828)
		(stroke
			(width 0.1016)
			(type default)
		)
		(layer "In1.Cu")
	)
	(gr_line
		(start 174.084488 -26.598372)
		(end 174.084488 -25.252172)
		(stroke
			(width 0.508)
			(type default)
		)
		(layer "In1.Cu")
	)
	(gr_line
		(start 174.084488 -26.572972)
		(end 174.084488 -25.226772)
		(stroke
			(width 0.508)
			(type default)
		)
		(layer "In1.Cu")
	)
	(gr_line
		(start 174.109888 -26.598372)
		(end 174.109888 -25.252172)
		(stroke
			(width 0.508)
			(type default)
		)
		(layer "In1.Cu")
	)
	(gr_line
		(start 174.135288 -26.826972)
		(end 174.465488 -26.826972)
		(stroke
			(width 0.1016)
			(type default)
		)
		(layer "In1.Cu")
	)
	(gr_line
		(start 174.135288 -26.572972)
		(end 174.135288 -25.226772)
		(stroke
			(width 0.508)
			(type default)
		)
		(layer "In1.Cu")
	)
	(gr_line
		(start 174.145448 -32.9184)
		(end 172.875448 -32.9184)
		(stroke
			(width 0.7874)
			(type default)
		)
		(layer "In1.Cu")
	)
	(gr_line
		(start 174.160688 -26.598372)
		(end 174.160688 -25.252172)
		(stroke
			(width 0.508)
			(type default)
		)
		(layer "In1.Cu")
	)
	(gr_line
		(start 174.160688 -26.572972)
		(end 174.160688 -25.226772)
		(stroke
			(width 0.508)
			(type default)
		)
		(layer "In1.Cu")
	)
	(gr_line
		(start 174.186088 -26.598372)
		(end 174.186088 -25.252172)
		(stroke
			(width 0.508)
			(type default)
		)
		(layer "In1.Cu")
	)
	(gr_line
		(start 174.262288 -26.598372)
		(end 174.262288 -25.252172)
		(stroke
			(width 0.508)
			(type default)
		)
		(layer "In1.Cu")
	)
	(gr_line
		(start 174.28718 -12.563348)
		(end 175.07458 -12.563348)
		(stroke
			(width 0.1016)
			(type default)
		)
		(layer "In1.Cu")
	)
	(gr_line
		(start 174.28718 -12.512548)
		(end 174.28718 -9.896348)
		(stroke
			(width 0.1016)
			(type default)
		)
		(layer "In1.Cu")
	)
	(gr_line
		(start 174.28718 -12.463272)
		(end 175.07458 -12.463272)
		(stroke
			(width 0.1016)
			(type default)
		)
		(layer "In1.Cu")
	)
	(gr_line
		(start 174.28718 -12.412472)
		(end 174.28718 -9.796272)
		(stroke
			(width 0.1016)
			(type default)
		)
		(layer "In1.Cu")
	)
	(gr_line
		(start 174.28718 -9.896348)
		(end 174.28718 -12.563348)
		(stroke
			(width 0.1016)
			(type default)
		)
		(layer "In1.Cu")
	)
	(gr_line
		(start 174.28718 -9.896348)
		(end 175.48098 -9.896348)
		(stroke
			(width 0.1016)
			(type default)
		)
		(layer "In1.Cu")
	)
	(gr_line
		(start 174.28718 -9.796272)
		(end 174.28718 -12.463272)
		(stroke
			(width 0.1016)
			(type default)
		)
		(layer "In1.Cu")
	)
	(gr_line
		(start 174.28718 -9.796272)
		(end 175.48098 -9.796272)
		(stroke
			(width 0.1016)
			(type default)
		)
		(layer "In1.Cu")
	)
	(gr_line
		(start 174.28718 -8.363204)
		(end 175.07458 -8.363204)
		(stroke
			(width 0.1016)
			(type default)
		)
		(layer "In1.Cu")
	)
	(gr_line
		(start 174.28718 -8.312404)
		(end 174.28718 -5.696204)
		(stroke
			(width 0.1016)
			(type default)
		)
		(layer "In1.Cu")
	)
	(gr_line
		(start 174.28718 -8.263128)
		(end 175.07458 -8.263128)
		(stroke
			(width 0.1016)
			(type default)
		)
		(layer "In1.Cu")
	)
	(gr_line
		(start 174.28718 -8.212328)
		(end 174.28718 -5.596128)
		(stroke
			(width 0.1016)
			(type default)
		)
		(layer "In1.Cu")
	)
	(gr_line
		(start 174.28718 -5.696204)
		(end 174.28718 -8.363204)
		(stroke
			(width 0.1016)
			(type default)
		)
		(layer "In1.Cu")
	)
	(gr_line
		(start 174.28718 -5.696204)
		(end 175.48098 -5.696204)
		(stroke
			(width 0.1016)
			(type default)
		)
		(layer "In1.Cu")
	)
	(gr_line
		(start 174.28718 -5.596128)
		(end 174.28718 -8.263128)
		(stroke
			(width 0.1016)
			(type default)
		)
		(layer "In1.Cu")
	)
	(gr_line
		(start 174.28718 -5.596128)
		(end 175.48098 -5.596128)
		(stroke
			(width 0.1016)
			(type default)
		)
		(layer "In1.Cu")
	)
	(gr_line
		(start 174.28718 -4.16306)
		(end 175.07458 -4.16306)
		(stroke
			(width 0.1016)
			(type default)
		)
		(layer "In1.Cu")
	)
	(gr_line
		(start 174.28718 -4.11226)
		(end 174.28718 -1.49606)
		(stroke
			(width 0.1016)
			(type default)
		)
		(layer "In1.Cu")
	)
	(gr_line
		(start 174.28718 -4.062984)
		(end 175.07458 -4.062984)
		(stroke
			(width 0.1016)
			(type default)
		)
		(layer "In1.Cu")
	)
	(gr_line
		(start 174.28718 -4.012184)
		(end 174.28718 -1.395984)
		(stroke
			(width 0.1016)
			(type default)
		)
		(layer "In1.Cu")
	)
	(gr_line
		(start 174.28718 -1.49606)
		(end 174.28718 -4.16306)
		(stroke
			(width 0.1016)
			(type default)
		)
		(layer "In1.Cu")
	)
	(gr_line
		(start 174.28718 -1.49606)
		(end 175.48098 -1.49606)
		(stroke
			(width 0.1016)
			(type default)
		)
		(layer "In1.Cu")
	)
	(gr_line
		(start 174.28718 -1.395984)
		(end 174.28718 -4.062984)
		(stroke
			(width 0.1016)
			(type default)
		)
		(layer "In1.Cu")
	)
	(gr_line
		(start 174.28718 -1.395984)
		(end 175.48098 -1.395984)
		(stroke
			(width 0.1016)
			(type default)
		)
		(layer "In1.Cu")
	)
	(gr_line
		(start 174.31258 -12.512548)
		(end 174.31258 -9.921748)
		(stroke
			(width 0.1016)
			(type default)
		)
		(layer "In1.Cu")
	)
	(gr_line
		(start 174.31258 -12.412472)
		(end 174.31258 -9.821672)
		(stroke
			(width 0.1016)
			(type default)
		)
		(layer "In1.Cu")
	)
	(gr_line
		(start 174.31258 -9.921748)
		(end 175.45558 -9.921748)
		(stroke
			(width 0.1016)
			(type default)
		)
		(layer "In1.Cu")
	)
	(gr_line
		(start 174.31258 -9.821672)
		(end 175.45558 -9.821672)
		(stroke
			(width 0.1016)
			(type default)
		)
		(layer "In1.Cu")
	)
	(gr_line
		(start 174.31258 -8.312404)
		(end 174.31258 -5.721604)
		(stroke
			(width 0.1016)
			(type default)
		)
		(layer "In1.Cu")
	)
	(gr_line
		(start 174.31258 -8.212328)
		(end 174.31258 -5.621528)
		(stroke
			(width 0.1016)
			(type default)
		)
		(layer "In1.Cu")
	)
	(gr_line
		(start 174.31258 -5.721604)
		(end 175.45558 -5.721604)
		(stroke
			(width 0.1016)
			(type default)
		)
		(layer "In1.Cu")
	)
	(gr_line
		(start 174.31258 -5.621528)
		(end 175.45558 -5.621528)
		(stroke
			(width 0.1016)
			(type default)
		)
		(layer "In1.Cu")
	)
	(gr_line
		(start 174.31258 -4.11226)
		(end 174.31258 -1.52146)
		(stroke
			(width 0.1016)
			(type default)
		)
		(layer "In1.Cu")
	)
	(gr_line
		(start 174.31258 -4.012184)
		(end 174.31258 -1.421384)
		(stroke
			(width 0.1016)
			(type default)
		)
		(layer "In1.Cu")
	)
	(gr_line
		(start 174.31258 -1.52146)
		(end 175.45558 -1.52146)
		(stroke
			(width 0.1016)
			(type default)
		)
		(layer "In1.Cu")
	)
	(gr_line
		(start 174.31258 -1.421384)
		(end 175.45558 -1.421384)
		(stroke
			(width 0.1016)
			(type default)
		)
		(layer "In1.Cu")
	)
	(gr_line
		(start 174.33798 -12.512548)
		(end 174.33798 -9.947148)
		(stroke
			(width 0.1016)
			(type default)
		)
		(layer "In1.Cu")
	)
	(gr_line
		(start 174.33798 -12.412472)
		(end 174.33798 -9.847072)
		(stroke
			(width 0.1016)
			(type default)
		)
		(layer "In1.Cu")
	)
	(gr_line
		(start 174.33798 -9.947148)
		(end 174.59198 -9.947148)
		(stroke
			(width 0.1016)
			(type default)
		)
		(layer "In1.Cu")
	)
	(gr_line
		(start 174.33798 -9.847072)
		(end 174.59198 -9.847072)
		(stroke
			(width 0.1016)
			(type default)
		)
		(layer "In1.Cu")
	)
	(gr_line
		(start 174.33798 -8.312404)
		(end 174.33798 -5.747004)
		(stroke
			(width 0.1016)
			(type default)
		)
		(layer "In1.Cu")
	)
	(gr_line
		(start 174.33798 -8.212328)
		(end 174.33798 -5.646928)
		(stroke
			(width 0.1016)
			(type default)
		)
		(layer "In1.Cu")
	)
	(gr_line
		(start 174.33798 -5.747004)
		(end 174.59198 -5.747004)
		(stroke
			(width 0.1016)
			(type default)
		)
		(layer "In1.Cu")
	)
	(gr_line
		(start 174.33798 -5.646928)
		(end 174.59198 -5.646928)
		(stroke
			(width 0.1016)
			(type default)
		)
		(layer "In1.Cu")
	)
	(gr_line
		(start 174.33798 -4.11226)
		(end 174.33798 -1.54686)
		(stroke
			(width 0.1016)
			(type default)
		)
		(layer "In1.Cu")
	)
	(gr_line
		(start 174.33798 -4.012184)
		(end 174.33798 -1.446784)
		(stroke
			(width 0.1016)
			(type default)
		)
		(layer "In1.Cu")
	)
	(gr_line
		(start 174.33798 -1.54686)
		(end 174.59198 -1.54686)
		(stroke
			(width 0.1016)
			(type default)
		)
		(layer "In1.Cu")
	)
	(gr_line
		(start 174.33798 -1.446784)
		(end 174.59198 -1.446784)
		(stroke
			(width 0.1016)
			(type default)
		)
		(layer "In1.Cu")
	)
	(gr_line
		(start 174.36338 -12.512548)
		(end 174.36338 -9.947148)
		(stroke
			(width 0.2032)
			(type default)
		)
		(layer "In1.Cu")
	)
	(gr_line
		(start 174.36338 -12.412472)
		(end 174.36338 -9.847072)
		(stroke
			(width 0.2032)
			(type default)
		)
		(layer "In1.Cu")
	)
	(gr_line
		(start 174.36338 -9.947148)
		(end 175.37938 -9.947148)
		(stroke
			(width 0.2032)
			(type default)
		)
		(layer "In1.Cu")
	)
	(gr_line
		(start 174.36338 -9.847072)
		(end 175.37938 -9.847072)
		(stroke
			(width 0.2032)
			(type default)
		)
		(layer "In1.Cu")
	)
	(gr_line
		(start 174.36338 -8.312404)
		(end 174.36338 -5.747004)
		(stroke
			(width 0.2032)
			(type default)
		)
		(layer "In1.Cu")
	)
	(gr_line
		(start 174.36338 -8.212328)
		(end 174.36338 -5.646928)
		(stroke
			(width 0.2032)
			(type default)
		)
		(layer "In1.Cu")
	)
	(gr_line
		(start 174.36338 -5.747004)
		(end 175.37938 -5.747004)
		(stroke
			(width 0.2032)
			(type default)
		)
		(layer "In1.Cu")
	)
	(gr_line
		(start 174.36338 -5.646928)
		(end 175.37938 -5.646928)
		(stroke
			(width 0.2032)
			(type default)
		)
		(layer "In1.Cu")
	)
	(gr_line
		(start 174.36338 -4.11226)
		(end 174.36338 -1.54686)
		(stroke
			(width 0.2032)
			(type default)
		)
		(layer "In1.Cu")
	)
	(gr_line
		(start 174.36338 -4.012184)
		(end 174.36338 -1.446784)
		(stroke
			(width 0.2032)
			(type default)
		)
		(layer "In1.Cu")
	)
	(gr_line
		(start 174.36338 -1.54686)
		(end 175.37938 -1.54686)
		(stroke
			(width 0.2032)
			(type default)
		)
		(layer "In1.Cu")
	)
	(gr_line
		(start 174.36338 -1.446784)
		(end 175.37938 -1.446784)
		(stroke
			(width 0.2032)
			(type default)
		)
		(layer "In1.Cu")
	)
	(gr_line
		(start 174.363888 -26.750772)
		(end 174.363888 -25.099772)
		(stroke
			(width 0.2032)
			(type default)
		)
		(layer "In1.Cu")
	)
	(gr_line
		(start 174.363888 -26.725372)
		(end 173.347888 -26.725372)
		(stroke
			(width 0.2032)
			(type default)
		)
		(layer "In1.Cu")
	)
	(gr_line
		(start 174.363888 -26.674572)
		(end 174.363888 -26.725372)
		(stroke
			(width 0.2032)
			(type default)
		)
		(layer "In1.Cu")
	)
	(gr_line
		(start 174.363888 -25.099772)
		(end 173.424088 -25.099772)
		(stroke
			(width 0.2032)
			(type default)
		)
		(layer "In1.Cu")
	)
	(gr_line
		(start 174.41418 -12.487148)
		(end 174.41418 -9.997948)
		(stroke
			(width 0.2032)
			(type default)
		)
		(layer "In1.Cu")
	)
	(gr_line
		(start 174.41418 -12.487148)
		(end 174.41418 -9.997948)
		(stroke
			(width 0.254)
			(type default)
		)
		(layer "In1.Cu")
	)
	(gr_line
		(start 174.41418 -12.387072)
		(end 174.41418 -9.897872)
		(stroke
			(width 0.2032)
			(type default)
		)
		(layer "In1.Cu")
	)
	(gr_line
		(start 174.41418 -12.387072)
		(end 174.41418 -9.897872)
		(stroke
			(width 0.254)
			(type default)
		)
		(layer "In1.Cu")
	)
	(gr_line
		(start 174.41418 -9.997948)
		(end 174.61738 -9.997948)
		(stroke
			(width 0.2032)
			(type default)
		)
		(layer "In1.Cu")
	)
	(gr_line
		(start 174.41418 -9.997948)
		(end 175.30318 -9.997948)
		(stroke
			(width 0.254)
			(type default)
		)
		(layer "In1.Cu")
	)
	(gr_line
		(start 174.41418 -9.897872)
		(end 174.61738 -9.897872)
		(stroke
			(width 0.2032)
			(type default)
		)
		(layer "In1.Cu")
	)
	(gr_line
		(start 174.41418 -9.897872)
		(end 175.30318 -9.897872)
		(stroke
			(width 0.254)
			(type default)
		)
		(layer "In1.Cu")
	)
	(gr_line
		(start 174.41418 -8.287004)
		(end 174.41418 -5.797804)
		(stroke
			(width 0.2032)
			(type default)
		)
		(layer "In1.Cu")
	)
	(gr_line
		(start 174.41418 -8.287004)
		(end 174.41418 -5.797804)
		(stroke
			(width 0.254)
			(type default)
		)
		(layer "In1.Cu")
	)
	(gr_line
		(start 174.41418 -8.186928)
		(end 174.41418 -5.697728)
		(stroke
			(width 0.2032)
			(type default)
		)
		(layer "In1.Cu")
	)
	(gr_line
		(start 174.41418 -8.186928)
		(end 174.41418 -5.697728)
		(stroke
			(width 0.254)
			(type default)
		)
		(layer "In1.Cu")
	)
	(gr_line
		(start 174.41418 -5.797804)
		(end 174.61738 -5.797804)
		(stroke
			(width 0.2032)
			(type default)
		)
		(layer "In1.Cu")
	)
	(gr_line
		(start 174.41418 -5.797804)
		(end 175.30318 -5.797804)
		(stroke
			(width 0.254)
			(type default)
		)
		(layer "In1.Cu")
	)
	(gr_line
		(start 174.41418 -5.697728)
		(end 174.61738 -5.697728)
		(stroke
			(width 0.2032)
			(type default)
		)
		(layer "In1.Cu")
	)
	(gr_line
		(start 174.41418 -5.697728)
		(end 175.30318 -5.697728)
		(stroke
			(width 0.254)
			(type default)
		)
		(layer "In1.Cu")
	)
	(gr_line
		(start 174.41418 -4.08686)
		(end 174.41418 -1.59766)
		(stroke
			(width 0.2032)
			(type default)
		)
		(layer "In1.Cu")
	)
	(gr_line
		(start 174.41418 -4.08686)
		(end 174.41418 -1.59766)
		(stroke
			(width 0.254)
			(type default)
		)
		(layer "In1.Cu")
	)
	(gr_line
		(start 174.41418 -3.986784)
		(end 174.41418 -1.497584)
		(stroke
			(width 0.2032)
			(type default)
		)
		(layer "In1.Cu")
	)
	(gr_line
		(start 174.41418 -3.986784)
		(end 174.41418 -1.497584)
		(stroke
			(width 0.254)
			(type default)
		)
		(layer "In1.Cu")
	)
	(gr_line
		(start 174.41418 -1.59766)
		(end 174.61738 -1.59766)
		(stroke
			(width 0.2032)
			(type default)
		)
		(layer "In1.Cu")
	)
	(gr_line
		(start 174.41418 -1.59766)
		(end 175.30318 -1.59766)
		(stroke
			(width 0.254)
			(type default)
		)
		(layer "In1.Cu")
	)
	(gr_line
		(start 174.41418 -1.497584)
		(end 174.61738 -1.497584)
		(stroke
			(width 0.2032)
			(type default)
		)
		(layer "In1.Cu")
	)
	(gr_line
		(start 174.41418 -1.497584)
		(end 175.30318 -1.497584)
		(stroke
			(width 0.254)
			(type default)
		)
		(layer "In1.Cu")
	)
	(gr_line
		(start 174.414688 -26.725372)
		(end 173.373288 -26.725372)
		(stroke
			(width 0.2032)
			(type default)
		)
		(layer "In1.Cu")
	)
	(gr_line
		(start 174.414688 -25.048972)
		(end 174.414688 -26.725372)
		(stroke
			(width 0.2032)
			(type default)
		)
		(layer "In1.Cu")
	)
	(gr_line
		(start 174.43958 -12.461748)
		(end 174.43958 -10.023348)
		(stroke
			(width 0.254)
			(type default)
		)
		(layer "In1.Cu")
	)
	(gr_line
		(start 174.43958 -12.361672)
		(end 174.43958 -9.923272)
		(stroke
			(width 0.254)
			(type default)
		)
		(layer "In1.Cu")
	)
	(gr_line
		(start 174.43958 -10.023348)
		(end 175.27778 -10.023348)
		(stroke
			(width 0.254)
			(type default)
		)
		(layer "In1.Cu")
	)
	(gr_line
		(start 174.43958 -9.923272)
		(end 175.27778 -9.923272)
		(stroke
			(width 0.254)
			(type default)
		)
		(layer "In1.Cu")
	)
	(gr_line
		(start 174.43958 -8.261604)
		(end 174.43958 -5.823204)
		(stroke
			(width 0.254)
			(type default)
		)
		(layer "In1.Cu")
	)
	(gr_line
		(start 174.43958 -8.161528)
		(end 174.43958 -5.723128)
		(stroke
			(width 0.254)
			(type default)
		)
		(layer "In1.Cu")
	)
	(gr_line
		(start 174.43958 -5.823204)
		(end 175.27778 -5.823204)
		(stroke
			(width 0.254)
			(type default)
		)
		(layer "In1.Cu")
	)
	(gr_line
		(start 174.43958 -5.723128)
		(end 175.27778 -5.723128)
		(stroke
			(width 0.254)
			(type default)
		)
		(layer "In1.Cu")
	)
	(gr_line
		(start 174.43958 -4.06146)
		(end 174.43958 -1.62306)
		(stroke
			(width 0.254)
			(type default)
		)
		(layer "In1.Cu")
	)
	(gr_line
		(start 174.43958 -3.961384)
		(end 174.43958 -1.522984)
		(stroke
			(width 0.254)
			(type default)
		)
		(layer "In1.Cu")
	)
	(gr_line
		(start 174.43958 -1.62306)
		(end 175.27778 -1.62306)
		(stroke
			(width 0.254)
			(type default)
		)
		(layer "In1.Cu")
	)
	(gr_line
		(start 174.43958 -1.522984)
		(end 175.27778 -1.522984)
		(stroke
			(width 0.254)
			(type default)
		)
		(layer "In1.Cu")
	)
	(gr_line
		(start 174.46498 -12.436348)
		(end 174.46498 -10.048748)
		(stroke
			(width 0.254)
			(type default)
		)
		(layer "In1.Cu")
	)
	(gr_line
		(start 174.46498 -12.336272)
		(end 174.46498 -9.948672)
		(stroke
			(width 0.254)
			(type default)
		)
		(layer "In1.Cu")
	)
	(gr_line
		(start 174.46498 -10.048748)
		(end 175.25238 -10.048748)
		(stroke
			(width 0.254)
			(type default)
		)
		(layer "In1.Cu")
	)
	(gr_line
		(start 174.46498 -9.948672)
		(end 175.25238 -9.948672)
		(stroke
			(width 0.254)
			(type default)
		)
		(layer "In1.Cu")
	)
	(gr_line
		(start 174.46498 -8.236204)
		(end 174.46498 -5.848604)
		(stroke
			(width 0.254)
			(type default)
		)
		(layer "In1.Cu")
	)
	(gr_line
		(start 174.46498 -8.136128)
		(end 174.46498 -5.748528)
		(stroke
			(width 0.254)
			(type default)
		)
		(layer "In1.Cu")
	)
	(gr_line
		(start 174.46498 -5.848604)
		(end 175.25238 -5.848604)
		(stroke
			(width 0.254)
			(type default)
		)
		(layer "In1.Cu")
	)
	(gr_line
		(start 174.46498 -5.748528)
		(end 175.25238 -5.748528)
		(stroke
			(width 0.254)
			(type default)
		)
		(layer "In1.Cu")
	)
	(gr_line
		(start 174.46498 -4.03606)
		(end 174.46498 -1.64846)
		(stroke
			(width 0.254)
			(type default)
		)
		(layer "In1.Cu")
	)
	(gr_line
		(start 174.46498 -3.935984)
		(end 174.46498 -1.548384)
		(stroke
			(width 0.254)
			(type default)
		)
		(layer "In1.Cu")
	)
	(gr_line
		(start 174.46498 -1.64846)
		(end 175.25238 -1.64846)
		(stroke
			(width 0.254)
			(type default)
		)
		(layer "In1.Cu")
	)
	(gr_line
		(start 174.46498 -1.548384)
		(end 175.25238 -1.548384)
		(stroke
			(width 0.254)
			(type default)
		)
		(layer "In1.Cu")
	)
	(gr_line
		(start 174.465488 -26.826972)
		(end 174.465488 -24.972772)
		(stroke
			(width 0.1016)
			(type default)
		)
		(layer "In1.Cu")
	)
	(gr_line
		(start 174.465488 -24.972772)
		(end 173.297088 -24.972772)
		(stroke
			(width 0.1016)
			(type default)
		)
		(layer "In1.Cu")
	)
	(gr_line
		(start 174.49038 -12.360148)
		(end 175.12538 -12.360148)
		(stroke
			(width 0.508)
			(type default)
		)
		(layer "In1.Cu")
	)
	(gr_line
		(start 174.49038 -12.260072)
		(end 175.12538 -12.260072)
		(stroke
			(width 0.508)
			(type default)
		)
		(layer "In1.Cu")
	)
	(gr_line
		(start 174.49038 -10.175748)
		(end 175.12538 -10.175748)
		(stroke
			(width 0.508)
			(type default)
		)
		(layer "In1.Cu")
	)
	(gr_line
		(start 174.49038 -10.124948)
		(end 175.12538 -10.124948)
		(stroke
			(width 0.508)
			(type default)
		)
		(layer "In1.Cu")
	)
	(gr_line
		(start 174.49038 -10.075672)
		(end 175.12538 -10.075672)
		(stroke
			(width 0.508)
			(type default)
		)
		(layer "In1.Cu")
	)
	(gr_line
		(start 174.49038 -10.024872)
		(end 175.12538 -10.024872)
		(stroke
			(width 0.508)
			(type default)
		)
		(layer "In1.Cu")
	)
	(gr_line
		(start 174.49038 -8.160004)
		(end 175.12538 -8.160004)
		(stroke
			(width 0.508)
			(type default)
		)
		(layer "In1.Cu")
	)
	(gr_line
		(start 174.49038 -8.059928)
		(end 175.12538 -8.059928)
		(stroke
			(width 0.508)
			(type default)
		)
		(layer "In1.Cu")
	)
	(gr_line
		(start 174.49038 -5.975604)
		(end 175.12538 -5.975604)
		(stroke
			(width 0.508)
			(type default)
		)
		(layer "In1.Cu")
	)
	(gr_line
		(start 174.49038 -5.924804)
		(end 175.12538 -5.924804)
		(stroke
			(width 0.508)
			(type default)
		)
		(layer "In1.Cu")
	)
	(gr_line
		(start 174.49038 -5.875528)
		(end 175.12538 -5.875528)
		(stroke
			(width 0.508)
			(type default)
		)
		(layer "In1.Cu")
	)
	(gr_line
		(start 174.49038 -5.824728)
		(end 175.12538 -5.824728)
		(stroke
			(width 0.508)
			(type default)
		)
		(layer "In1.Cu")
	)
	(gr_line
		(start 174.49038 -3.95986)
		(end 175.12538 -3.95986)
		(stroke
			(width 0.508)
			(type default)
		)
		(layer "In1.Cu")
	)
	(gr_line
		(start 174.49038 -3.859784)
		(end 175.12538 -3.859784)
		(stroke
			(width 0.508)
			(type default)
		)
		(layer "In1.Cu")
	)
	(gr_line
		(start 174.49038 -1.77546)
		(end 175.12538 -1.77546)
		(stroke
			(width 0.508)
			(type default)
		)
		(layer "In1.Cu")
	)
	(gr_line
		(start 174.49038 -1.72466)
		(end 175.12538 -1.72466)
		(stroke
			(width 0.508)
			(type default)
		)
		(layer "In1.Cu")
	)
	(gr_line
		(start 174.49038 -1.675384)
		(end 175.12538 -1.675384)
		(stroke
			(width 0.508)
			(type default)
		)
		(layer "In1.Cu")
	)
	(gr_line
		(start 174.49038 -1.624584)
		(end 175.12538 -1.624584)
		(stroke
			(width 0.508)
			(type default)
		)
		(layer "In1.Cu")
	)
	(gr_line
		(start 174.51578 -10.429748)
		(end 175.15078 -10.429748)
		(stroke
			(width 0.508)
			(type default)
		)
		(layer "In1.Cu")
	)
	(gr_line
		(start 174.51578 -10.329672)
		(end 175.15078 -10.329672)
		(stroke
			(width 0.508)
			(type default)
		)
		(layer "In1.Cu")
	)
	(gr_line
		(start 174.51578 -6.229604)
		(end 175.15078 -6.229604)
		(stroke
			(width 0.508)
			(type default)
		)
		(layer "In1.Cu")
	)
	(gr_line
		(start 174.51578 -6.129528)
		(end 175.15078 -6.129528)
		(stroke
			(width 0.508)
			(type default)
		)
		(layer "In1.Cu")
	)
	(gr_line
		(start 174.51578 -2.02946)
		(end 175.15078 -2.02946)
		(stroke
			(width 0.508)
			(type default)
		)
		(layer "In1.Cu")
	)
	(gr_line
		(start 174.51578 -1.929384)
		(end 175.15078 -1.929384)
		(stroke
			(width 0.508)
			(type default)
		)
		(layer "In1.Cu")
	)
	(gr_line
		(start 174.54118 -12.385548)
		(end 174.54118 -10.124948)
		(stroke
			(width 0.254)
			(type default)
		)
		(layer "In1.Cu")
	)
	(gr_line
		(start 174.54118 -12.285472)
		(end 174.54118 -10.024872)
		(stroke
			(width 0.254)
			(type default)
		)
		(layer "In1.Cu")
	)
	(gr_line
		(start 174.54118 -12.233148)
		(end 175.17618 -12.233148)
		(stroke
			(width 0.508)
			(type default)
		)
		(layer "In1.Cu")
	)
	(gr_line
		(start 174.54118 -12.133072)
		(end 175.17618 -12.133072)
		(stroke
			(width 0.508)
			(type default)
		)
		(layer "In1.Cu")
	)
	(gr_line
		(start 174.54118 -10.124948)
		(end 175.17618 -10.124948)
		(stroke
			(width 0.254)
			(type default)
		)
		(layer "In1.Cu")
	)
	(gr_line
		(start 174.54118 -10.024872)
		(end 175.17618 -10.024872)
		(stroke
			(width 0.254)
			(type default)
		)
		(layer "In1.Cu")
	)
	(gr_line
		(start 174.54118 -8.185404)
		(end 174.54118 -5.924804)
		(stroke
			(width 0.254)
			(type default)
		)
		(layer "In1.Cu")
	)
	(gr_line
		(start 174.54118 -8.085328)
		(end 174.54118 -5.824728)
		(stroke
			(width 0.254)
			(type default)
		)
		(layer "In1.Cu")
	)
	(gr_line
		(start 174.54118 -8.033004)
		(end 175.17618 -8.033004)
		(stroke
			(width 0.508)
			(type default)
		)
		(layer "In1.Cu")
	)
	(gr_line
		(start 174.54118 -7.932928)
		(end 175.17618 -7.932928)
		(stroke
			(width 0.508)
			(type default)
		)
		(layer "In1.Cu")
	)
	(gr_line
		(start 174.54118 -5.924804)
		(end 175.17618 -5.924804)
		(stroke
			(width 0.254)
			(type default)
		)
		(layer "In1.Cu")
	)
	(gr_line
		(start 174.54118 -5.824728)
		(end 175.17618 -5.824728)
		(stroke
			(width 0.254)
			(type default)
		)
		(layer "In1.Cu")
	)
	(gr_line
		(start 174.54118 -3.98526)
		(end 174.54118 -1.72466)
		(stroke
			(width 0.254)
			(type default)
		)
		(layer "In1.Cu")
	)
	(gr_line
		(start 174.54118 -3.885184)
		(end 174.54118 -1.624584)
		(stroke
			(width 0.254)
			(type default)
		)
		(layer "In1.Cu")
	)
	(gr_line
		(start 174.54118 -3.83286)
		(end 175.17618 -3.83286)
		(stroke
			(width 0.508)
			(type default)
		)
		(layer "In1.Cu")
	)
	(gr_line
		(start 174.54118 -3.732784)
		(end 175.17618 -3.732784)
		(stroke
			(width 0.508)
			(type default)
		)
		(layer "In1.Cu")
	)
	(gr_line
		(start 174.54118 -1.72466)
		(end 175.17618 -1.72466)
		(stroke
			(width 0.254)
			(type default)
		)
		(layer "In1.Cu")
	)
	(gr_line
		(start 174.54118 -1.624584)
		(end 175.17618 -1.624584)
		(stroke
			(width 0.254)
			(type default)
		)
		(layer "In1.Cu")
	)
	(gr_line
		(start 174.56658 -12.080748)
		(end 175.20158 -12.080748)
		(stroke
			(width 0.508)
			(type default)
		)
		(layer "In1.Cu")
	)
	(gr_line
		(start 174.56658 -11.980672)
		(end 175.20158 -11.980672)
		(stroke
			(width 0.508)
			(type default)
		)
		(layer "In1.Cu")
	)
	(gr_line
		(start 174.56658 -7.880604)
		(end 175.20158 -7.880604)
		(stroke
			(width 0.508)
			(type default)
		)
		(layer "In1.Cu")
	)
	(gr_line
		(start 174.56658 -7.780528)
		(end 175.20158 -7.780528)
		(stroke
			(width 0.508)
			(type default)
		)
		(layer "In1.Cu")
	)
	(gr_line
		(start 174.56658 -3.68046)
		(end 175.20158 -3.68046)
		(stroke
			(width 0.508)
			(type default)
		)
		(layer "In1.Cu")
	)
	(gr_line
		(start 174.56658 -3.580384)
		(end 175.20158 -3.580384)
		(stroke
			(width 0.508)
			(type default)
		)
		(layer "In1.Cu")
	)
	(gr_line
		(start 174.59198 -12.360148)
		(end 175.22698 -12.360148)
		(stroke
			(width 0.508)
			(type default)
		)
		(layer "In1.Cu")
	)
	(gr_line
		(start 174.59198 -12.260072)
		(end 175.22698 -12.260072)
		(stroke
			(width 0.508)
			(type default)
		)
		(layer "In1.Cu")
	)
	(gr_line
		(start 174.59198 -9.947148)
		(end 175.43018 -9.947148)
		(stroke
			(width 0.2032)
			(type default)
		)
		(layer "In1.Cu")
	)
	(gr_line
		(start 174.59198 -9.847072)
		(end 175.43018 -9.847072)
		(stroke
			(width 0.2032)
			(type default)
		)
		(layer "In1.Cu")
	)
	(gr_line
		(start 174.59198 -8.160004)
		(end 175.22698 -8.160004)
		(stroke
			(width 0.508)
			(type default)
		)
		(layer "In1.Cu")
	)
	(gr_line
		(start 174.59198 -8.059928)
		(end 175.22698 -8.059928)
		(stroke
			(width 0.508)
			(type default)
		)
		(layer "In1.Cu")
	)
	(gr_line
		(start 174.59198 -5.747004)
		(end 175.43018 -5.747004)
		(stroke
			(width 0.2032)
			(type default)
		)
		(layer "In1.Cu")
	)
	(gr_line
		(start 174.59198 -5.646928)
		(end 175.43018 -5.646928)
		(stroke
			(width 0.2032)
			(type default)
		)
		(layer "In1.Cu")
	)
	(gr_line
		(start 174.59198 -3.95986)
		(end 175.22698 -3.95986)
		(stroke
			(width 0.508)
			(type default)
		)
		(layer "In1.Cu")
	)
	(gr_line
		(start 174.59198 -3.859784)
		(end 175.22698 -3.859784)
		(stroke
			(width 0.508)
			(type default)
		)
		(layer "In1.Cu")
	)
	(gr_line
		(start 174.59198 -1.54686)
		(end 175.43018 -1.54686)
		(stroke
			(width 0.2032)
			(type default)
		)
		(layer "In1.Cu")
	)
	(gr_line
		(start 174.59198 -1.446784)
		(end 175.43018 -1.446784)
		(stroke
			(width 0.2032)
			(type default)
		)
		(layer "In1.Cu")
	)
	(gr_line
		(start 174.61738 -12.360148)
		(end 174.61738 -10.175748)
		(stroke
			(width 0.254)
			(type default)
		)
		(layer "In1.Cu")
	)
	(gr_line
		(start 174.61738 -12.260072)
		(end 174.61738 -10.075672)
		(stroke
			(width 0.254)
			(type default)
		)
		(layer "In1.Cu")
	)
	(gr_line
		(start 174.61738 -10.175748)
		(end 175.09998 -10.175748)
		(stroke
			(width 0.254)
			(type default)
		)
		(layer "In1.Cu")
	)
	(gr_line
		(start 174.61738 -10.075672)
		(end 175.09998 -10.075672)
		(stroke
			(width 0.254)
			(type default)
		)
		(layer "In1.Cu")
	)
	(gr_line
		(start 174.61738 -9.997948)
		(end 175.35398 -9.997948)
		(stroke
			(width 0.254)
			(type default)
		)
		(layer "In1.Cu")
	)
	(gr_line
		(start 174.61738 -9.897872)
		(end 175.35398 -9.897872)
		(stroke
			(width 0.254)
			(type default)
		)
		(layer "In1.Cu")
	)
	(gr_line
		(start 174.61738 -8.160004)
		(end 174.61738 -5.975604)
		(stroke
			(width 0.254)
			(type default)
		)
		(layer "In1.Cu")
	)
	(gr_line
		(start 174.61738 -8.059928)
		(end 174.61738 -5.875528)
		(stroke
			(width 0.254)
			(type default)
		)
		(layer "In1.Cu")
	)
	(gr_line
		(start 174.61738 -5.975604)
		(end 175.09998 -5.975604)
		(stroke
			(width 0.254)
			(type default)
		)
		(layer "In1.Cu")
	)
	(gr_line
		(start 174.61738 -5.875528)
		(end 175.09998 -5.875528)
		(stroke
			(width 0.254)
			(type default)
		)
		(layer "In1.Cu")
	)
	(gr_line
		(start 174.61738 -5.797804)
		(end 175.35398 -5.797804)
		(stroke
			(width 0.254)
			(type default)
		)
		(layer "In1.Cu")
	)
	(gr_line
		(start 174.61738 -5.697728)
		(end 175.35398 -5.697728)
		(stroke
			(width 0.254)
			(type default)
		)
		(layer "In1.Cu")
	)
	(gr_line
		(start 174.61738 -3.95986)
		(end 174.61738 -1.77546)
		(stroke
			(width 0.254)
			(type default)
		)
		(layer "In1.Cu")
	)
	(gr_line
		(start 174.61738 -3.859784)
		(end 174.61738 -1.675384)
		(stroke
			(width 0.254)
			(type default)
		)
		(layer "In1.Cu")
	)
	(gr_line
		(start 174.61738 -1.77546)
		(end 175.09998 -1.77546)
		(stroke
			(width 0.254)
			(type default)
		)
		(layer "In1.Cu")
	)
	(gr_line
		(start 174.61738 -1.675384)
		(end 175.09998 -1.675384)
		(stroke
			(width 0.254)
			(type default)
		)
		(layer "In1.Cu")
	)
	(gr_line
		(start 174.61738 -1.59766)
		(end 175.35398 -1.59766)
		(stroke
			(width 0.254)
			(type default)
		)
		(layer "In1.Cu")
	)
	(gr_line
		(start 174.61738 -1.497584)
		(end 175.35398 -1.497584)
		(stroke
			(width 0.254)
			(type default)
		)
		(layer "In1.Cu")
	)
	(gr_line
		(start 174.635922 -10.110978)
		(end 175.270922 -10.110978)
		(stroke
			(width 0.508)
			(type default)
		)
		(layer "In1.Cu")
	)
	(gr_line
		(start 174.635922 -10.010902)
		(end 175.270922 -10.010902)
		(stroke
			(width 0.508)
			(type default)
		)
		(layer "In1.Cu")
	)
	(gr_line
		(start 174.635922 -5.910834)
		(end 175.270922 -5.910834)
		(stroke
			(width 0.508)
			(type default)
		)
		(layer "In1.Cu")
	)
	(gr_line
		(start 174.635922 -5.810758)
		(end 175.270922 -5.810758)
		(stroke
			(width 0.508)
			(type default)
		)
		(layer "In1.Cu")
	)
	(gr_line
		(start 174.635922 -1.71069)
		(end 175.270922 -1.71069)
		(stroke
			(width 0.508)
			(type default)
		)
		(layer "In1.Cu")
	)
	(gr_line
		(start 174.635922 -1.610614)
		(end 175.270922 -1.610614)
		(stroke
			(width 0.508)
			(type default)
		)
		(layer "In1.Cu")
	)
	(gr_line
		(start 174.64278 -12.360148)
		(end 175.27778 -12.360148)
		(stroke
			(width 0.508)
			(type default)
		)
		(layer "In1.Cu")
	)
	(gr_line
		(start 174.64278 -12.260072)
		(end 175.27778 -12.260072)
		(stroke
			(width 0.508)
			(type default)
		)
		(layer "In1.Cu")
	)
	(gr_line
		(start 174.64278 -12.233148)
		(end 174.64278 -10.251948)
		(stroke
			(width 0.762)
			(type default)
		)
		(layer "In1.Cu")
	)
	(gr_line
		(start 174.64278 -12.133072)
		(end 174.64278 -10.151872)
		(stroke
			(width 0.762)
			(type default)
		)
		(layer "In1.Cu")
	)
	(gr_line
		(start 174.64278 -10.251948)
		(end 175.27778 -10.251948)
		(stroke
			(width 0.508)
			(type default)
		)
		(layer "In1.Cu")
	)
	(gr_line
		(start 174.64278 -10.151872)
		(end 175.27778 -10.151872)
		(stroke
			(width 0.508)
			(type default)
		)
		(layer "In1.Cu")
	)
	(gr_line
		(start 174.64278 -8.160004)
		(end 175.27778 -8.160004)
		(stroke
			(width 0.508)
			(type default)
		)
		(layer "In1.Cu")
	)
	(gr_line
		(start 174.64278 -8.059928)
		(end 175.27778 -8.059928)
		(stroke
			(width 0.508)
			(type default)
		)
		(layer "In1.Cu")
	)
	(gr_line
		(start 174.64278 -8.033004)
		(end 174.64278 -6.051804)
		(stroke
			(width 0.762)
			(type default)
		)
		(layer "In1.Cu")
	)
	(gr_line
		(start 174.64278 -7.932928)
		(end 174.64278 -5.951728)
		(stroke
			(width 0.762)
			(type default)
		)
		(layer "In1.Cu")
	)
	(gr_line
		(start 174.64278 -6.051804)
		(end 175.27778 -6.051804)
		(stroke
			(width 0.508)
			(type default)
		)
		(layer "In1.Cu")
	)
	(gr_line
		(start 174.64278 -5.951728)
		(end 175.27778 -5.951728)
		(stroke
			(width 0.508)
			(type default)
		)
		(layer "In1.Cu")
	)
	(gr_line
		(start 174.64278 -3.95986)
		(end 175.27778 -3.95986)
		(stroke
			(width 0.508)
			(type default)
		)
		(layer "In1.Cu")
	)
	(gr_line
		(start 174.64278 -3.859784)
		(end 175.27778 -3.859784)
		(stroke
			(width 0.508)
			(type default)
		)
		(layer "In1.Cu")
	)
	(gr_line
		(start 174.64278 -3.83286)
		(end 174.64278 -1.85166)
		(stroke
			(width 0.762)
			(type default)
		)
		(layer "In1.Cu")
	)
	(gr_line
		(start 174.64278 -3.732784)
		(end 174.64278 -1.751584)
		(stroke
			(width 0.762)
			(type default)
		)
		(layer "In1.Cu")
	)
	(gr_line
		(start 174.64278 -1.85166)
		(end 175.27778 -1.85166)
		(stroke
			(width 0.508)
			(type default)
		)
		(layer "In1.Cu")
	)
	(gr_line
		(start 174.64278 -1.751584)
		(end 175.27778 -1.751584)
		(stroke
			(width 0.508)
			(type default)
		)
		(layer "In1.Cu")
	)
	(gr_line
		(start 174.69358 -12.283948)
		(end 174.69358 -10.251948)
		(stroke
			(width 0.254)
			(type default)
		)
		(layer "In1.Cu")
	)
	(gr_line
		(start 174.69358 -12.183872)
		(end 174.69358 -10.151872)
		(stroke
			(width 0.254)
			(type default)
		)
		(layer "In1.Cu")
	)
	(gr_line
		(start 174.69358 -10.251948)
		(end 175.02378 -10.251948)
		(stroke
			(width 0.254)
			(type default)
		)
		(layer "In1.Cu")
	)
	(gr_line
		(start 174.69358 -10.151872)
		(end 175.02378 -10.151872)
		(stroke
			(width 0.254)
			(type default)
		)
		(layer "In1.Cu")
	)
	(gr_line
		(start 174.69358 -8.083804)
		(end 174.69358 -6.051804)
		(stroke
			(width 0.254)
			(type default)
		)
		(layer "In1.Cu")
	)
	(gr_line
		(start 174.69358 -7.983728)
		(end 174.69358 -5.951728)
		(stroke
			(width 0.254)
			(type default)
		)
		(layer "In1.Cu")
	)
	(gr_line
		(start 174.69358 -6.051804)
		(end 175.02378 -6.051804)
		(stroke
			(width 0.254)
			(type default)
		)
		(layer "In1.Cu")
	)
	(gr_line
		(start 174.69358 -5.951728)
		(end 175.02378 -5.951728)
		(stroke
			(width 0.254)
			(type default)
		)
		(layer "In1.Cu")
	)
	(gr_line
		(start 174.69358 -3.88366)
		(end 174.69358 -1.85166)
		(stroke
			(width 0.254)
			(type default)
		)
		(layer "In1.Cu")
	)
	(gr_line
		(start 174.69358 -3.783584)
		(end 174.69358 -1.751584)
		(stroke
			(width 0.254)
			(type default)
		)
		(layer "In1.Cu")
	)
	(gr_line
		(start 174.69358 -1.85166)
		(end 175.02378 -1.85166)
		(stroke
			(width 0.254)
			(type default)
		)
		(layer "In1.Cu")
	)
	(gr_line
		(start 174.69358 -1.751584)
		(end 175.02378 -1.751584)
		(stroke
			(width 0.254)
			(type default)
		)
		(layer "In1.Cu")
	)
	(gr_line
		(start 174.79518 -12.207748)
		(end 174.79518 -10.404348)
		(stroke
			(width 0.254)
			(type default)
		)
		(layer "In1.Cu")
	)
	(gr_line
		(start 174.79518 -12.207748)
		(end 174.79518 -10.226548)
		(stroke
			(width 0.762)
			(type default)
		)
		(layer "In1.Cu")
	)
	(gr_line
		(start 174.79518 -12.107672)
		(end 174.79518 -10.304272)
		(stroke
			(width 0.254)
			(type default)
		)
		(layer "In1.Cu")
	)
	(gr_line
		(start 174.79518 -12.107672)
		(end 174.79518 -10.126472)
		(stroke
			(width 0.762)
			(type default)
		)
		(layer "In1.Cu")
	)
	(gr_line
		(start 174.79518 -10.404348)
		(end 174.89678 -10.404348)
		(stroke
			(width 0.254)
			(type default)
		)
		(layer "In1.Cu")
	)
	(gr_line
		(start 174.79518 -10.304272)
		(end 174.89678 -10.304272)
		(stroke
			(width 0.254)
			(type default)
		)
		(layer "In1.Cu")
	)
	(gr_line
		(start 174.79518 -8.007604)
		(end 174.79518 -6.204204)
		(stroke
			(width 0.254)
			(type default)
		)
		(layer "In1.Cu")
	)
	(gr_line
		(start 174.79518 -8.007604)
		(end 174.79518 -6.026404)
		(stroke
			(width 0.762)
			(type default)
		)
		(layer "In1.Cu")
	)
	(gr_line
		(start 174.79518 -7.907528)
		(end 174.79518 -6.104128)
		(stroke
			(width 0.254)
			(type default)
		)
		(layer "In1.Cu")
	)
	(gr_line
		(start 174.79518 -7.907528)
		(end 174.79518 -5.926328)
		(stroke
			(width 0.762)
			(type default)
		)
		(layer "In1.Cu")
	)
	(gr_line
		(start 174.79518 -6.204204)
		(end 174.89678 -6.204204)
		(stroke
			(width 0.254)
			(type default)
		)
		(layer "In1.Cu")
	)
	(gr_line
		(start 174.79518 -6.104128)
		(end 174.89678 -6.104128)
		(stroke
			(width 0.254)
			(type default)
		)
		(layer "In1.Cu")
	)
	(gr_line
		(start 174.79518 -3.80746)
		(end 174.79518 -2.00406)
		(stroke
			(width 0.254)
			(type default)
		)
		(layer "In1.Cu")
	)
	(gr_line
		(start 174.79518 -3.80746)
		(end 174.79518 -1.82626)
		(stroke
			(width 0.762)
			(type default)
		)
		(layer "In1.Cu")
	)
	(gr_line
		(start 174.79518 -3.707384)
		(end 174.79518 -1.903984)
		(stroke
			(width 0.254)
			(type default)
		)
		(layer "In1.Cu")
	)
	(gr_line
		(start 174.79518 -3.707384)
		(end 174.79518 -1.726184)
		(stroke
			(width 0.762)
			(type default)
		)
		(layer "In1.Cu")
	)
	(gr_line
		(start 174.79518 -2.00406)
		(end 174.89678 -2.00406)
		(stroke
			(width 0.254)
			(type default)
		)
		(layer "In1.Cu")
	)
	(gr_line
		(start 174.79518 -1.903984)
		(end 174.89678 -1.903984)
		(stroke
			(width 0.254)
			(type default)
		)
		(layer "In1.Cu")
	)
	(gr_line
		(start 174.89678 -12.309348)
		(end 174.84598 -12.309348)
		(stroke
			(width 0.254)
			(type default)
		)
		(layer "In1.Cu")
	)
	(gr_line
		(start 174.89678 -12.209272)
		(end 174.84598 -12.209272)
		(stroke
			(width 0.254)
			(type default)
		)
		(layer "In1.Cu")
	)
	(gr_line
		(start 174.89678 -10.404348)
		(end 174.89678 -12.309348)
		(stroke
			(width 0.254)
			(type default)
		)
		(layer "In1.Cu")
	)
	(gr_line
		(start 174.89678 -10.304272)
		(end 174.89678 -12.209272)
		(stroke
			(width 0.254)
			(type default)
		)
		(layer "In1.Cu")
	)
	(gr_line
		(start 174.89678 -8.109204)
		(end 174.84598 -8.109204)
		(stroke
			(width 0.254)
			(type default)
		)
		(layer "In1.Cu")
	)
	(gr_line
		(start 174.89678 -8.009128)
		(end 174.84598 -8.009128)
		(stroke
			(width 0.254)
			(type default)
		)
		(layer "In1.Cu")
	)
	(gr_line
		(start 174.89678 -6.204204)
		(end 174.89678 -8.109204)
		(stroke
			(width 0.254)
			(type default)
		)
		(layer "In1.Cu")
	)
	(gr_line
		(start 174.89678 -6.104128)
		(end 174.89678 -8.009128)
		(stroke
			(width 0.254)
			(type default)
		)
		(layer "In1.Cu")
	)
	(gr_line
		(start 174.89678 -3.90906)
		(end 174.84598 -3.90906)
		(stroke
			(width 0.254)
			(type default)
		)
		(layer "In1.Cu")
	)
	(gr_line
		(start 174.89678 -3.808984)
		(end 174.84598 -3.808984)
		(stroke
			(width 0.254)
			(type default)
		)
		(layer "In1.Cu")
	)
	(gr_line
		(start 174.89678 -2.00406)
		(end 174.89678 -3.90906)
		(stroke
			(width 0.254)
			(type default)
		)
		(layer "In1.Cu")
	)
	(gr_line
		(start 174.89678 -1.903984)
		(end 174.89678 -3.808984)
		(stroke
			(width 0.254)
			(type default)
		)
		(layer "In1.Cu")
	)
	(gr_line
		(start 174.94758 -12.233148)
		(end 174.94758 -10.251948)
		(stroke
			(width 0.762)
			(type default)
		)
		(layer "In1.Cu")
	)
	(gr_line
		(start 174.94758 -12.133072)
		(end 174.94758 -10.151872)
		(stroke
			(width 0.762)
			(type default)
		)
		(layer "In1.Cu")
	)
	(gr_line
		(start 174.94758 -8.033004)
		(end 174.94758 -6.051804)
		(stroke
			(width 0.762)
			(type default)
		)
		(layer "In1.Cu")
	)
	(gr_line
		(start 174.94758 -7.932928)
		(end 174.94758 -5.951728)
		(stroke
			(width 0.762)
			(type default)
		)
		(layer "In1.Cu")
	)
	(gr_line
		(start 174.94758 -3.83286)
		(end 174.94758 -1.85166)
		(stroke
			(width 0.762)
			(type default)
		)
		(layer "In1.Cu")
	)
	(gr_line
		(start 174.94758 -3.732784)
		(end 174.94758 -1.751584)
		(stroke
			(width 0.762)
			(type default)
		)
		(layer "In1.Cu")
	)
	(gr_line
		(start 175.02378 -12.207748)
		(end 174.79518 -12.207748)
		(stroke
			(width 0.254)
			(type default)
		)
		(layer "In1.Cu")
	)
	(gr_line
		(start 175.02378 -12.107672)
		(end 174.79518 -12.107672)
		(stroke
			(width 0.254)
			(type default)
		)
		(layer "In1.Cu")
	)
	(gr_line
		(start 175.02378 -10.251948)
		(end 175.02378 -12.207748)
		(stroke
			(width 0.254)
			(type default)
		)
		(layer "In1.Cu")
	)
	(gr_line
		(start 175.02378 -10.151872)
		(end 175.02378 -12.107672)
		(stroke
			(width 0.254)
			(type default)
		)
		(layer "In1.Cu")
	)
	(gr_line
		(start 175.02378 -8.007604)
		(end 174.79518 -8.007604)
		(stroke
			(width 0.254)
			(type default)
		)
		(layer "In1.Cu")
	)
	(gr_line
		(start 175.02378 -7.907528)
		(end 174.79518 -7.907528)
		(stroke
			(width 0.254)
			(type default)
		)
		(layer "In1.Cu")
	)
	(gr_line
		(start 175.02378 -6.051804)
		(end 175.02378 -8.007604)
		(stroke
			(width 0.254)
			(type default)
		)
		(layer "In1.Cu")
	)
	(gr_line
		(start 175.02378 -5.951728)
		(end 175.02378 -7.907528)
		(stroke
			(width 0.254)
			(type default)
		)
		(layer "In1.Cu")
	)
	(gr_line
		(start 175.02378 -3.80746)
		(end 174.79518 -3.80746)
		(stroke
			(width 0.254)
			(type default)
		)
		(layer "In1.Cu")
	)
	(gr_line
		(start 175.02378 -3.707384)
		(end 174.79518 -3.707384)
		(stroke
			(width 0.254)
			(type default)
		)
		(layer "In1.Cu")
	)
	(gr_line
		(start 175.02378 -1.85166)
		(end 175.02378 -3.80746)
		(stroke
			(width 0.254)
			(type default)
		)
		(layer "In1.Cu")
	)
	(gr_line
		(start 175.02378 -1.751584)
		(end 175.02378 -3.707384)
		(stroke
			(width 0.254)
			(type default)
		)
		(layer "In1.Cu")
	)
	(gr_line
		(start 175.07458 -12.563348)
		(end 175.07458 -12.512548)
		(stroke
			(width 0.1016)
			(type default)
		)
		(layer "In1.Cu")
	)
	(gr_line
		(start 175.07458 -12.563348)
		(end 175.48098 -12.563348)
		(stroke
			(width 0.1016)
			(type default)
		)
		(layer "In1.Cu")
	)
	(gr_line
		(start 175.07458 -12.512548)
		(end 174.31258 -12.512548)
		(stroke
			(width 0.1016)
			(type default)
		)
		(layer "In1.Cu")
	)
	(gr_line
		(start 175.07458 -12.463272)
		(end 175.07458 -12.412472)
		(stroke
			(width 0.1016)
			(type default)
		)
		(layer "In1.Cu")
	)
	(gr_line
		(start 175.07458 -12.463272)
		(end 175.48098 -12.463272)
		(stroke
			(width 0.1016)
			(type default)
		)
		(layer "In1.Cu")
	)
	(gr_line
		(start 175.07458 -12.412472)
		(end 174.31258 -12.412472)
		(stroke
			(width 0.1016)
			(type default)
		)
		(layer "In1.Cu")
	)
	(gr_line
		(start 175.07458 -12.233148)
		(end 175.07458 -10.251948)
		(stroke
			(width 0.762)
			(type default)
		)
		(layer "In1.Cu")
	)
	(gr_line
		(start 175.07458 -12.133072)
		(end 175.07458 -10.151872)
		(stroke
			(width 0.762)
			(type default)
		)
		(layer "In1.Cu")
	)
	(gr_line
		(start 175.07458 -8.363204)
		(end 175.07458 -8.312404)
		(stroke
			(width 0.1016)
			(type default)
		)
		(layer "In1.Cu")
	)
	(gr_line
		(start 175.07458 -8.363204)
		(end 175.48098 -8.363204)
		(stroke
			(width 0.1016)
			(type default)
		)
		(layer "In1.Cu")
	)
	(gr_line
		(start 175.07458 -8.312404)
		(end 174.31258 -8.312404)
		(stroke
			(width 0.1016)
			(type default)
		)
		(layer "In1.Cu")
	)
	(gr_line
		(start 175.07458 -8.263128)
		(end 175.07458 -8.212328)
		(stroke
			(width 0.1016)
			(type default)
		)
		(layer "In1.Cu")
	)
	(gr_line
		(start 175.07458 -8.263128)
		(end 175.48098 -8.263128)
		(stroke
			(width 0.1016)
			(type default)
		)
		(layer "In1.Cu")
	)
	(gr_line
		(start 175.07458 -8.212328)
		(end 174.31258 -8.212328)
		(stroke
			(width 0.1016)
			(type default)
		)
		(layer "In1.Cu")
	)
	(gr_line
		(start 175.07458 -8.033004)
		(end 175.07458 -6.051804)
		(stroke
			(width 0.762)
			(type default)
		)
		(layer "In1.Cu")
	)
	(gr_line
		(start 175.07458 -7.932928)
		(end 175.07458 -5.951728)
		(stroke
			(width 0.762)
			(type default)
		)
		(layer "In1.Cu")
	)
	(gr_line
		(start 175.07458 -4.16306)
		(end 175.07458 -4.11226)
		(stroke
			(width 0.1016)
			(type default)
		)
		(layer "In1.Cu")
	)
	(gr_line
		(start 175.07458 -4.16306)
		(end 175.48098 -4.16306)
		(stroke
			(width 0.1016)
			(type default)
		)
		(layer "In1.Cu")
	)
	(gr_line
		(start 175.07458 -4.11226)
		(end 174.31258 -4.11226)
		(stroke
			(width 0.1016)
			(type default)
		)
		(layer "In1.Cu")
	)
	(gr_line
		(start 175.07458 -4.062984)
		(end 175.07458 -4.012184)
		(stroke
			(width 0.1016)
			(type default)
		)
		(layer "In1.Cu")
	)
	(gr_line
		(start 175.07458 -4.062984)
		(end 175.48098 -4.062984)
		(stroke
			(width 0.1016)
			(type default)
		)
		(layer "In1.Cu")
	)
	(gr_line
		(start 175.07458 -4.012184)
		(end 174.31258 -4.012184)
		(stroke
			(width 0.1016)
			(type default)
		)
		(layer "In1.Cu")
	)
	(gr_line
		(start 175.07458 -3.83286)
		(end 175.07458 -1.85166)
		(stroke
			(width 0.762)
			(type default)
		)
		(layer "In1.Cu")
	)
	(gr_line
		(start 175.07458 -3.732784)
		(end 175.07458 -1.751584)
		(stroke
			(width 0.762)
			(type default)
		)
		(layer "In1.Cu")
	)
	(gr_line
		(start 175.09998 -12.283948)
		(end 174.69358 -12.283948)
		(stroke
			(width 0.254)
			(type default)
		)
		(layer "In1.Cu")
	)
	(gr_line
		(start 175.09998 -12.183872)
		(end 174.69358 -12.183872)
		(stroke
			(width 0.254)
			(type default)
		)
		(layer "In1.Cu")
	)
	(gr_line
		(start 175.09998 -10.175748)
		(end 175.09998 -12.283948)
		(stroke
			(width 0.254)
			(type default)
		)
		(layer "In1.Cu")
	)
	(gr_line
		(start 175.09998 -10.075672)
		(end 175.09998 -12.183872)
		(stroke
			(width 0.254)
			(type default)
		)
		(layer "In1.Cu")
	)
	(gr_line
		(start 175.09998 -8.083804)
		(end 174.69358 -8.083804)
		(stroke
			(width 0.254)
			(type default)
		)
		(layer "In1.Cu")
	)
	(gr_line
		(start 175.09998 -7.983728)
		(end 174.69358 -7.983728)
		(stroke
			(width 0.254)
			(type default)
		)
		(layer "In1.Cu")
	)
	(gr_line
		(start 175.09998 -5.975604)
		(end 175.09998 -8.083804)
		(stroke
			(width 0.254)
			(type default)
		)
		(layer "In1.Cu")
	)
	(gr_line
		(start 175.09998 -5.875528)
		(end 175.09998 -7.983728)
		(stroke
			(width 0.254)
			(type default)
		)
		(layer "In1.Cu")
	)
	(gr_line
		(start 175.09998 -3.88366)
		(end 174.69358 -3.88366)
		(stroke
			(width 0.254)
			(type default)
		)
		(layer "In1.Cu")
	)
	(gr_line
		(start 175.09998 -3.783584)
		(end 174.69358 -3.783584)
		(stroke
			(width 0.254)
			(type default)
		)
		(layer "In1.Cu")
	)
	(gr_line
		(start 175.09998 -1.77546)
		(end 175.09998 -3.88366)
		(stroke
			(width 0.254)
			(type default)
		)
		(layer "In1.Cu")
	)
	(gr_line
		(start 175.09998 -1.675384)
		(end 175.09998 -3.783584)
		(stroke
			(width 0.254)
			(type default)
		)
		(layer "In1.Cu")
	)
	(gr_line
		(start 175.15078 -12.233148)
		(end 175.15078 -10.251948)
		(stroke
			(width 0.762)
			(type default)
		)
		(layer "In1.Cu")
	)
	(gr_line
		(start 175.15078 -12.133072)
		(end 175.15078 -10.151872)
		(stroke
			(width 0.762)
			(type default)
		)
		(layer "In1.Cu")
	)
	(gr_line
		(start 175.15078 -8.033004)
		(end 175.15078 -6.051804)
		(stroke
			(width 0.762)
			(type default)
		)
		(layer "In1.Cu")
	)
	(gr_line
		(start 175.15078 -7.932928)
		(end 175.15078 -5.951728)
		(stroke
			(width 0.762)
			(type default)
		)
		(layer "In1.Cu")
	)
	(gr_line
		(start 175.15078 -3.83286)
		(end 175.15078 -1.85166)
		(stroke
			(width 0.762)
			(type default)
		)
		(layer "In1.Cu")
	)
	(gr_line
		(start 175.15078 -3.732784)
		(end 175.15078 -1.751584)
		(stroke
			(width 0.762)
			(type default)
		)
		(layer "In1.Cu")
	)
	(gr_line
		(start 175.17618 -12.360148)
		(end 174.61738 -12.360148)
		(stroke
			(width 0.254)
			(type default)
		)
		(layer "In1.Cu")
	)
	(gr_line
		(start 175.17618 -12.260072)
		(end 174.61738 -12.260072)
		(stroke
			(width 0.254)
			(type default)
		)
		(layer "In1.Cu")
	)
	(gr_line
		(start 175.17618 -10.124948)
		(end 175.17618 -12.360148)
		(stroke
			(width 0.254)
			(type default)
		)
		(layer "In1.Cu")
	)
	(gr_line
		(start 175.17618 -10.024872)
		(end 175.17618 -12.260072)
		(stroke
			(width 0.254)
			(type default)
		)
		(layer "In1.Cu")
	)
	(gr_line
		(start 175.17618 -8.160004)
		(end 174.61738 -8.160004)
		(stroke
			(width 0.254)
			(type default)
		)
		(layer "In1.Cu")
	)
	(gr_line
		(start 175.17618 -8.059928)
		(end 174.61738 -8.059928)
		(stroke
			(width 0.254)
			(type default)
		)
		(layer "In1.Cu")
	)
	(gr_line
		(start 175.17618 -5.924804)
		(end 175.17618 -8.160004)
		(stroke
			(width 0.254)
			(type default)
		)
		(layer "In1.Cu")
	)
	(gr_line
		(start 175.17618 -5.824728)
		(end 175.17618 -8.059928)
		(stroke
			(width 0.254)
			(type default)
		)
		(layer "In1.Cu")
	)
	(gr_line
		(start 175.17618 -3.95986)
		(end 174.61738 -3.95986)
		(stroke
			(width 0.254)
			(type default)
		)
		(layer "In1.Cu")
	)
	(gr_line
		(start 175.17618 -3.859784)
		(end 174.61738 -3.859784)
		(stroke
			(width 0.254)
			(type default)
		)
		(layer "In1.Cu")
	)
	(gr_line
		(start 175.17618 -1.72466)
		(end 175.17618 -3.95986)
		(stroke
			(width 0.254)
			(type default)
		)
		(layer "In1.Cu")
	)
	(gr_line
		(start 175.17618 -1.624584)
		(end 175.17618 -3.859784)
		(stroke
			(width 0.254)
			(type default)
		)
		(layer "In1.Cu")
	)
	(gr_line
		(start 175.25238 -12.385548)
		(end 174.54118 -12.385548)
		(stroke
			(width 0.254)
			(type default)
		)
		(layer "In1.Cu")
	)
	(gr_line
		(start 175.25238 -12.285472)
		(end 174.54118 -12.285472)
		(stroke
			(width 0.254)
			(type default)
		)
		(layer "In1.Cu")
	)
	(gr_line
		(start 175.25238 -10.048748)
		(end 175.25238 -12.385548)
		(stroke
			(width 0.254)
			(type default)
		)
		(layer "In1.Cu")
	)
	(gr_line
		(start 175.25238 -9.948672)
		(end 175.25238 -12.285472)
		(stroke
			(width 0.254)
			(type default)
		)
		(layer "In1.Cu")
	)
	(gr_line
		(start 175.25238 -8.185404)
		(end 174.54118 -8.185404)
		(stroke
			(width 0.254)
			(type default)
		)
		(layer "In1.Cu")
	)
	(gr_line
		(start 175.25238 -8.085328)
		(end 174.54118 -8.085328)
		(stroke
			(width 0.254)
			(type default)
		)
		(layer "In1.Cu")
	)
	(gr_line
		(start 175.25238 -5.848604)
		(end 175.25238 -8.185404)
		(stroke
			(width 0.254)
			(type default)
		)
		(layer "In1.Cu")
	)
	(gr_line
		(start 175.25238 -5.748528)
		(end 175.25238 -8.085328)
		(stroke
			(width 0.254)
			(type default)
		)
		(layer "In1.Cu")
	)
	(gr_line
		(start 175.25238 -3.98526)
		(end 174.54118 -3.98526)
		(stroke
			(width 0.254)
			(type default)
		)
		(layer "In1.Cu")
	)
	(gr_line
		(start 175.25238 -3.885184)
		(end 174.54118 -3.885184)
		(stroke
			(width 0.254)
			(type default)
		)
		(layer "In1.Cu")
	)
	(gr_line
		(start 175.25238 -1.64846)
		(end 175.25238 -3.98526)
		(stroke
			(width 0.254)
			(type default)
		)
		(layer "In1.Cu")
	)
	(gr_line
		(start 175.25238 -1.548384)
		(end 175.25238 -3.885184)
		(stroke
			(width 0.254)
			(type default)
		)
		(layer "In1.Cu")
	)
	(gr_line
		(start 175.27778 -12.512548)
		(end 174.28718 -12.512548)
		(stroke
			(width 0.1016)
			(type default)
		)
		(layer "In1.Cu")
	)
	(gr_line
		(start 175.27778 -12.436348)
		(end 174.46498 -12.436348)
		(stroke
			(width 0.254)
			(type default)
		)
		(layer "In1.Cu")
	)
	(gr_line
		(start 175.27778 -12.412472)
		(end 174.28718 -12.412472)
		(stroke
			(width 0.1016)
			(type default)
		)
		(layer "In1.Cu")
	)
	(gr_line
		(start 175.27778 -12.336272)
		(end 174.46498 -12.336272)
		(stroke
			(width 0.254)
			(type default)
		)
		(layer "In1.Cu")
	)
	(gr_line
		(start 175.27778 -10.023348)
		(end 175.27778 -12.436348)
		(stroke
			(width 0.254)
			(type default)
		)
		(layer "In1.Cu")
	)
	(gr_line
		(start 175.27778 -9.923272)
		(end 175.27778 -12.336272)
		(stroke
			(width 0.254)
			(type default)
		)
		(layer "In1.Cu")
	)
	(gr_line
		(start 175.27778 -8.312404)
		(end 174.28718 -8.312404)
		(stroke
			(width 0.1016)
			(type default)
		)
		(layer "In1.Cu")
	)
	(gr_line
		(start 175.27778 -8.236204)
		(end 174.46498 -8.236204)
		(stroke
			(width 0.254)
			(type default)
		)
		(layer "In1.Cu")
	)
	(gr_line
		(start 175.27778 -8.212328)
		(end 174.28718 -8.212328)
		(stroke
			(width 0.1016)
			(type default)
		)
		(layer "In1.Cu")
	)
	(gr_line
		(start 175.27778 -8.136128)
		(end 174.46498 -8.136128)
		(stroke
			(width 0.254)
			(type default)
		)
		(layer "In1.Cu")
	)
	(gr_line
		(start 175.27778 -5.823204)
		(end 175.27778 -8.236204)
		(stroke
			(width 0.254)
			(type default)
		)
		(layer "In1.Cu")
	)
	(gr_line
		(start 175.27778 -5.723128)
		(end 175.27778 -8.136128)
		(stroke
			(width 0.254)
			(type default)
		)
		(layer "In1.Cu")
	)
	(gr_line
		(start 175.27778 -4.11226)
		(end 174.28718 -4.11226)
		(stroke
			(width 0.1016)
			(type default)
		)
		(layer "In1.Cu")
	)
	(gr_line
		(start 175.27778 -4.03606)
		(end 174.46498 -4.03606)
		(stroke
			(width 0.254)
			(type default)
		)
		(layer "In1.Cu")
	)
	(gr_line
		(start 175.27778 -4.012184)
		(end 174.28718 -4.012184)
		(stroke
			(width 0.1016)
			(type default)
		)
		(layer "In1.Cu")
	)
	(gr_line
		(start 175.27778 -3.935984)
		(end 174.46498 -3.935984)
		(stroke
			(width 0.254)
			(type default)
		)
		(layer "In1.Cu")
	)
	(gr_line
		(start 175.27778 -1.62306)
		(end 175.27778 -4.03606)
		(stroke
			(width 0.254)
			(type default)
		)
		(layer "In1.Cu")
	)
	(gr_line
		(start 175.27778 -1.522984)
		(end 175.27778 -3.935984)
		(stroke
			(width 0.254)
			(type default)
		)
		(layer "In1.Cu")
	)
	(gr_line
		(start 175.297084 -29.337)
		(end 176.135284 -29.337)
		(stroke
			(width 0.1016)
			(type default)
		)
		(layer "In1.Cu")
	)
	(gr_line
		(start 175.297084 -27.4828)
		(end 175.297084 -29.337)
		(stroke
			(width 0.1016)
			(type default)
		)
		(layer "In1.Cu")
	)
	(gr_line
		(start 175.30318 -12.461748)
		(end 174.43958 -12.461748)
		(stroke
			(width 0.254)
			(type default)
		)
		(layer "In1.Cu")
	)
	(gr_line
		(start 175.30318 -12.361672)
		(end 174.43958 -12.361672)
		(stroke
			(width 0.254)
			(type default)
		)
		(layer "In1.Cu")
	)
	(gr_line
		(start 175.30318 -9.997948)
		(end 175.30318 -12.461748)
		(stroke
			(width 0.254)
			(type default)
		)
		(layer "In1.Cu")
	)
	(gr_line
		(start 175.30318 -9.897872)
		(end 175.30318 -12.361672)
		(stroke
			(width 0.254)
			(type default)
		)
		(layer "In1.Cu")
	)
	(gr_line
		(start 175.30318 -8.261604)
		(end 174.43958 -8.261604)
		(stroke
			(width 0.254)
			(type default)
		)
		(layer "In1.Cu")
	)
	(gr_line
		(start 175.30318 -8.161528)
		(end 174.43958 -8.161528)
		(stroke
			(width 0.254)
			(type default)
		)
		(layer "In1.Cu")
	)
	(gr_line
		(start 175.30318 -5.797804)
		(end 175.30318 -8.261604)
		(stroke
			(width 0.254)
			(type default)
		)
		(layer "In1.Cu")
	)
	(gr_line
		(start 175.30318 -5.697728)
		(end 175.30318 -8.161528)
		(stroke
			(width 0.254)
			(type default)
		)
		(layer "In1.Cu")
	)
	(gr_line
		(start 175.30318 -4.06146)
		(end 174.43958 -4.06146)
		(stroke
			(width 0.254)
			(type default)
		)
		(layer "In1.Cu")
	)
	(gr_line
		(start 175.30318 -3.961384)
		(end 174.43958 -3.961384)
		(stroke
			(width 0.254)
			(type default)
		)
		(layer "In1.Cu")
	)
	(gr_line
		(start 175.30318 -1.59766)
		(end 175.30318 -4.06146)
		(stroke
			(width 0.254)
			(type default)
		)
		(layer "In1.Cu")
	)
	(gr_line
		(start 175.30318 -1.497584)
		(end 175.30318 -3.961384)
		(stroke
			(width 0.254)
			(type default)
		)
		(layer "In1.Cu")
	)
	(gr_line
		(start 175.347884 -29.2354)
		(end 175.347884 -27.559)
		(stroke
			(width 0.2032)
			(type default)
		)
		(layer "In1.Cu")
	)
	(gr_line
		(start 175.347884 -27.559)
		(end 176.414684 -27.559)
		(stroke
			(width 0.2032)
			(type default)
		)
		(layer "In1.Cu")
	)
	(gr_line
		(start 175.35398 -12.487148)
		(end 174.41418 -12.487148)
		(stroke
			(width 0.254)
			(type default)
		)
		(layer "In1.Cu")
	)
	(gr_line
		(start 175.35398 -12.387072)
		(end 174.41418 -12.387072)
		(stroke
			(width 0.254)
			(type default)
		)
		(layer "In1.Cu")
	)
	(gr_line
		(start 175.35398 -9.997948)
		(end 175.35398 -12.487148)
		(stroke
			(width 0.254)
			(type default)
		)
		(layer "In1.Cu")
	)
	(gr_line
		(start 175.35398 -9.897872)
		(end 175.35398 -12.387072)
		(stroke
			(width 0.254)
			(type default)
		)
		(layer "In1.Cu")
	)
	(gr_line
		(start 175.35398 -8.287004)
		(end 174.41418 -8.287004)
		(stroke
			(width 0.254)
			(type default)
		)
		(layer "In1.Cu")
	)
	(gr_line
		(start 175.35398 -8.186928)
		(end 174.41418 -8.186928)
		(stroke
			(width 0.254)
			(type default)
		)
		(layer "In1.Cu")
	)
	(gr_line
		(start 175.35398 -5.797804)
		(end 175.35398 -8.287004)
		(stroke
			(width 0.254)
			(type default)
		)
		(layer "In1.Cu")
	)
	(gr_line
		(start 175.35398 -5.697728)
		(end 175.35398 -8.186928)
		(stroke
			(width 0.254)
			(type default)
		)
		(layer "In1.Cu")
	)
	(gr_line
		(start 175.35398 -4.08686)
		(end 174.41418 -4.08686)
		(stroke
			(width 0.254)
			(type default)
		)
		(layer "In1.Cu")
	)
	(gr_line
		(start 175.35398 -3.986784)
		(end 174.41418 -3.986784)
		(stroke
			(width 0.254)
			(type default)
		)
		(layer "In1.Cu")
	)
	(gr_line
		(start 175.35398 -1.59766)
		(end 175.35398 -4.08686)
		(stroke
			(width 0.254)
			(type default)
		)
		(layer "In1.Cu")
	)
	(gr_line
		(start 175.35398 -1.497584)
		(end 175.35398 -3.986784)
		(stroke
			(width 0.254)
			(type default)
		)
		(layer "In1.Cu")
	)
	(gr_line
		(start 175.373284 -29.2608)
		(end 176.363884 -29.2608)
		(stroke
			(width 0.2032)
			(type default)
		)
		(layer "In1.Cu")
	)
	(gr_line
		(start 175.373284 -29.2354)
		(end 175.373284 -29.2608)
		(stroke
			(width 0.2032)
			(type default)
		)
		(layer "In1.Cu")
	)
	(gr_line
		(start 175.37938 -12.487148)
		(end 174.41418 -12.487148)
		(stroke
			(width 0.2032)
			(type default)
		)
		(layer "In1.Cu")
	)
	(gr_line
		(start 175.37938 -12.387072)
		(end 174.41418 -12.387072)
		(stroke
			(width 0.2032)
			(type default)
		)
		(layer "In1.Cu")
	)
	(gr_line
		(start 175.37938 -9.947148)
		(end 175.37938 -12.487148)
		(stroke
			(width 0.2032)
			(type default)
		)
		(layer "In1.Cu")
	)
	(gr_line
		(start 175.37938 -9.847072)
		(end 175.37938 -12.387072)
		(stroke
			(width 0.2032)
			(type default)
		)
		(layer "In1.Cu")
	)
	(gr_line
		(start 175.37938 -8.287004)
		(end 174.41418 -8.287004)
		(stroke
			(width 0.2032)
			(type default)
		)
		(layer "In1.Cu")
	)
	(gr_line
		(start 175.37938 -8.186928)
		(end 174.41418 -8.186928)
		(stroke
			(width 0.2032)
			(type default)
		)
		(layer "In1.Cu")
	)
	(gr_line
		(start 175.37938 -5.747004)
		(end 175.37938 -8.287004)
		(stroke
			(width 0.2032)
			(type default)
		)
		(layer "In1.Cu")
	)
	(gr_line
		(start 175.37938 -5.646928)
		(end 175.37938 -8.186928)
		(stroke
			(width 0.2032)
			(type default)
		)
		(layer "In1.Cu")
	)
	(gr_line
		(start 175.37938 -4.08686)
		(end 174.41418 -4.08686)
		(stroke
			(width 0.2032)
			(type default)
		)
		(layer "In1.Cu")
	)
	(gr_line
		(start 175.37938 -3.986784)
		(end 174.41418 -3.986784)
		(stroke
			(width 0.2032)
			(type default)
		)
		(layer "In1.Cu")
	)
	(gr_line
		(start 175.37938 -1.54686)
		(end 175.37938 -4.08686)
		(stroke
			(width 0.2032)
			(type default)
		)
		(layer "In1.Cu")
	)
	(gr_line
		(start 175.37938 -1.446784)
		(end 175.37938 -3.986784)
		(stroke
			(width 0.2032)
			(type default)
		)
		(layer "In1.Cu")
	)
	(gr_line
		(start 175.424084 -29.1846)
		(end 176.363884 -29.1846)
		(stroke
			(width 0.2032)
			(type default)
		)
		(layer "In1.Cu")
	)
	(gr_line
		(start 175.424084 -27.6098)
		(end 175.424084 -29.1846)
		(stroke
			(width 0.2032)
			(type default)
		)
		(layer "In1.Cu")
	)
	(gr_line
		(start 175.43018 -12.512548)
		(end 174.36338 -12.512548)
		(stroke
			(width 0.2032)
			(type default)
		)
		(layer "In1.Cu")
	)
	(gr_line
		(start 175.43018 -12.412472)
		(end 174.36338 -12.412472)
		(stroke
			(width 0.2032)
			(type default)
		)
		(layer "In1.Cu")
	)
	(gr_line
		(start 175.43018 -9.947148)
		(end 175.43018 -12.512548)
		(stroke
			(width 0.2032)
			(type default)
		)
		(layer "In1.Cu")
	)
	(gr_line
		(start 175.43018 -9.847072)
		(end 175.43018 -12.412472)
		(stroke
			(width 0.2032)
			(type default)
		)
		(layer "In1.Cu")
	)
	(gr_line
		(start 175.43018 -8.312404)
		(end 174.36338 -8.312404)
		(stroke
			(width 0.2032)
			(type default)
		)
		(layer "In1.Cu")
	)
	(gr_line
		(start 175.43018 -8.212328)
		(end 174.36338 -8.212328)
		(stroke
			(width 0.2032)
			(type default)
		)
		(layer "In1.Cu")
	)
	(gr_line
		(start 175.43018 -5.747004)
		(end 175.43018 -8.312404)
		(stroke
			(width 0.2032)
			(type default)
		)
		(layer "In1.Cu")
	)
	(gr_line
		(start 175.43018 -5.646928)
		(end 175.43018 -8.212328)
		(stroke
			(width 0.2032)
			(type default)
		)
		(layer "In1.Cu")
	)
	(gr_line
		(start 175.43018 -4.11226)
		(end 174.36338 -4.11226)
		(stroke
			(width 0.2032)
			(type default)
		)
		(layer "In1.Cu")
	)
	(gr_line
		(start 175.43018 -4.012184)
		(end 174.36338 -4.012184)
		(stroke
			(width 0.2032)
			(type default)
		)
		(layer "In1.Cu")
	)
	(gr_line
		(start 175.43018 -1.54686)
		(end 175.43018 -4.11226)
		(stroke
			(width 0.2032)
			(type default)
		)
		(layer "In1.Cu")
	)
	(gr_line
		(start 175.43018 -1.446784)
		(end 175.43018 -4.012184)
		(stroke
			(width 0.2032)
			(type default)
		)
		(layer "In1.Cu")
	)
	(gr_line
		(start 175.45558 -12.512548)
		(end 174.33798 -12.512548)
		(stroke
			(width 0.1016)
			(type default)
		)
		(layer "In1.Cu")
	)
	(gr_line
		(start 175.45558 -12.412472)
		(end 174.33798 -12.412472)
		(stroke
			(width 0.1016)
			(type default)
		)
		(layer "In1.Cu")
	)
	(gr_line
		(start 175.45558 -9.921748)
		(end 175.45558 -12.512548)
		(stroke
			(width 0.1016)
			(type default)
		)
		(layer "In1.Cu")
	)
	(gr_line
		(start 175.45558 -9.821672)
		(end 175.45558 -12.412472)
		(stroke
			(width 0.1016)
			(type default)
		)
		(layer "In1.Cu")
	)
	(gr_line
		(start 175.45558 -8.312404)
		(end 174.33798 -8.312404)
		(stroke
			(width 0.1016)
			(type default)
		)
		(layer "In1.Cu")
	)
	(gr_line
		(start 175.45558 -8.212328)
		(end 174.33798 -8.212328)
		(stroke
			(width 0.1016)
			(type default)
		)
		(layer "In1.Cu")
	)
	(gr_line
		(start 175.45558 -5.721604)
		(end 175.45558 -8.312404)
		(stroke
			(width 0.1016)
			(type default)
		)
		(layer "In1.Cu")
	)
	(gr_line
		(start 175.45558 -5.621528)
		(end 175.45558 -8.212328)
		(stroke
			(width 0.1016)
			(type default)
		)
		(layer "In1.Cu")
	)
	(gr_line
		(start 175.45558 -4.11226)
		(end 174.33798 -4.11226)
		(stroke
			(width 0.1016)
			(type default)
		)
		(layer "In1.Cu")
	)
	(gr_line
		(start 175.45558 -4.012184)
		(end 174.33798 -4.012184)
		(stroke
			(width 0.1016)
			(type default)
		)
		(layer "In1.Cu")
	)
	(gr_line
		(start 175.45558 -1.52146)
		(end 175.45558 -4.11226)
		(stroke
			(width 0.1016)
			(type default)
		)
		(layer "In1.Cu")
	)
	(gr_line
		(start 175.45558 -1.421384)
		(end 175.45558 -4.012184)
		(stroke
			(width 0.1016)
			(type default)
		)
		(layer "In1.Cu")
	)
	(gr_line
		(start 175.48098 -12.563348)
		(end 175.07458 -12.563348)
		(stroke
			(width 0.1016)
			(type default)
		)
		(layer "In1.Cu")
	)
	(gr_line
		(start 175.48098 -12.563348)
		(end 175.48098 -9.896348)
		(stroke
			(width 0.1016)
			(type default)
		)
		(layer "In1.Cu")
	)
	(gr_line
		(start 175.48098 -12.463272)
		(end 175.07458 -12.463272)
		(stroke
			(width 0.1016)
			(type default)
		)
		(layer "In1.Cu")
	)
	(gr_line
		(start 175.48098 -12.463272)
		(end 175.48098 -9.796272)
		(stroke
			(width 0.1016)
			(type default)
		)
		(layer "In1.Cu")
	)
	(gr_line
		(start 175.48098 -9.896348)
		(end 174.28718 -9.896348)
		(stroke
			(width 0.1016)
			(type default)
		)
		(layer "In1.Cu")
	)
	(gr_line
		(start 175.48098 -9.896348)
		(end 175.48098 -12.563348)
		(stroke
			(width 0.1016)
			(type default)
		)
		(layer "In1.Cu")
	)
	(gr_line
		(start 175.48098 -9.796272)
		(end 174.28718 -9.796272)
		(stroke
			(width 0.1016)
			(type default)
		)
		(layer "In1.Cu")
	)
	(gr_line
		(start 175.48098 -9.796272)
		(end 175.48098 -12.463272)
		(stroke
			(width 0.1016)
			(type default)
		)
		(layer "In1.Cu")
	)
	(gr_line
		(start 175.48098 -8.363204)
		(end 175.07458 -8.363204)
		(stroke
			(width 0.1016)
			(type default)
		)
		(layer "In1.Cu")
	)
	(gr_line
		(start 175.48098 -8.363204)
		(end 175.48098 -5.696204)
		(stroke
			(width 0.1016)
			(type default)
		)
		(layer "In1.Cu")
	)
	(gr_line
		(start 175.48098 -8.263128)
		(end 175.07458 -8.263128)
		(stroke
			(width 0.1016)
			(type default)
		)
		(layer "In1.Cu")
	)
	(gr_line
		(start 175.48098 -8.263128)
		(end 175.48098 -5.596128)
		(stroke
			(width 0.1016)
			(type default)
		)
		(layer "In1.Cu")
	)
	(gr_line
		(start 175.48098 -5.696204)
		(end 174.28718 -5.696204)
		(stroke
			(width 0.1016)
			(type default)
		)
		(layer "In1.Cu")
	)
	(gr_line
		(start 175.48098 -5.696204)
		(end 175.48098 -8.363204)
		(stroke
			(width 0.1016)
			(type default)
		)
		(layer "In1.Cu")
	)
	(gr_line
		(start 175.48098 -5.596128)
		(end 174.28718 -5.596128)
		(stroke
			(width 0.1016)
			(type default)
		)
		(layer "In1.Cu")
	)
	(gr_line
		(start 175.48098 -5.596128)
		(end 175.48098 -8.263128)
		(stroke
			(width 0.1016)
			(type default)
		)
		(layer "In1.Cu")
	)
	(gr_line
		(start 175.48098 -4.16306)
		(end 175.07458 -4.16306)
		(stroke
			(width 0.1016)
			(type default)
		)
		(layer "In1.Cu")
	)
	(gr_line
		(start 175.48098 -4.16306)
		(end 175.48098 -1.49606)
		(stroke
			(width 0.1016)
			(type default)
		)
		(layer "In1.Cu")
	)
	(gr_line
		(start 175.48098 -4.062984)
		(end 175.07458 -4.062984)
		(stroke
			(width 0.1016)
			(type default)
		)
		(layer "In1.Cu")
	)
	(gr_line
		(start 175.48098 -4.062984)
		(end 175.48098 -1.395984)
		(stroke
			(width 0.1016)
			(type default)
		)
		(layer "In1.Cu")
	)
	(gr_line
		(start 175.48098 -1.49606)
		(end 174.28718 -1.49606)
		(stroke
			(width 0.1016)
			(type default)
		)
		(layer "In1.Cu")
	)
	(gr_line
		(start 175.48098 -1.49606)
		(end 175.48098 -4.16306)
		(stroke
			(width 0.1016)
			(type default)
		)
		(layer "In1.Cu")
	)
	(gr_line
		(start 175.48098 -1.395984)
		(end 174.28718 -1.395984)
		(stroke
			(width 0.1016)
			(type default)
		)
		(layer "In1.Cu")
	)
	(gr_line
		(start 175.48098 -1.395984)
		(end 175.48098 -4.062984)
		(stroke
			(width 0.1016)
			(type default)
		)
		(layer "In1.Cu")
	)
	(gr_line
		(start 175.500284 -29.1084)
		(end 175.500284 -27.7622)
		(stroke
			(width 0.508)
			(type default)
		)
		(layer "In1.Cu")
	)
	(gr_line
		(start 175.525684 -29.1084)
		(end 176.186084 -29.1084)
		(stroke
			(width 0.508)
			(type default)
		)
		(layer "In1.Cu")
	)
	(gr_line
		(start 175.525684 -29.083)
		(end 175.525684 -27.7368)
		(stroke
			(width 0.508)
			(type default)
		)
		(layer "In1.Cu")
	)
	(gr_line
		(start 175.525684 -27.7114)
		(end 176.160684 -27.7114)
		(stroke
			(width 0.508)
			(type default)
		)
		(layer "In1.Cu")
	)
	(gr_line
		(start 175.551084 -29.083)
		(end 175.551084 -27.7368)
		(stroke
			(width 0.508)
			(type default)
		)
		(layer "In1.Cu")
	)
	(gr_line
		(start 175.576484 -29.083)
		(end 175.576484 -27.7368)
		(stroke
			(width 0.508)
			(type default)
		)
		(layer "In1.Cu")
	)
	(gr_line
		(start 175.627284 -29.1084)
		(end 175.627284 -27.7622)
		(stroke
			(width 0.508)
			(type default)
		)
		(layer "In1.Cu")
	)
	(gr_line
		(start 175.627284 -29.083)
		(end 175.627284 -27.7368)
		(stroke
			(width 0.508)
			(type default)
		)
		(layer "In1.Cu")
	)
	(gr_line
		(start 175.678084 -29.083)
		(end 175.678084 -27.7368)
		(stroke
			(width 0.508)
			(type default)
		)
		(layer "In1.Cu")
	)
	(gr_line
		(start 175.697134 -26.826972)
		(end 176.535334 -26.826972)
		(stroke
			(width 0.1016)
			(type default)
		)
		(layer "In1.Cu")
	)
	(gr_line
		(start 175.697134 -24.972772)
		(end 175.697134 -26.826972)
		(stroke
			(width 0.1016)
			(type default)
		)
		(layer "In1.Cu")
	)
	(gr_line
		(start 175.703484 -29.0576)
		(end 175.703484 -27.7114)
		(stroke
			(width 0.508)
			(type default)
		)
		(layer "In1.Cu")
	)
	(gr_line
		(start 175.728884 -29.083)
		(end 175.728884 -27.7368)
		(stroke
			(width 0.508)
			(type default)
		)
		(layer "In1.Cu")
	)
	(gr_line
		(start 175.747934 -26.725372)
		(end 175.747934 -25.048972)
		(stroke
			(width 0.2032)
			(type default)
		)
		(layer "In1.Cu")
	)
	(gr_line
		(start 175.747934 -25.048972)
		(end 176.814734 -25.048972)
		(stroke
			(width 0.2032)
			(type default)
		)
		(layer "In1.Cu")
	)
	(gr_line
		(start 175.754284 -29.083)
		(end 175.754284 -27.7368)
		(stroke
			(width 0.508)
			(type default)
		)
		(layer "In1.Cu")
	)
	(gr_line
		(start 175.773334 -26.750772)
		(end 176.763934 -26.750772)
		(stroke
			(width 0.2032)
			(type default)
		)
		(layer "In1.Cu")
	)
	(gr_line
		(start 175.773334 -26.725372)
		(end 175.773334 -26.750772)
		(stroke
			(width 0.2032)
			(type default)
		)
		(layer "In1.Cu")
	)
	(gr_line
		(start 175.779684 -29.083)
		(end 175.779684 -27.7368)
		(stroke
			(width 0.508)
			(type default)
		)
		(layer "In1.Cu")
	)
	(gr_line
		(start 175.824134 -26.674572)
		(end 176.763934 -26.674572)
		(stroke
			(width 0.2032)
			(type default)
		)
		(layer "In1.Cu")
	)
	(gr_line
		(start 175.824134 -25.099772)
		(end 175.824134 -26.674572)
		(stroke
			(width 0.2032)
			(type default)
		)
		(layer "In1.Cu")
	)
	(gr_line
		(start 175.830484 -29.083)
		(end 175.830484 -27.7368)
		(stroke
			(width 0.508)
			(type default)
		)
		(layer "In1.Cu")
	)
	(gr_line
		(start 175.855884 -29.083)
		(end 175.855884 -27.7368)
		(stroke
			(width 0.508)
			(type default)
		)
		(layer "In1.Cu")
	)
	(gr_line
		(start 175.881284 -29.083)
		(end 175.881284 -27.7368)
		(stroke
			(width 0.508)
			(type default)
		)
		(layer "In1.Cu")
	)
	(gr_line
		(start 175.900334 -26.598372)
		(end 175.900334 -25.252172)
		(stroke
			(width 0.508)
			(type default)
		)
		(layer "In1.Cu")
	)
	(gr_line
		(start 175.906684 -29.083)
		(end 175.906684 -27.7368)
		(stroke
			(width 0.508)
			(type default)
		)
		(layer "In1.Cu")
	)
	(gr_line
		(start 175.925734 -26.598372)
		(end 176.586134 -26.598372)
		(stroke
			(width 0.508)
			(type default)
		)
		(layer "In1.Cu")
	)
	(gr_line
		(start 175.925734 -26.572972)
		(end 175.925734 -25.226772)
		(stroke
			(width 0.508)
			(type default)
		)
		(layer "In1.Cu")
	)
	(gr_line
		(start 175.925734 -25.201372)
		(end 176.560734 -25.201372)
		(stroke
			(width 0.508)
			(type default)
		)
		(layer "In1.Cu")
	)
	(gr_line
		(start 175.932084 -29.1084)
		(end 175.932084 -27.7622)
		(stroke
			(width 0.508)
			(type default)
		)
		(layer "In1.Cu")
	)
	(gr_line
		(start 175.951134 -26.572972)
		(end 175.951134 -25.226772)
		(stroke
			(width 0.508)
			(type default)
		)
		(layer "In1.Cu")
	)
	(gr_line
		(start 175.957484 -29.1084)
		(end 175.957484 -27.7622)
		(stroke
			(width 0.508)
			(type default)
		)
		(layer "In1.Cu")
	)
	(gr_line
		(start 175.957484 -29.083)
		(end 175.957484 -27.7368)
		(stroke
			(width 0.508)
			(type default)
		)
		(layer "In1.Cu")
	)
	(gr_line
		(start 175.976534 -26.572972)
		(end 175.976534 -25.226772)
		(stroke
			(width 0.508)
			(type default)
		)
		(layer "In1.Cu")
	)
	(gr_line
		(start 175.982884 -29.083)
		(end 175.982884 -27.7368)
		(stroke
			(width 0.508)
			(type default)
		)
		(layer "In1.Cu")
	)
	(gr_line
		(start 176.008284 -29.083)
		(end 176.008284 -27.7368)
		(stroke
			(width 0.508)
			(type default)
		)
		(layer "In1.Cu")
	)
	(gr_line
		(start 176.027334 -26.598372)
		(end 176.027334 -25.252172)
		(stroke
			(width 0.508)
			(type default)
		)
		(layer "In1.Cu")
	)
	(gr_line
		(start 176.027334 -26.572972)
		(end 176.027334 -25.226772)
		(stroke
			(width 0.508)
			(type default)
		)
		(layer "In1.Cu")
	)
	(gr_line
		(start 176.033684 -29.083)
		(end 176.033684 -27.7368)
		(stroke
			(width 0.508)
			(type default)
		)
		(layer "In1.Cu")
	)
	(gr_line
		(start 176.059084 -29.1084)
		(end 176.059084 -27.7622)
		(stroke
			(width 0.508)
			(type default)
		)
		(layer "In1.Cu")
	)
	(gr_line
		(start 176.059084 -29.083)
		(end 176.059084 -27.7368)
		(stroke
			(width 0.508)
			(type default)
		)
		(layer "In1.Cu")
	)
	(gr_line
		(start 176.078134 -26.572972)
		(end 176.078134 -25.226772)
		(stroke
			(width 0.508)
			(type default)
		)
		(layer "In1.Cu")
	)
	(gr_line
		(start 176.084484 -29.1084)
		(end 176.084484 -27.7622)
		(stroke
			(width 0.508)
			(type default)
		)
		(layer "In1.Cu")
	)
	(gr_line
		(start 176.084484 -29.083)
		(end 176.084484 -27.7368)
		(stroke
			(width 0.508)
			(type default)
		)
		(layer "In1.Cu")
	)
	(gr_line
		(start 176.103534 -26.547572)
		(end 176.103534 -25.201372)
		(stroke
			(width 0.508)
			(type default)
		)
		(layer "In1.Cu")
	)
	(gr_line
		(start 176.109884 -29.1084)
		(end 176.109884 -27.7622)
		(stroke
			(width 0.508)
			(type default)
		)
		(layer "In1.Cu")
	)
	(gr_line
		(start 176.128934 -26.572972)
		(end 176.128934 -25.226772)
		(stroke
			(width 0.508)
			(type default)
		)
		(layer "In1.Cu")
	)
	(gr_line
		(start 176.135284 -29.337)
		(end 176.465484 -29.337)
		(stroke
			(width 0.1016)
			(type default)
		)
		(layer "In1.Cu")
	)
	(gr_line
		(start 176.135284 -29.083)
		(end 176.135284 -27.7368)
		(stroke
			(width 0.508)
			(type default)
		)
		(layer "In1.Cu")
	)
	(gr_line
		(start 176.154334 -26.572972)
		(end 176.154334 -25.226772)
		(stroke
			(width 0.508)
			(type default)
		)
		(layer "In1.Cu")
	)
	(gr_line
		(start 176.160684 -29.1084)
		(end 176.160684 -27.7622)
		(stroke
			(width 0.508)
			(type default)
		)
		(layer "In1.Cu")
	)
	(gr_line
		(start 176.160684 -29.083)
		(end 176.160684 -27.7368)
		(stroke
			(width 0.508)
			(type default)
		)
		(layer "In1.Cu")
	)
	(gr_line
		(start 176.179734 -26.572972)
		(end 176.179734 -25.226772)
		(stroke
			(width 0.508)
			(type default)
		)
		(layer "In1.Cu")
	)
	(gr_line
		(start 176.186084 -29.1084)
		(end 176.186084 -27.7622)
		(stroke
			(width 0.508)
			(type default)
		)
		(layer "In1.Cu")
	)
	(gr_line
		(start 176.230534 -26.572972)
		(end 176.230534 -25.226772)
		(stroke
			(width 0.508)
			(type default)
		)
		(layer "In1.Cu")
	)
	(gr_line
		(start 176.255934 -26.572972)
		(end 176.255934 -25.226772)
		(stroke
			(width 0.508)
			(type default)
		)
		(layer "In1.Cu")
	)
	(gr_line
		(start 176.262284 -29.1084)
		(end 176.262284 -27.7622)
		(stroke
			(width 0.508)
			(type default)
		)
		(layer "In1.Cu")
	)
	(gr_line
		(start 176.281334 -26.572972)
		(end 176.281334 -25.226772)
		(stroke
			(width 0.508)
			(type default)
		)
		(layer "In1.Cu")
	)
	(gr_line
		(start 176.306734 -26.572972)
		(end 176.306734 -25.226772)
		(stroke
			(width 0.508)
			(type default)
		)
		(layer "In1.Cu")
	)
	(gr_line
		(start 176.332134 -26.598372)
		(end 176.332134 -25.252172)
		(stroke
			(width 0.508)
			(type default)
		)
		(layer "In1.Cu")
	)
	(gr_line
		(start 176.357534 -26.598372)
		(end 176.357534 -25.252172)
		(stroke
			(width 0.508)
			(type default)
		)
		(layer "In1.Cu")
	)
	(gr_line
		(start 176.357534 -26.572972)
		(end 176.357534 -25.226772)
		(stroke
			(width 0.508)
			(type default)
		)
		(layer "In1.Cu")
	)
	(gr_line
		(start 176.363884 -29.2608)
		(end 176.363884 -27.6098)
		(stroke
			(width 0.2032)
			(type default)
		)
		(layer "In1.Cu")
	)
	(gr_line
		(start 176.363884 -29.2354)
		(end 175.347884 -29.2354)
		(stroke
			(width 0.2032)
			(type default)
		)
		(layer "In1.Cu")
	)
	(gr_line
		(start 176.363884 -29.1846)
		(end 176.363884 -29.2354)
		(stroke
			(width 0.2032)
			(type default)
		)
		(layer "In1.Cu")
	)
	(gr_line
		(start 176.363884 -27.6098)
		(end 175.424084 -27.6098)
		(stroke
			(width 0.2032)
			(type default)
		)
		(layer "In1.Cu")
	)
	(gr_line
		(start 176.382934 -26.572972)
		(end 176.382934 -25.226772)
		(stroke
			(width 0.508)
			(type default)
		)
		(layer "In1.Cu")
	)
	(gr_line
		(start 176.408334 -26.572972)
		(end 176.408334 -25.226772)
		(stroke
			(width 0.508)
			(type default)
		)
		(layer "In1.Cu")
	)
	(gr_line
		(start 176.414684 -29.2354)
		(end 175.373284 -29.2354)
		(stroke
			(width 0.2032)
			(type default)
		)
		(layer "In1.Cu")
	)
	(gr_line
		(start 176.414684 -27.559)
		(end 176.414684 -29.2354)
		(stroke
			(width 0.2032)
			(type default)
		)
		(layer "In1.Cu")
	)
	(gr_line
		(start 176.433734 -26.572972)
		(end 176.433734 -25.226772)
		(stroke
			(width 0.508)
			(type default)
		)
		(layer "In1.Cu")
	)
	(gr_line
		(start 176.459134 -26.598372)
		(end 176.459134 -25.252172)
		(stroke
			(width 0.508)
			(type default)
		)
		(layer "In1.Cu")
	)
	(gr_line
		(start 176.459134 -26.572972)
		(end 176.459134 -25.226772)
		(stroke
			(width 0.508)
			(type default)
		)
		(layer "In1.Cu")
	)
	(gr_line
		(start 176.465484 -29.337)
		(end 176.465484 -27.4828)
		(stroke
			(width 0.1016)
			(type default)
		)
		(layer "In1.Cu")
	)
	(gr_line
		(start 176.465484 -27.4828)
		(end 175.297084 -27.4828)
		(stroke
			(width 0.1016)
			(type default)
		)
		(layer "In1.Cu")
	)
	(gr_line
		(start 176.484534 -26.598372)
		(end 176.484534 -25.252172)
		(stroke
			(width 0.508)
			(type default)
		)
		(layer "In1.Cu")
	)
	(gr_line
		(start 176.484534 -26.572972)
		(end 176.484534 -25.226772)
		(stroke
			(width 0.508)
			(type default)
		)
		(layer "In1.Cu")
	)
	(gr_line
		(start 176.509934 -26.598372)
		(end 176.509934 -25.252172)
		(stroke
			(width 0.508)
			(type default)
		)
		(layer "In1.Cu")
	)
	(gr_line
		(start 176.520094 -30.99562)
		(end 175.250094 -30.99562)
		(stroke
			(width 0.7874)
			(type default)
		)
		(layer "In1.Cu")
	)
	(gr_line
		(start 176.535334 -26.826972)
		(end 176.865534 -26.826972)
		(stroke
			(width 0.1016)
			(type default)
		)
		(layer "In1.Cu")
	)
	(gr_line
		(start 176.535334 -26.572972)
		(end 176.535334 -25.226772)
		(stroke
			(width 0.508)
			(type default)
		)
		(layer "In1.Cu")
	)
	(gr_line
		(start 176.560734 -26.598372)
		(end 176.560734 -25.252172)
		(stroke
			(width 0.508)
			(type default)
		)
		(layer "In1.Cu")
	)
	(gr_line
		(start 176.560734 -26.572972)
		(end 176.560734 -25.226772)
		(stroke
			(width 0.508)
			(type default)
		)
		(layer "In1.Cu")
	)
	(gr_line
		(start 176.586134 -26.598372)
		(end 176.586134 -25.252172)
		(stroke
			(width 0.508)
			(type default)
		)
		(layer "In1.Cu")
	)
	(gr_line
		(start 176.662334 -26.598372)
		(end 176.662334 -25.252172)
		(stroke
			(width 0.508)
			(type default)
		)
		(layer "In1.Cu")
	)
	(gr_line
		(start 176.763934 -26.750772)
		(end 176.763934 -25.099772)
		(stroke
			(width 0.2032)
			(type default)
		)
		(layer "In1.Cu")
	)
	(gr_line
		(start 176.763934 -26.725372)
		(end 175.747934 -26.725372)
		(stroke
			(width 0.2032)
			(type default)
		)
		(layer "In1.Cu")
	)
	(gr_line
		(start 176.763934 -26.674572)
		(end 176.763934 -26.725372)
		(stroke
			(width 0.2032)
			(type default)
		)
		(layer "In1.Cu")
	)
	(gr_line
		(start 176.763934 -25.099772)
		(end 175.824134 -25.099772)
		(stroke
			(width 0.2032)
			(type default)
		)
		(layer "In1.Cu")
	)
	(gr_line
		(start 176.814734 -26.725372)
		(end 175.773334 -26.725372)
		(stroke
			(width 0.2032)
			(type default)
		)
		(layer "In1.Cu")
	)
	(gr_line
		(start 176.814734 -25.048972)
		(end 176.814734 -26.725372)
		(stroke
			(width 0.2032)
			(type default)
		)
		(layer "In1.Cu")
	)
	(gr_line
		(start 176.865534 -26.826972)
		(end 176.865534 -24.972772)
		(stroke
			(width 0.1016)
			(type default)
		)
		(layer "In1.Cu")
	)
	(gr_line
		(start 176.865534 -24.972772)
		(end 175.697134 -24.972772)
		(stroke
			(width 0.1016)
			(type default)
		)
		(layer "In1.Cu")
	)
	(gr_line
		(start 178.22418 -24.6634)
		(end 178.22418 -23.3934)
		(stroke
			(width 0.7874)
			(type default)
		)
		(layer "In1.Cu")
	)
	(gr_line
		(start 183.9976 -26.8224)
		(end 185.2676 -26.8224)
		(stroke
			(width 0.7874)
			(type default)
		)
		(layer "In1.Cu")
	)
	(gr_line
		(start 184.22874 -29.30906)
		(end 185.49874 -29.30906)
		(stroke
			(width 0.7874)
			(type default)
		)
		(layer "In1.Cu")
	)
	(gr_line
		(start 187.107068 -29.337)
		(end 187.945268 -29.337)
		(stroke
			(width 0.1016)
			(type default)
		)
		(layer "In1.Cu")
	)
	(gr_line
		(start 187.107068 -27.4828)
		(end 187.107068 -29.337)
		(stroke
			(width 0.1016)
			(type default)
		)
		(layer "In1.Cu")
	)
	(gr_line
		(start 187.157868 -29.2354)
		(end 187.157868 -27.559)
		(stroke
			(width 0.2032)
			(type default)
		)
		(layer "In1.Cu")
	)
	(gr_line
		(start 187.157868 -27.559)
		(end 188.224668 -27.559)
		(stroke
			(width 0.2032)
			(type default)
		)
		(layer "In1.Cu")
	)
	(gr_line
		(start 187.183268 -29.2608)
		(end 188.173868 -29.2608)
		(stroke
			(width 0.2032)
			(type default)
		)
		(layer "In1.Cu")
	)
	(gr_line
		(start 187.183268 -29.2354)
		(end 187.183268 -29.2608)
		(stroke
			(width 0.2032)
			(type default)
		)
		(layer "In1.Cu")
	)
	(gr_line
		(start 187.234068 -29.1846)
		(end 188.173868 -29.1846)
		(stroke
			(width 0.2032)
			(type default)
		)
		(layer "In1.Cu")
	)
	(gr_line
		(start 187.234068 -27.6098)
		(end 187.234068 -29.1846)
		(stroke
			(width 0.2032)
			(type default)
		)
		(layer "In1.Cu")
	)
	(gr_line
		(start 187.310268 -29.1084)
		(end 187.310268 -27.7622)
		(stroke
			(width 0.508)
			(type default)
		)
		(layer "In1.Cu")
	)
	(gr_line
		(start 187.335668 -29.1084)
		(end 187.996068 -29.1084)
		(stroke
			(width 0.508)
			(type default)
		)
		(layer "In1.Cu")
	)
	(gr_line
		(start 187.335668 -29.083)
		(end 187.335668 -27.7368)
		(stroke
			(width 0.508)
			(type default)
		)
		(layer "In1.Cu")
	)
	(gr_line
		(start 187.335668 -27.7114)
		(end 187.970668 -27.7114)
		(stroke
			(width 0.508)
			(type default)
		)
		(layer "In1.Cu")
	)
	(gr_line
		(start 187.361068 -29.083)
		(end 187.361068 -27.7368)
		(stroke
			(width 0.508)
			(type default)
		)
		(layer "In1.Cu")
	)
	(gr_line
		(start 187.386468 -29.083)
		(end 187.386468 -27.7368)
		(stroke
			(width 0.508)
			(type default)
		)
		(layer "In1.Cu")
	)
	(gr_line
		(start 187.437268 -29.1084)
		(end 187.437268 -27.7622)
		(stroke
			(width 0.508)
			(type default)
		)
		(layer "In1.Cu")
	)
	(gr_line
		(start 187.437268 -29.083)
		(end 187.437268 -27.7368)
		(stroke
			(width 0.508)
			(type default)
		)
		(layer "In1.Cu")
	)
	(gr_line
		(start 187.488068 -29.083)
		(end 187.488068 -27.7368)
		(stroke
			(width 0.508)
			(type default)
		)
		(layer "In1.Cu")
	)
	(gr_line
		(start 187.507118 -26.826972)
		(end 188.345318 -26.826972)
		(stroke
			(width 0.1016)
			(type default)
		)
		(layer "In1.Cu")
	)
	(gr_line
		(start 187.507118 -24.972772)
		(end 187.507118 -26.826972)
		(stroke
			(width 0.1016)
			(type default)
		)
		(layer "In1.Cu")
	)
	(gr_line
		(start 187.513468 -29.0576)
		(end 187.513468 -27.7114)
		(stroke
			(width 0.508)
			(type default)
		)
		(layer "In1.Cu")
	)
	(gr_line
		(start 187.538868 -29.083)
		(end 187.538868 -27.7368)
		(stroke
			(width 0.508)
			(type default)
		)
		(layer "In1.Cu")
	)
	(gr_line
		(start 187.557918 -26.725372)
		(end 187.557918 -25.048972)
		(stroke
			(width 0.2032)
			(type default)
		)
		(layer "In1.Cu")
	)
	(gr_line
		(start 187.557918 -25.048972)
		(end 188.624718 -25.048972)
		(stroke
			(width 0.2032)
			(type default)
		)
		(layer "In1.Cu")
	)
	(gr_line
		(start 187.564268 -29.083)
		(end 187.564268 -27.7368)
		(stroke
			(width 0.508)
			(type default)
		)
		(layer "In1.Cu")
	)
	(gr_line
		(start 187.583318 -26.750772)
		(end 188.573918 -26.750772)
		(stroke
			(width 0.2032)
			(type default)
		)
		(layer "In1.Cu")
	)
	(gr_line
		(start 187.583318 -26.725372)
		(end 187.583318 -26.750772)
		(stroke
			(width 0.2032)
			(type default)
		)
		(layer "In1.Cu")
	)
	(gr_line
		(start 187.589668 -29.083)
		(end 187.589668 -27.7368)
		(stroke
			(width 0.508)
			(type default)
		)
		(layer "In1.Cu")
	)
	(gr_line
		(start 187.634118 -26.674572)
		(end 188.573918 -26.674572)
		(stroke
			(width 0.2032)
			(type default)
		)
		(layer "In1.Cu")
	)
	(gr_line
		(start 187.634118 -25.099772)
		(end 187.634118 -26.674572)
		(stroke
			(width 0.2032)
			(type default)
		)
		(layer "In1.Cu")
	)
	(gr_line
		(start 187.640468 -29.083)
		(end 187.640468 -27.7368)
		(stroke
			(width 0.508)
			(type default)
		)
		(layer "In1.Cu")
	)
	(gr_line
		(start 187.665868 -29.083)
		(end 187.665868 -27.7368)
		(stroke
			(width 0.508)
			(type default)
		)
		(layer "In1.Cu")
	)
	(gr_line
		(start 187.691268 -29.083)
		(end 187.691268 -27.7368)
		(stroke
			(width 0.508)
			(type default)
		)
		(layer "In1.Cu")
	)
	(gr_line
		(start 187.710318 -26.598372)
		(end 187.710318 -25.252172)
		(stroke
			(width 0.508)
			(type default)
		)
		(layer "In1.Cu")
	)
	(gr_line
		(start 187.716668 -29.083)
		(end 187.716668 -27.7368)
		(stroke
			(width 0.508)
			(type default)
		)
		(layer "In1.Cu")
	)
	(gr_line
		(start 187.735718 -26.598372)
		(end 188.396118 -26.598372)
		(stroke
			(width 0.508)
			(type default)
		)
		(layer "In1.Cu")
	)
	(gr_line
		(start 187.735718 -26.572972)
		(end 187.735718 -25.226772)
		(stroke
			(width 0.508)
			(type default)
		)
		(layer "In1.Cu")
	)
	(gr_line
		(start 187.735718 -25.201372)
		(end 188.370718 -25.201372)
		(stroke
			(width 0.508)
			(type default)
		)
		(layer "In1.Cu")
	)
	(gr_line
		(start 187.742068 -29.1084)
		(end 187.742068 -27.7622)
		(stroke
			(width 0.508)
			(type default)
		)
		(layer "In1.Cu")
	)
	(gr_line
		(start 187.761118 -26.572972)
		(end 187.761118 -25.226772)
		(stroke
			(width 0.508)
			(type default)
		)
		(layer "In1.Cu")
	)
	(gr_line
		(start 187.767468 -29.1084)
		(end 187.767468 -27.7622)
		(stroke
			(width 0.508)
			(type default)
		)
		(layer "In1.Cu")
	)
	(gr_line
		(start 187.767468 -29.083)
		(end 187.767468 -27.7368)
		(stroke
			(width 0.508)
			(type default)
		)
		(layer "In1.Cu")
	)
	(gr_line
		(start 187.786518 -26.572972)
		(end 187.786518 -25.226772)
		(stroke
			(width 0.508)
			(type default)
		)
		(layer "In1.Cu")
	)
	(gr_line
		(start 187.792868 -29.083)
		(end 187.792868 -27.7368)
		(stroke
			(width 0.508)
			(type default)
		)
		(layer "In1.Cu")
	)
	(gr_line
		(start 187.818268 -29.083)
		(end 187.818268 -27.7368)
		(stroke
			(width 0.508)
			(type default)
		)
		(layer "In1.Cu")
	)
	(gr_line
		(start 187.837318 -26.598372)
		(end 187.837318 -25.252172)
		(stroke
			(width 0.508)
			(type default)
		)
		(layer "In1.Cu")
	)
	(gr_line
		(start 187.837318 -26.572972)
		(end 187.837318 -25.226772)
		(stroke
			(width 0.508)
			(type default)
		)
		(layer "In1.Cu")
	)
	(gr_line
		(start 187.843668 -29.083)
		(end 187.843668 -27.7368)
		(stroke
			(width 0.508)
			(type default)
		)
		(layer "In1.Cu")
	)
	(gr_line
		(start 187.869068 -29.1084)
		(end 187.869068 -27.7622)
		(stroke
			(width 0.508)
			(type default)
		)
		(layer "In1.Cu")
	)
	(gr_line
		(start 187.869068 -29.083)
		(end 187.869068 -27.7368)
		(stroke
			(width 0.508)
			(type default)
		)
		(layer "In1.Cu")
	)
	(gr_line
		(start 187.888118 -26.572972)
		(end 187.888118 -25.226772)
		(stroke
			(width 0.508)
			(type default)
		)
		(layer "In1.Cu")
	)
	(gr_line
		(start 187.894468 -29.1084)
		(end 187.894468 -27.7622)
		(stroke
			(width 0.508)
			(type default)
		)
		(layer "In1.Cu")
	)
	(gr_line
		(start 187.894468 -29.083)
		(end 187.894468 -27.7368)
		(stroke
			(width 0.508)
			(type default)
		)
		(layer "In1.Cu")
	)
	(gr_line
		(start 187.913518 -26.547572)
		(end 187.913518 -25.201372)
		(stroke
			(width 0.508)
			(type default)
		)
		(layer "In1.Cu")
	)
	(gr_line
		(start 187.919868 -29.1084)
		(end 187.919868 -27.7622)
		(stroke
			(width 0.508)
			(type default)
		)
		(layer "In1.Cu")
	)
	(gr_line
		(start 187.938918 -26.572972)
		(end 187.938918 -25.226772)
		(stroke
			(width 0.508)
			(type default)
		)
		(layer "In1.Cu")
	)
	(gr_line
		(start 187.945268 -29.337)
		(end 188.275468 -29.337)
		(stroke
			(width 0.1016)
			(type default)
		)
		(layer "In1.Cu")
	)
	(gr_line
		(start 187.945268 -29.083)
		(end 187.945268 -27.7368)
		(stroke
			(width 0.508)
			(type default)
		)
		(layer "In1.Cu")
	)
	(gr_line
		(start 187.964318 -26.572972)
		(end 187.964318 -25.226772)
		(stroke
			(width 0.508)
			(type default)
		)
		(layer "In1.Cu")
	)
	(gr_line
		(start 187.970668 -29.1084)
		(end 187.970668 -27.7622)
		(stroke
			(width 0.508)
			(type default)
		)
		(layer "In1.Cu")
	)
	(gr_line
		(start 187.970668 -29.083)
		(end 187.970668 -27.7368)
		(stroke
			(width 0.508)
			(type default)
		)
		(layer "In1.Cu")
	)
	(gr_line
		(start 187.989718 -26.572972)
		(end 187.989718 -25.226772)
		(stroke
			(width 0.508)
			(type default)
		)
		(layer "In1.Cu")
	)
	(gr_line
		(start 187.996068 -29.1084)
		(end 187.996068 -27.7622)
		(stroke
			(width 0.508)
			(type default)
		)
		(layer "In1.Cu")
	)
	(gr_line
		(start 188.040518 -26.572972)
		(end 188.040518 -25.226772)
		(stroke
			(width 0.508)
			(type default)
		)
		(layer "In1.Cu")
	)
	(gr_line
		(start 188.065918 -26.572972)
		(end 188.065918 -25.226772)
		(stroke
			(width 0.508)
			(type default)
		)
		(layer "In1.Cu")
	)
	(gr_line
		(start 188.072268 -29.1084)
		(end 188.072268 -27.7622)
		(stroke
			(width 0.508)
			(type default)
		)
		(layer "In1.Cu")
	)
	(gr_line
		(start 188.091318 -26.572972)
		(end 188.091318 -25.226772)
		(stroke
			(width 0.508)
			(type default)
		)
		(layer "In1.Cu")
	)
	(gr_line
		(start 188.116718 -26.572972)
		(end 188.116718 -25.226772)
		(stroke
			(width 0.508)
			(type default)
		)
		(layer "In1.Cu")
	)
	(gr_line
		(start 188.142118 -26.598372)
		(end 188.142118 -25.252172)
		(stroke
			(width 0.508)
			(type default)
		)
		(layer "In1.Cu")
	)
	(gr_line
		(start 188.167518 -26.598372)
		(end 188.167518 -25.252172)
		(stroke
			(width 0.508)
			(type default)
		)
		(layer "In1.Cu")
	)
	(gr_line
		(start 188.167518 -26.572972)
		(end 188.167518 -25.226772)
		(stroke
			(width 0.508)
			(type default)
		)
		(layer "In1.Cu")
	)
	(gr_line
		(start 188.173868 -29.2608)
		(end 188.173868 -27.6098)
		(stroke
			(width 0.2032)
			(type default)
		)
		(layer "In1.Cu")
	)
	(gr_line
		(start 188.173868 -29.2354)
		(end 187.157868 -29.2354)
		(stroke
			(width 0.2032)
			(type default)
		)
		(layer "In1.Cu")
	)
	(gr_line
		(start 188.173868 -29.1846)
		(end 188.173868 -29.2354)
		(stroke
			(width 0.2032)
			(type default)
		)
		(layer "In1.Cu")
	)
	(gr_line
		(start 188.173868 -27.6098)
		(end 187.234068 -27.6098)
		(stroke
			(width 0.2032)
			(type default)
		)
		(layer "In1.Cu")
	)
	(gr_line
		(start 188.192918 -26.572972)
		(end 188.192918 -25.226772)
		(stroke
			(width 0.508)
			(type default)
		)
		(layer "In1.Cu")
	)
	(gr_line
		(start 188.218318 -26.572972)
		(end 188.218318 -25.226772)
		(stroke
			(width 0.508)
			(type default)
		)
		(layer "In1.Cu")
	)
	(gr_line
		(start 188.224668 -29.2354)
		(end 187.183268 -29.2354)
		(stroke
			(width 0.2032)
			(type default)
		)
		(layer "In1.Cu")
	)
	(gr_line
		(start 188.224668 -27.559)
		(end 188.224668 -29.2354)
		(stroke
			(width 0.2032)
			(type default)
		)
		(layer "In1.Cu")
	)
	(gr_line
		(start 188.243718 -26.572972)
		(end 188.243718 -25.226772)
		(stroke
			(width 0.508)
			(type default)
		)
		(layer "In1.Cu")
	)
	(gr_line
		(start 188.269118 -26.598372)
		(end 188.269118 -25.252172)
		(stroke
			(width 0.508)
			(type default)
		)
		(layer "In1.Cu")
	)
	(gr_line
		(start 188.269118 -26.572972)
		(end 188.269118 -25.226772)
		(stroke
			(width 0.508)
			(type default)
		)
		(layer "In1.Cu")
	)
	(gr_line
		(start 188.275468 -29.337)
		(end 188.275468 -27.4828)
		(stroke
			(width 0.1016)
			(type default)
		)
		(layer "In1.Cu")
	)
	(gr_line
		(start 188.275468 -27.4828)
		(end 187.107068 -27.4828)
		(stroke
			(width 0.1016)
			(type default)
		)
		(layer "In1.Cu")
	)
	(gr_line
		(start 188.294518 -26.598372)
		(end 188.294518 -25.252172)
		(stroke
			(width 0.508)
			(type default)
		)
		(layer "In1.Cu")
	)
	(gr_line
		(start 188.294518 -26.572972)
		(end 188.294518 -25.226772)
		(stroke
			(width 0.508)
			(type default)
		)
		(layer "In1.Cu")
	)
	(gr_line
		(start 188.319918 -26.598372)
		(end 188.319918 -25.252172)
		(stroke
			(width 0.508)
			(type default)
		)
		(layer "In1.Cu")
	)
	(gr_line
		(start 188.345318 -26.826972)
		(end 188.675518 -26.826972)
		(stroke
			(width 0.1016)
			(type default)
		)
		(layer "In1.Cu")
	)
	(gr_line
		(start 188.345318 -26.572972)
		(end 188.345318 -25.226772)
		(stroke
			(width 0.508)
			(type default)
		)
		(layer "In1.Cu")
	)
	(gr_line
		(start 188.370718 -26.598372)
		(end 188.370718 -25.252172)
		(stroke
			(width 0.508)
			(type default)
		)
		(layer "In1.Cu")
	)
	(gr_line
		(start 188.370718 -26.572972)
		(end 188.370718 -25.226772)
		(stroke
			(width 0.508)
			(type default)
		)
		(layer "In1.Cu")
	)
	(gr_line
		(start 188.396118 -26.598372)
		(end 188.396118 -25.252172)
		(stroke
			(width 0.508)
			(type default)
		)
		(layer "In1.Cu")
	)
	(gr_line
		(start 188.472318 -26.598372)
		(end 188.472318 -25.252172)
		(stroke
			(width 0.508)
			(type default)
		)
		(layer "In1.Cu")
	)
	(gr_line
		(start 188.573918 -26.750772)
		(end 188.573918 -25.099772)
		(stroke
			(width 0.2032)
			(type default)
		)
		(layer "In1.Cu")
	)
	(gr_line
		(start 188.573918 -26.725372)
		(end 187.557918 -26.725372)
		(stroke
			(width 0.2032)
			(type default)
		)
		(layer "In1.Cu")
	)
	(gr_line
		(start 188.573918 -26.674572)
		(end 188.573918 -26.725372)
		(stroke
			(width 0.2032)
			(type default)
		)
		(layer "In1.Cu")
	)
	(gr_line
		(start 188.573918 -25.099772)
		(end 187.634118 -25.099772)
		(stroke
			(width 0.2032)
			(type default)
		)
		(layer "In1.Cu")
	)
	(gr_line
		(start 188.624718 -26.725372)
		(end 187.583318 -26.725372)
		(stroke
			(width 0.2032)
			(type default)
		)
		(layer "In1.Cu")
	)
	(gr_line
		(start 188.624718 -25.048972)
		(end 188.624718 -26.725372)
		(stroke
			(width 0.2032)
			(type default)
		)
		(layer "In1.Cu")
	)
	(gr_line
		(start 188.675518 -26.826972)
		(end 188.675518 -24.972772)
		(stroke
			(width 0.1016)
			(type default)
		)
		(layer "In1.Cu")
	)
	(gr_line
		(start 188.675518 -24.972772)
		(end 187.507118 -24.972772)
		(stroke
			(width 0.1016)
			(type default)
		)
		(layer "In1.Cu")
	)
	(gr_line
		(start 189.45987 -30.594808)
		(end 190.72987 -30.594808)
		(stroke
			(width 0.7874)
			(type default)
		)
		(layer "In1.Cu")
	)
	(gr_line
		(start 189.507114 -29.337)
		(end 190.345314 -29.337)
		(stroke
			(width 0.1016)
			(type default)
		)
		(layer "In1.Cu")
	)
	(gr_line
		(start 189.507114 -27.4828)
		(end 189.507114 -29.337)
		(stroke
			(width 0.1016)
			(type default)
		)
		(layer "In1.Cu")
	)
	(gr_line
		(start 189.557914 -29.2354)
		(end 189.557914 -27.559)
		(stroke
			(width 0.2032)
			(type default)
		)
		(layer "In1.Cu")
	)
	(gr_line
		(start 189.557914 -27.559)
		(end 190.624714 -27.559)
		(stroke
			(width 0.2032)
			(type default)
		)
		(layer "In1.Cu")
	)
	(gr_line
		(start 189.583314 -29.2608)
		(end 190.573914 -29.2608)
		(stroke
			(width 0.2032)
			(type default)
		)
		(layer "In1.Cu")
	)
	(gr_line
		(start 189.583314 -29.2354)
		(end 189.583314 -29.2608)
		(stroke
			(width 0.2032)
			(type default)
		)
		(layer "In1.Cu")
	)
	(gr_line
		(start 189.634114 -29.1846)
		(end 190.573914 -29.1846)
		(stroke
			(width 0.2032)
			(type default)
		)
		(layer "In1.Cu")
	)
	(gr_line
		(start 189.634114 -27.6098)
		(end 189.634114 -29.1846)
		(stroke
			(width 0.2032)
			(type default)
		)
		(layer "In1.Cu")
	)
	(gr_line
		(start 189.710314 -29.1084)
		(end 189.710314 -27.7622)
		(stroke
			(width 0.508)
			(type default)
		)
		(layer "In1.Cu")
	)
	(gr_line
		(start 189.735714 -29.1084)
		(end 190.396114 -29.1084)
		(stroke
			(width 0.508)
			(type default)
		)
		(layer "In1.Cu")
	)
	(gr_line
		(start 189.735714 -29.083)
		(end 189.735714 -27.7368)
		(stroke
			(width 0.508)
			(type default)
		)
		(layer "In1.Cu")
	)
	(gr_line
		(start 189.735714 -27.7114)
		(end 190.370714 -27.7114)
		(stroke
			(width 0.508)
			(type default)
		)
		(layer "In1.Cu")
	)
	(gr_line
		(start 189.761114 -29.083)
		(end 189.761114 -27.7368)
		(stroke
			(width 0.508)
			(type default)
		)
		(layer "In1.Cu")
	)
	(gr_line
		(start 189.786514 -29.083)
		(end 189.786514 -27.7368)
		(stroke
			(width 0.508)
			(type default)
		)
		(layer "In1.Cu")
	)
	(gr_line
		(start 189.837314 -29.1084)
		(end 189.837314 -27.7622)
		(stroke
			(width 0.508)
			(type default)
		)
		(layer "In1.Cu")
	)
	(gr_line
		(start 189.837314 -29.083)
		(end 189.837314 -27.7368)
		(stroke
			(width 0.508)
			(type default)
		)
		(layer "In1.Cu")
	)
	(gr_line
		(start 189.888114 -29.083)
		(end 189.888114 -27.7368)
		(stroke
			(width 0.508)
			(type default)
		)
		(layer "In1.Cu")
	)
	(gr_line
		(start 189.907164 -26.826972)
		(end 190.745364 -26.826972)
		(stroke
			(width 0.1016)
			(type default)
		)
		(layer "In1.Cu")
	)
	(gr_line
		(start 189.907164 -24.972772)
		(end 189.907164 -26.826972)
		(stroke
			(width 0.1016)
			(type default)
		)
		(layer "In1.Cu")
	)
	(gr_line
		(start 189.913514 -29.0576)
		(end 189.913514 -27.7114)
		(stroke
			(width 0.508)
			(type default)
		)
		(layer "In1.Cu")
	)
	(gr_line
		(start 189.938914 -29.083)
		(end 189.938914 -27.7368)
		(stroke
			(width 0.508)
			(type default)
		)
		(layer "In1.Cu")
	)
	(gr_line
		(start 189.957964 -26.725372)
		(end 189.957964 -25.048972)
		(stroke
			(width 0.2032)
			(type default)
		)
		(layer "In1.Cu")
	)
	(gr_line
		(start 189.957964 -25.048972)
		(end 191.024764 -25.048972)
		(stroke
			(width 0.2032)
			(type default)
		)
		(layer "In1.Cu")
	)
	(gr_line
		(start 189.964314 -29.083)
		(end 189.964314 -27.7368)
		(stroke
			(width 0.508)
			(type default)
		)
		(layer "In1.Cu")
	)
	(gr_line
		(start 189.983364 -26.750772)
		(end 190.973964 -26.750772)
		(stroke
			(width 0.2032)
			(type default)
		)
		(layer "In1.Cu")
	)
	(gr_line
		(start 189.983364 -26.725372)
		(end 189.983364 -26.750772)
		(stroke
			(width 0.2032)
			(type default)
		)
		(layer "In1.Cu")
	)
	(gr_line
		(start 189.989714 -29.083)
		(end 189.989714 -27.7368)
		(stroke
			(width 0.508)
			(type default)
		)
		(layer "In1.Cu")
	)
	(gr_line
		(start 190.034164 -26.674572)
		(end 190.973964 -26.674572)
		(stroke
			(width 0.2032)
			(type default)
		)
		(layer "In1.Cu")
	)
	(gr_line
		(start 190.034164 -25.099772)
		(end 190.034164 -26.674572)
		(stroke
			(width 0.2032)
			(type default)
		)
		(layer "In1.Cu")
	)
	(gr_line
		(start 190.040514 -29.083)
		(end 190.040514 -27.7368)
		(stroke
			(width 0.508)
			(type default)
		)
		(layer "In1.Cu")
	)
	(gr_line
		(start 190.065914 -29.083)
		(end 190.065914 -27.7368)
		(stroke
			(width 0.508)
			(type default)
		)
		(layer "In1.Cu")
	)
	(gr_line
		(start 190.091314 -29.083)
		(end 190.091314 -27.7368)
		(stroke
			(width 0.508)
			(type default)
		)
		(layer "In1.Cu")
	)
	(gr_line
		(start 190.110364 -26.598372)
		(end 190.110364 -25.252172)
		(stroke
			(width 0.508)
			(type default)
		)
		(layer "In1.Cu")
	)
	(gr_line
		(start 190.116714 -29.083)
		(end 190.116714 -27.7368)
		(stroke
			(width 0.508)
			(type default)
		)
		(layer "In1.Cu")
	)
	(gr_line
		(start 190.135764 -26.598372)
		(end 190.796164 -26.598372)
		(stroke
			(width 0.508)
			(type default)
		)
		(layer "In1.Cu")
	)
	(gr_line
		(start 190.135764 -26.572972)
		(end 190.135764 -25.226772)
		(stroke
			(width 0.508)
			(type default)
		)
		(layer "In1.Cu")
	)
	(gr_line
		(start 190.135764 -25.201372)
		(end 190.770764 -25.201372)
		(stroke
			(width 0.508)
			(type default)
		)
		(layer "In1.Cu")
	)
	(gr_line
		(start 190.142114 -29.1084)
		(end 190.142114 -27.7622)
		(stroke
			(width 0.508)
			(type default)
		)
		(layer "In1.Cu")
	)
	(gr_line
		(start 190.161164 -26.572972)
		(end 190.161164 -25.226772)
		(stroke
			(width 0.508)
			(type default)
		)
		(layer "In1.Cu")
	)
	(gr_line
		(start 190.167514 -29.1084)
		(end 190.167514 -27.7622)
		(stroke
			(width 0.508)
			(type default)
		)
		(layer "In1.Cu")
	)
	(gr_line
		(start 190.167514 -29.083)
		(end 190.167514 -27.7368)
		(stroke
			(width 0.508)
			(type default)
		)
		(layer "In1.Cu")
	)
	(gr_line
		(start 190.186564 -26.572972)
		(end 190.186564 -25.226772)
		(stroke
			(width 0.508)
			(type default)
		)
		(layer "In1.Cu")
	)
	(gr_line
		(start 190.192914 -29.083)
		(end 190.192914 -27.7368)
		(stroke
			(width 0.508)
			(type default)
		)
		(layer "In1.Cu")
	)
	(gr_line
		(start 190.218314 -29.083)
		(end 190.218314 -27.7368)
		(stroke
			(width 0.508)
			(type default)
		)
		(layer "In1.Cu")
	)
	(gr_line
		(start 190.237364 -26.598372)
		(end 190.237364 -25.252172)
		(stroke
			(width 0.508)
			(type default)
		)
		(layer "In1.Cu")
	)
	(gr_line
		(start 190.237364 -26.572972)
		(end 190.237364 -25.226772)
		(stroke
			(width 0.508)
			(type default)
		)
		(layer "In1.Cu")
	)
	(gr_line
		(start 190.243714 -29.083)
		(end 190.243714 -27.7368)
		(stroke
			(width 0.508)
			(type default)
		)
		(layer "In1.Cu")
	)
	(gr_line
		(start 190.269114 -29.1084)
		(end 190.269114 -27.7622)
		(stroke
			(width 0.508)
			(type default)
		)
		(layer "In1.Cu")
	)
	(gr_line
		(start 190.269114 -29.083)
		(end 190.269114 -27.7368)
		(stroke
			(width 0.508)
			(type default)
		)
		(layer "In1.Cu")
	)
	(gr_line
		(start 190.288164 -26.572972)
		(end 190.288164 -25.226772)
		(stroke
			(width 0.508)
			(type default)
		)
		(layer "In1.Cu")
	)
	(gr_line
		(start 190.294514 -29.1084)
		(end 190.294514 -27.7622)
		(stroke
			(width 0.508)
			(type default)
		)
		(layer "In1.Cu")
	)
	(gr_line
		(start 190.294514 -29.083)
		(end 190.294514 -27.7368)
		(stroke
			(width 0.508)
			(type default)
		)
		(layer "In1.Cu")
	)
	(gr_line
		(start 190.313564 -26.547572)
		(end 190.313564 -25.201372)
		(stroke
			(width 0.508)
			(type default)
		)
		(layer "In1.Cu")
	)
	(gr_line
		(start 190.319914 -29.1084)
		(end 190.319914 -27.7622)
		(stroke
			(width 0.508)
			(type default)
		)
		(layer "In1.Cu")
	)
	(gr_line
		(start 190.338964 -26.572972)
		(end 190.338964 -25.226772)
		(stroke
			(width 0.508)
			(type default)
		)
		(layer "In1.Cu")
	)
	(gr_line
		(start 190.345314 -29.337)
		(end 190.675514 -29.337)
		(stroke
			(width 0.1016)
			(type default)
		)
		(layer "In1.Cu")
	)
	(gr_line
		(start 190.345314 -29.083)
		(end 190.345314 -27.7368)
		(stroke
			(width 0.508)
			(type default)
		)
		(layer "In1.Cu")
	)
	(gr_line
		(start 190.364364 -26.572972)
		(end 190.364364 -25.226772)
		(stroke
			(width 0.508)
			(type default)
		)
		(layer "In1.Cu")
	)
	(gr_line
		(start 190.370714 -29.1084)
		(end 190.370714 -27.7622)
		(stroke
			(width 0.508)
			(type default)
		)
		(layer "In1.Cu")
	)
	(gr_line
		(start 190.370714 -29.083)
		(end 190.370714 -27.7368)
		(stroke
			(width 0.508)
			(type default)
		)
		(layer "In1.Cu")
	)
	(gr_line
		(start 190.389764 -26.572972)
		(end 190.389764 -25.226772)
		(stroke
			(width 0.508)
			(type default)
		)
		(layer "In1.Cu")
	)
	(gr_line
		(start 190.396114 -29.1084)
		(end 190.396114 -27.7622)
		(stroke
			(width 0.508)
			(type default)
		)
		(layer "In1.Cu")
	)
	(gr_line
		(start 190.440564 -26.572972)
		(end 190.440564 -25.226772)
		(stroke
			(width 0.508)
			(type default)
		)
		(layer "In1.Cu")
	)
	(gr_line
		(start 190.465964 -26.572972)
		(end 190.465964 -25.226772)
		(stroke
			(width 0.508)
			(type default)
		)
		(layer "In1.Cu")
	)
	(gr_line
		(start 190.472314 -29.1084)
		(end 190.472314 -27.7622)
		(stroke
			(width 0.508)
			(type default)
		)
		(layer "In1.Cu")
	)
	(gr_line
		(start 190.491364 -26.572972)
		(end 190.491364 -25.226772)
		(stroke
			(width 0.508)
			(type default)
		)
		(layer "In1.Cu")
	)
	(gr_line
		(start 190.516764 -26.572972)
		(end 190.516764 -25.226772)
		(stroke
			(width 0.508)
			(type default)
		)
		(layer "In1.Cu")
	)
	(gr_line
		(start 190.542164 -26.598372)
		(end 190.542164 -25.252172)
		(stroke
			(width 0.508)
			(type default)
		)
		(layer "In1.Cu")
	)
	(gr_line
		(start 190.567564 -26.598372)
		(end 190.567564 -25.252172)
		(stroke
			(width 0.508)
			(type default)
		)
		(layer "In1.Cu")
	)
	(gr_line
		(start 190.567564 -26.572972)
		(end 190.567564 -25.226772)
		(stroke
			(width 0.508)
			(type default)
		)
		(layer "In1.Cu")
	)
	(gr_line
		(start 190.573914 -29.2608)
		(end 190.573914 -27.6098)
		(stroke
			(width 0.2032)
			(type default)
		)
		(layer "In1.Cu")
	)
	(gr_line
		(start 190.573914 -29.2354)
		(end 189.557914 -29.2354)
		(stroke
			(width 0.2032)
			(type default)
		)
		(layer "In1.Cu")
	)
	(gr_line
		(start 190.573914 -29.1846)
		(end 190.573914 -29.2354)
		(stroke
			(width 0.2032)
			(type default)
		)
		(layer "In1.Cu")
	)
	(gr_line
		(start 190.573914 -27.6098)
		(end 189.634114 -27.6098)
		(stroke
			(width 0.2032)
			(type default)
		)
		(layer "In1.Cu")
	)
	(gr_line
		(start 190.592964 -26.572972)
		(end 190.592964 -25.226772)
		(stroke
			(width 0.508)
			(type default)
		)
		(layer "In1.Cu")
	)
	(gr_line
		(start 190.618364 -26.572972)
		(end 190.618364 -25.226772)
		(stroke
			(width 0.508)
			(type default)
		)
		(layer "In1.Cu")
	)
	(gr_line
		(start 190.624714 -29.2354)
		(end 189.583314 -29.2354)
		(stroke
			(width 0.2032)
			(type default)
		)
		(layer "In1.Cu")
	)
	(gr_line
		(start 190.624714 -27.559)
		(end 190.624714 -29.2354)
		(stroke
			(width 0.2032)
			(type default)
		)
		(layer "In1.Cu")
	)
	(gr_line
		(start 190.643764 -26.572972)
		(end 190.643764 -25.226772)
		(stroke
			(width 0.508)
			(type default)
		)
		(layer "In1.Cu")
	)
	(gr_line
		(start 190.669164 -26.598372)
		(end 190.669164 -25.252172)
		(stroke
			(width 0.508)
			(type default)
		)
		(layer "In1.Cu")
	)
	(gr_line
		(start 190.669164 -26.572972)
		(end 190.669164 -25.226772)
		(stroke
			(width 0.508)
			(type default)
		)
		(layer "In1.Cu")
	)
	(gr_line
		(start 190.675514 -29.337)
		(end 190.675514 -27.4828)
		(stroke
			(width 0.1016)
			(type default)
		)
		(layer "In1.Cu")
	)
	(gr_line
		(start 190.675514 -27.4828)
		(end 189.507114 -27.4828)
		(stroke
			(width 0.1016)
			(type default)
		)
		(layer "In1.Cu")
	)
	(gr_line
		(start 190.694564 -26.598372)
		(end 190.694564 -25.252172)
		(stroke
			(width 0.508)
			(type default)
		)
		(layer "In1.Cu")
	)
	(gr_line
		(start 190.694564 -26.572972)
		(end 190.694564 -25.226772)
		(stroke
			(width 0.508)
			(type default)
		)
		(layer "In1.Cu")
	)
	(gr_line
		(start 190.719964 -26.598372)
		(end 190.719964 -25.252172)
		(stroke
			(width 0.508)
			(type default)
		)
		(layer "In1.Cu")
	)
	(gr_line
		(start 190.745364 -26.826972)
		(end 191.075564 -26.826972)
		(stroke
			(width 0.1016)
			(type default)
		)
		(layer "In1.Cu")
	)
	(gr_line
		(start 190.745364 -26.572972)
		(end 190.745364 -25.226772)
		(stroke
			(width 0.508)
			(type default)
		)
		(layer "In1.Cu")
	)
	(gr_line
		(start 190.770764 -26.598372)
		(end 190.770764 -25.252172)
		(stroke
			(width 0.508)
			(type default)
		)
		(layer "In1.Cu")
	)
	(gr_line
		(start 190.770764 -26.572972)
		(end 190.770764 -25.226772)
		(stroke
			(width 0.508)
			(type default)
		)
		(layer "In1.Cu")
	)
	(gr_line
		(start 190.796164 -26.598372)
		(end 190.796164 -25.252172)
		(stroke
			(width 0.508)
			(type default)
		)
		(layer "In1.Cu")
	)
	(gr_line
		(start 190.872364 -26.598372)
		(end 190.872364 -25.252172)
		(stroke
			(width 0.508)
			(type default)
		)
		(layer "In1.Cu")
	)
	(gr_line
		(start 190.973964 -26.750772)
		(end 190.973964 -25.099772)
		(stroke
			(width 0.2032)
			(type default)
		)
		(layer "In1.Cu")
	)
	(gr_line
		(start 190.973964 -26.725372)
		(end 189.957964 -26.725372)
		(stroke
			(width 0.2032)
			(type default)
		)
		(layer "In1.Cu")
	)
	(gr_line
		(start 190.973964 -26.674572)
		(end 190.973964 -26.725372)
		(stroke
			(width 0.2032)
			(type default)
		)
		(layer "In1.Cu")
	)
	(gr_line
		(start 190.973964 -25.099772)
		(end 190.034164 -25.099772)
		(stroke
			(width 0.2032)
			(type default)
		)
		(layer "In1.Cu")
	)
	(gr_line
		(start 191.024764 -26.725372)
		(end 189.983364 -26.725372)
		(stroke
			(width 0.2032)
			(type default)
		)
		(layer "In1.Cu")
	)
	(gr_line
		(start 191.024764 -25.048972)
		(end 191.024764 -26.725372)
		(stroke
			(width 0.2032)
			(type default)
		)
		(layer "In1.Cu")
	)
	(gr_line
		(start 191.075564 -26.826972)
		(end 191.075564 -24.972772)
		(stroke
			(width 0.1016)
			(type default)
		)
		(layer "In1.Cu")
	)
	(gr_line
		(start 191.075564 -24.972772)
		(end 189.907164 -24.972772)
		(stroke
			(width 0.1016)
			(type default)
		)
		(layer "In1.Cu")
	)
	(gr_line
		(start 191.12992 -23.57882)
		(end 189.85992 -23.57882)
		(stroke
			(width 0.7874)
			(type default)
		)
		(layer "In1.Cu")
	)
	(gr_line
		(start 191.87414 -31.68142)
		(end 193.14414 -31.68142)
		(stroke
			(width 0.7874)
			(type default)
		)
		(layer "In1.Cu")
	)
	(gr_line
		(start 191.906906 -29.337)
		(end 192.745106 -29.337)
		(stroke
			(width 0.1016)
			(type default)
		)
		(layer "In1.Cu")
	)
	(gr_line
		(start 191.906906 -27.4828)
		(end 191.906906 -29.337)
		(stroke
			(width 0.1016)
			(type default)
		)
		(layer "In1.Cu")
	)
	(gr_line
		(start 191.957706 -29.2354)
		(end 191.957706 -27.559)
		(stroke
			(width 0.2032)
			(type default)
		)
		(layer "In1.Cu")
	)
	(gr_line
		(start 191.957706 -27.559)
		(end 193.024506 -27.559)
		(stroke
			(width 0.2032)
			(type default)
		)
		(layer "In1.Cu")
	)
	(gr_line
		(start 191.983106 -29.2608)
		(end 192.973706 -29.2608)
		(stroke
			(width 0.2032)
			(type default)
		)
		(layer "In1.Cu")
	)
	(gr_line
		(start 191.983106 -29.2354)
		(end 191.983106 -29.2608)
		(stroke
			(width 0.2032)
			(type default)
		)
		(layer "In1.Cu")
	)
	(gr_line
		(start 192.033906 -29.1846)
		(end 192.973706 -29.1846)
		(stroke
			(width 0.2032)
			(type default)
		)
		(layer "In1.Cu")
	)
	(gr_line
		(start 192.033906 -27.6098)
		(end 192.033906 -29.1846)
		(stroke
			(width 0.2032)
			(type default)
		)
		(layer "In1.Cu")
	)
	(gr_line
		(start 192.110106 -29.1084)
		(end 192.110106 -27.7622)
		(stroke
			(width 0.508)
			(type default)
		)
		(layer "In1.Cu")
	)
	(gr_line
		(start 192.135506 -29.1084)
		(end 192.795906 -29.1084)
		(stroke
			(width 0.508)
			(type default)
		)
		(layer "In1.Cu")
	)
	(gr_line
		(start 192.135506 -29.083)
		(end 192.135506 -27.7368)
		(stroke
			(width 0.508)
			(type default)
		)
		(layer "In1.Cu")
	)
	(gr_line
		(start 192.135506 -27.7114)
		(end 192.770506 -27.7114)
		(stroke
			(width 0.508)
			(type default)
		)
		(layer "In1.Cu")
	)
	(gr_line
		(start 192.160906 -29.083)
		(end 192.160906 -27.7368)
		(stroke
			(width 0.508)
			(type default)
		)
		(layer "In1.Cu")
	)
	(gr_line
		(start 192.186306 -29.083)
		(end 192.186306 -27.7368)
		(stroke
			(width 0.508)
			(type default)
		)
		(layer "In1.Cu")
	)
	(gr_line
		(start 192.237106 -29.1084)
		(end 192.237106 -27.7622)
		(stroke
			(width 0.508)
			(type default)
		)
		(layer "In1.Cu")
	)
	(gr_line
		(start 192.237106 -29.083)
		(end 192.237106 -27.7368)
		(stroke
			(width 0.508)
			(type default)
		)
		(layer "In1.Cu")
	)
	(gr_line
		(start 192.287906 -29.083)
		(end 192.287906 -27.7368)
		(stroke
			(width 0.508)
			(type default)
		)
		(layer "In1.Cu")
	)
	(gr_line
		(start 192.306956 -26.826972)
		(end 193.145156 -26.826972)
		(stroke
			(width 0.1016)
			(type default)
		)
		(layer "In1.Cu")
	)
	(gr_line
		(start 192.306956 -24.972772)
		(end 192.306956 -26.826972)
		(stroke
			(width 0.1016)
			(type default)
		)
		(layer "In1.Cu")
	)
	(gr_line
		(start 192.313306 -29.0576)
		(end 192.313306 -27.7114)
		(stroke
			(width 0.508)
			(type default)
		)
		(layer "In1.Cu")
	)
	(gr_line
		(start 192.338706 -29.083)
		(end 192.338706 -27.7368)
		(stroke
			(width 0.508)
			(type default)
		)
		(layer "In1.Cu")
	)
	(gr_line
		(start 192.357756 -26.725372)
		(end 192.357756 -25.048972)
		(stroke
			(width 0.2032)
			(type default)
		)
		(layer "In1.Cu")
	)
	(gr_line
		(start 192.357756 -25.048972)
		(end 193.424556 -25.048972)
		(stroke
			(width 0.2032)
			(type default)
		)
		(layer "In1.Cu")
	)
	(gr_line
		(start 192.364106 -29.083)
		(end 192.364106 -27.7368)
		(stroke
			(width 0.508)
			(type default)
		)
		(layer "In1.Cu")
	)
	(gr_line
		(start 192.383156 -26.750772)
		(end 193.373756 -26.750772)
		(stroke
			(width 0.2032)
			(type default)
		)
		(layer "In1.Cu")
	)
	(gr_line
		(start 192.383156 -26.725372)
		(end 192.383156 -26.750772)
		(stroke
			(width 0.2032)
			(type default)
		)
		(layer "In1.Cu")
	)
	(gr_line
		(start 192.389506 -29.083)
		(end 192.389506 -27.7368)
		(stroke
			(width 0.508)
			(type default)
		)
		(layer "In1.Cu")
	)
	(gr_line
		(start 192.433956 -26.674572)
		(end 193.373756 -26.674572)
		(stroke
			(width 0.2032)
			(type default)
		)
		(layer "In1.Cu")
	)
	(gr_line
		(start 192.433956 -25.099772)
		(end 192.433956 -26.674572)
		(stroke
			(width 0.2032)
			(type default)
		)
		(layer "In1.Cu")
	)
	(gr_line
		(start 192.440306 -29.083)
		(end 192.440306 -27.7368)
		(stroke
			(width 0.508)
			(type default)
		)
		(layer "In1.Cu")
	)
	(gr_line
		(start 192.465706 -29.083)
		(end 192.465706 -27.7368)
		(stroke
			(width 0.508)
			(type default)
		)
		(layer "In1.Cu")
	)
	(gr_line
		(start 192.491106 -29.083)
		(end 192.491106 -27.7368)
		(stroke
			(width 0.508)
			(type default)
		)
		(layer "In1.Cu")
	)
	(gr_line
		(start 192.510156 -26.598372)
		(end 192.510156 -25.252172)
		(stroke
			(width 0.508)
			(type default)
		)
		(layer "In1.Cu")
	)
	(gr_line
		(start 192.516506 -29.083)
		(end 192.516506 -27.7368)
		(stroke
			(width 0.508)
			(type default)
		)
		(layer "In1.Cu")
	)
	(gr_line
		(start 192.535556 -26.598372)
		(end 193.195956 -26.598372)
		(stroke
			(width 0.508)
			(type default)
		)
		(layer "In1.Cu")
	)
	(gr_line
		(start 192.535556 -26.572972)
		(end 192.535556 -25.226772)
		(stroke
			(width 0.508)
			(type default)
		)
		(layer "In1.Cu")
	)
	(gr_line
		(start 192.535556 -25.201372)
		(end 193.170556 -25.201372)
		(stroke
			(width 0.508)
			(type default)
		)
		(layer "In1.Cu")
	)
	(gr_line
		(start 192.541906 -29.1084)
		(end 192.541906 -27.7622)
		(stroke
			(width 0.508)
			(type default)
		)
		(layer "In1.Cu")
	)
	(gr_line
		(start 192.560956 -26.572972)
		(end 192.560956 -25.226772)
		(stroke
			(width 0.508)
			(type default)
		)
		(layer "In1.Cu")
	)
	(gr_line
		(start 192.567306 -29.1084)
		(end 192.567306 -27.7622)
		(stroke
			(width 0.508)
			(type default)
		)
		(layer "In1.Cu")
	)
	(gr_line
		(start 192.567306 -29.083)
		(end 192.567306 -27.7368)
		(stroke
			(width 0.508)
			(type default)
		)
		(layer "In1.Cu")
	)
	(gr_line
		(start 192.586356 -26.572972)
		(end 192.586356 -25.226772)
		(stroke
			(width 0.508)
			(type default)
		)
		(layer "In1.Cu")
	)
	(gr_line
		(start 192.592706 -29.083)
		(end 192.592706 -27.7368)
		(stroke
			(width 0.508)
			(type default)
		)
		(layer "In1.Cu")
	)
	(gr_line
		(start 192.618106 -29.083)
		(end 192.618106 -27.7368)
		(stroke
			(width 0.508)
			(type default)
		)
		(layer "In1.Cu")
	)
	(gr_line
		(start 192.637156 -26.598372)
		(end 192.637156 -25.252172)
		(stroke
			(width 0.508)
			(type default)
		)
		(layer "In1.Cu")
	)
	(gr_line
		(start 192.637156 -26.572972)
		(end 192.637156 -25.226772)
		(stroke
			(width 0.508)
			(type default)
		)
		(layer "In1.Cu")
	)
	(gr_line
		(start 192.643506 -29.083)
		(end 192.643506 -27.7368)
		(stroke
			(width 0.508)
			(type default)
		)
		(layer "In1.Cu")
	)
	(gr_line
		(start 192.668906 -29.1084)
		(end 192.668906 -27.7622)
		(stroke
			(width 0.508)
			(type default)
		)
		(layer "In1.Cu")
	)
	(gr_line
		(start 192.668906 -29.083)
		(end 192.668906 -27.7368)
		(stroke
			(width 0.508)
			(type default)
		)
		(layer "In1.Cu")
	)
	(gr_line
		(start 192.687956 -26.572972)
		(end 192.687956 -25.226772)
		(stroke
			(width 0.508)
			(type default)
		)
		(layer "In1.Cu")
	)
	(gr_line
		(start 192.694306 -29.1084)
		(end 192.694306 -27.7622)
		(stroke
			(width 0.508)
			(type default)
		)
		(layer "In1.Cu")
	)
	(gr_line
		(start 192.694306 -29.083)
		(end 192.694306 -27.7368)
		(stroke
			(width 0.508)
			(type default)
		)
		(layer "In1.Cu")
	)
	(gr_line
		(start 192.713356 -26.547572)
		(end 192.713356 -25.201372)
		(stroke
			(width 0.508)
			(type default)
		)
		(layer "In1.Cu")
	)
	(gr_line
		(start 192.719706 -29.1084)
		(end 192.719706 -27.7622)
		(stroke
			(width 0.508)
			(type default)
		)
		(layer "In1.Cu")
	)
	(gr_line
		(start 192.738756 -26.572972)
		(end 192.738756 -25.226772)
		(stroke
			(width 0.508)
			(type default)
		)
		(layer "In1.Cu")
	)
	(gr_line
		(start 192.745106 -29.337)
		(end 193.075306 -29.337)
		(stroke
			(width 0.1016)
			(type default)
		)
		(layer "In1.Cu")
	)
	(gr_line
		(start 192.745106 -29.083)
		(end 192.745106 -27.7368)
		(stroke
			(width 0.508)
			(type default)
		)
		(layer "In1.Cu")
	)
	(gr_line
		(start 192.764156 -26.572972)
		(end 192.764156 -25.226772)
		(stroke
			(width 0.508)
			(type default)
		)
		(layer "In1.Cu")
	)
	(gr_line
		(start 192.770506 -29.1084)
		(end 192.770506 -27.7622)
		(stroke
			(width 0.508)
			(type default)
		)
		(layer "In1.Cu")
	)
	(gr_line
		(start 192.770506 -29.083)
		(end 192.770506 -27.7368)
		(stroke
			(width 0.508)
			(type default)
		)
		(layer "In1.Cu")
	)
	(gr_line
		(start 192.789556 -26.572972)
		(end 192.789556 -25.226772)
		(stroke
			(width 0.508)
			(type default)
		)
		(layer "In1.Cu")
	)
	(gr_line
		(start 192.795906 -29.1084)
		(end 192.795906 -27.7622)
		(stroke
			(width 0.508)
			(type default)
		)
		(layer "In1.Cu")
	)
	(gr_line
		(start 192.840356 -26.572972)
		(end 192.840356 -25.226772)
		(stroke
			(width 0.508)
			(type default)
		)
		(layer "In1.Cu")
	)
	(gr_line
		(start 192.865756 -26.572972)
		(end 192.865756 -25.226772)
		(stroke
			(width 0.508)
			(type default)
		)
		(layer "In1.Cu")
	)
	(gr_line
		(start 192.872106 -29.1084)
		(end 192.872106 -27.7622)
		(stroke
			(width 0.508)
			(type default)
		)
		(layer "In1.Cu")
	)
	(gr_line
		(start 192.891156 -26.572972)
		(end 192.891156 -25.226772)
		(stroke
			(width 0.508)
			(type default)
		)
		(layer "In1.Cu")
	)
	(gr_line
		(start 192.916556 -26.572972)
		(end 192.916556 -25.226772)
		(stroke
			(width 0.508)
			(type default)
		)
		(layer "In1.Cu")
	)
	(gr_line
		(start 192.941956 -26.598372)
		(end 192.941956 -25.252172)
		(stroke
			(width 0.508)
			(type default)
		)
		(layer "In1.Cu")
	)
	(gr_line
		(start 192.967356 -26.598372)
		(end 192.967356 -25.252172)
		(stroke
			(width 0.508)
			(type default)
		)
		(layer "In1.Cu")
	)
	(gr_line
		(start 192.967356 -26.572972)
		(end 192.967356 -25.226772)
		(stroke
			(width 0.508)
			(type default)
		)
		(layer "In1.Cu")
	)
	(gr_line
		(start 192.973706 -29.2608)
		(end 192.973706 -27.6098)
		(stroke
			(width 0.2032)
			(type default)
		)
		(layer "In1.Cu")
	)
	(gr_line
		(start 192.973706 -29.2354)
		(end 191.957706 -29.2354)
		(stroke
			(width 0.2032)
			(type default)
		)
		(layer "In1.Cu")
	)
	(gr_line
		(start 192.973706 -29.1846)
		(end 192.973706 -29.2354)
		(stroke
			(width 0.2032)
			(type default)
		)
		(layer "In1.Cu")
	)
	(gr_line
		(start 192.973706 -27.6098)
		(end 192.033906 -27.6098)
		(stroke
			(width 0.2032)
			(type default)
		)
		(layer "In1.Cu")
	)
	(gr_line
		(start 192.992756 -26.572972)
		(end 192.992756 -25.226772)
		(stroke
			(width 0.508)
			(type default)
		)
		(layer "In1.Cu")
	)
	(gr_line
		(start 193.018156 -26.572972)
		(end 193.018156 -25.226772)
		(stroke
			(width 0.508)
			(type default)
		)
		(layer "In1.Cu")
	)
	(gr_line
		(start 193.024506 -29.2354)
		(end 191.983106 -29.2354)
		(stroke
			(width 0.2032)
			(type default)
		)
		(layer "In1.Cu")
	)
	(gr_line
		(start 193.024506 -27.559)
		(end 193.024506 -29.2354)
		(stroke
			(width 0.2032)
			(type default)
		)
		(layer "In1.Cu")
	)
	(gr_line
		(start 193.043556 -26.572972)
		(end 193.043556 -25.226772)
		(stroke
			(width 0.508)
			(type default)
		)
		(layer "In1.Cu")
	)
	(gr_line
		(start 193.068956 -26.598372)
		(end 193.068956 -25.252172)
		(stroke
			(width 0.508)
			(type default)
		)
		(layer "In1.Cu")
	)
	(gr_line
		(start 193.068956 -26.572972)
		(end 193.068956 -25.226772)
		(stroke
			(width 0.508)
			(type default)
		)
		(layer "In1.Cu")
	)
	(gr_line
		(start 193.075306 -29.337)
		(end 193.075306 -27.4828)
		(stroke
			(width 0.1016)
			(type default)
		)
		(layer "In1.Cu")
	)
	(gr_line
		(start 193.075306 -27.4828)
		(end 191.906906 -27.4828)
		(stroke
			(width 0.1016)
			(type default)
		)
		(layer "In1.Cu")
	)
	(gr_line
		(start 193.094356 -26.598372)
		(end 193.094356 -25.252172)
		(stroke
			(width 0.508)
			(type default)
		)
		(layer "In1.Cu")
	)
	(gr_line
		(start 193.094356 -26.572972)
		(end 193.094356 -25.226772)
		(stroke
			(width 0.508)
			(type default)
		)
		(layer "In1.Cu")
	)
	(gr_line
		(start 193.119756 -26.598372)
		(end 193.119756 -25.252172)
		(stroke
			(width 0.508)
			(type default)
		)
		(layer "In1.Cu")
	)
	(gr_line
		(start 193.145156 -26.826972)
		(end 193.475356 -26.826972)
		(stroke
			(width 0.1016)
			(type default)
		)
		(layer "In1.Cu")
	)
	(gr_line
		(start 193.145156 -26.572972)
		(end 193.145156 -25.226772)
		(stroke
			(width 0.508)
			(type default)
		)
		(layer "In1.Cu")
	)
	(gr_line
		(start 193.170556 -26.598372)
		(end 193.170556 -25.252172)
		(stroke
			(width 0.508)
			(type default)
		)
		(layer "In1.Cu")
	)
	(gr_line
		(start 193.170556 -26.572972)
		(end 193.170556 -25.226772)
		(stroke
			(width 0.508)
			(type default)
		)
		(layer "In1.Cu")
	)
	(gr_line
		(start 193.195956 -26.598372)
		(end 193.195956 -25.252172)
		(stroke
			(width 0.508)
			(type default)
		)
		(layer "In1.Cu")
	)
	(gr_line
		(start 193.272156 -26.598372)
		(end 193.272156 -25.252172)
		(stroke
			(width 0.508)
			(type default)
		)
		(layer "In1.Cu")
	)
	(gr_line
		(start 193.373756 -26.750772)
		(end 193.373756 -25.099772)
		(stroke
			(width 0.2032)
			(type default)
		)
		(layer "In1.Cu")
	)
	(gr_line
		(start 193.373756 -26.725372)
		(end 192.357756 -26.725372)
		(stroke
			(width 0.2032)
			(type default)
		)
		(layer "In1.Cu")
	)
	(gr_line
		(start 193.373756 -26.674572)
		(end 193.373756 -26.725372)
		(stroke
			(width 0.2032)
			(type default)
		)
		(layer "In1.Cu")
	)
	(gr_line
		(start 193.373756 -25.099772)
		(end 192.433956 -25.099772)
		(stroke
			(width 0.2032)
			(type default)
		)
		(layer "In1.Cu")
	)
	(gr_line
		(start 193.424556 -26.725372)
		(end 192.383156 -26.725372)
		(stroke
			(width 0.2032)
			(type default)
		)
		(layer "In1.Cu")
	)
	(gr_line
		(start 193.424556 -25.048972)
		(end 193.424556 -26.725372)
		(stroke
			(width 0.2032)
			(type default)
		)
		(layer "In1.Cu")
	)
	(gr_line
		(start 193.475356 -26.826972)
		(end 193.475356 -24.972772)
		(stroke
			(width 0.1016)
			(type default)
		)
		(layer "In1.Cu")
	)
	(gr_line
		(start 193.475356 -24.972772)
		(end 192.306956 -24.972772)
		(stroke
			(width 0.1016)
			(type default)
		)
		(layer "In1.Cu")
	)
	(gr_line
		(start 193.529966 -18.5166)
		(end 192.259966 -18.5166)
		(stroke
			(width 0.7874)
			(type default)
		)
		(layer "In1.Cu")
	)
	(gr_line
		(start 194.259962 -30.56382)
		(end 195.529962 -30.56382)
		(stroke
			(width 0.7874)
			(type default)
		)
		(layer "In1.Cu")
	)
	(gr_line
		(start 194.306952 -29.337)
		(end 195.145152 -29.337)
		(stroke
			(width 0.1016)
			(type default)
		)
		(layer "In1.Cu")
	)
	(gr_line
		(start 194.306952 -27.4828)
		(end 194.306952 -29.337)
		(stroke
			(width 0.1016)
			(type default)
		)
		(layer "In1.Cu")
	)
	(gr_line
		(start 194.357752 -29.2354)
		(end 194.357752 -27.559)
		(stroke
			(width 0.2032)
			(type default)
		)
		(layer "In1.Cu")
	)
	(gr_line
		(start 194.357752 -27.559)
		(end 195.424552 -27.559)
		(stroke
			(width 0.2032)
			(type default)
		)
		(layer "In1.Cu")
	)
	(gr_line
		(start 194.383152 -29.2608)
		(end 195.373752 -29.2608)
		(stroke
			(width 0.2032)
			(type default)
		)
		(layer "In1.Cu")
	)
	(gr_line
		(start 194.383152 -29.2354)
		(end 194.383152 -29.2608)
		(stroke
			(width 0.2032)
			(type default)
		)
		(layer "In1.Cu")
	)
	(gr_line
		(start 194.433952 -29.1846)
		(end 195.373752 -29.1846)
		(stroke
			(width 0.2032)
			(type default)
		)
		(layer "In1.Cu")
	)
	(gr_line
		(start 194.433952 -27.6098)
		(end 194.433952 -29.1846)
		(stroke
			(width 0.2032)
			(type default)
		)
		(layer "In1.Cu")
	)
	(gr_line
		(start 194.510152 -29.1084)
		(end 194.510152 -27.7622)
		(stroke
			(width 0.508)
			(type default)
		)
		(layer "In1.Cu")
	)
	(gr_line
		(start 194.535552 -29.1084)
		(end 195.195952 -29.1084)
		(stroke
			(width 0.508)
			(type default)
		)
		(layer "In1.Cu")
	)
	(gr_line
		(start 194.535552 -29.083)
		(end 194.535552 -27.7368)
		(stroke
			(width 0.508)
			(type default)
		)
		(layer "In1.Cu")
	)
	(gr_line
		(start 194.535552 -27.7114)
		(end 195.170552 -27.7114)
		(stroke
			(width 0.508)
			(type default)
		)
		(layer "In1.Cu")
	)
	(gr_line
		(start 194.560952 -29.083)
		(end 194.560952 -27.7368)
		(stroke
			(width 0.508)
			(type default)
		)
		(layer "In1.Cu")
	)
	(gr_line
		(start 194.586352 -29.083)
		(end 194.586352 -27.7368)
		(stroke
			(width 0.508)
			(type default)
		)
		(layer "In1.Cu")
	)
	(gr_line
		(start 194.637152 -29.1084)
		(end 194.637152 -27.7622)
		(stroke
			(width 0.508)
			(type default)
		)
		(layer "In1.Cu")
	)
	(gr_line
		(start 194.637152 -29.083)
		(end 194.637152 -27.7368)
		(stroke
			(width 0.508)
			(type default)
		)
		(layer "In1.Cu")
	)
	(gr_line
		(start 194.687952 -29.083)
		(end 194.687952 -27.7368)
		(stroke
			(width 0.508)
			(type default)
		)
		(layer "In1.Cu")
	)
	(gr_line
		(start 194.707002 -26.826972)
		(end 195.545202 -26.826972)
		(stroke
			(width 0.1016)
			(type default)
		)
		(layer "In1.Cu")
	)
	(gr_line
		(start 194.707002 -24.972772)
		(end 194.707002 -26.826972)
		(stroke
			(width 0.1016)
			(type default)
		)
		(layer "In1.Cu")
	)
	(gr_line
		(start 194.713352 -29.0576)
		(end 194.713352 -27.7114)
		(stroke
			(width 0.508)
			(type default)
		)
		(layer "In1.Cu")
	)
	(gr_line
		(start 194.738752 -29.083)
		(end 194.738752 -27.7368)
		(stroke
			(width 0.508)
			(type default)
		)
		(layer "In1.Cu")
	)
	(gr_line
		(start 194.757802 -26.725372)
		(end 194.757802 -25.048972)
		(stroke
			(width 0.2032)
			(type default)
		)
		(layer "In1.Cu")
	)
	(gr_line
		(start 194.757802 -25.048972)
		(end 195.824602 -25.048972)
		(stroke
			(width 0.2032)
			(type default)
		)
		(layer "In1.Cu")
	)
	(gr_line
		(start 194.764152 -29.083)
		(end 194.764152 -27.7368)
		(stroke
			(width 0.508)
			(type default)
		)
		(layer "In1.Cu")
	)
	(gr_line
		(start 194.783202 -26.750772)
		(end 195.773802 -26.750772)
		(stroke
			(width 0.2032)
			(type default)
		)
		(layer "In1.Cu")
	)
	(gr_line
		(start 194.783202 -26.725372)
		(end 194.783202 -26.750772)
		(stroke
			(width 0.2032)
			(type default)
		)
		(layer "In1.Cu")
	)
	(gr_line
		(start 194.789552 -29.083)
		(end 194.789552 -27.7368)
		(stroke
			(width 0.508)
			(type default)
		)
		(layer "In1.Cu")
	)
	(gr_line
		(start 194.834002 -26.674572)
		(end 195.773802 -26.674572)
		(stroke
			(width 0.2032)
			(type default)
		)
		(layer "In1.Cu")
	)
	(gr_line
		(start 194.834002 -25.099772)
		(end 194.834002 -26.674572)
		(stroke
			(width 0.2032)
			(type default)
		)
		(layer "In1.Cu")
	)
	(gr_line
		(start 194.840352 -29.083)
		(end 194.840352 -27.7368)
		(stroke
			(width 0.508)
			(type default)
		)
		(layer "In1.Cu")
	)
	(gr_line
		(start 194.865752 -29.083)
		(end 194.865752 -27.7368)
		(stroke
			(width 0.508)
			(type default)
		)
		(layer "In1.Cu")
	)
	(gr_line
		(start 194.891152 -29.083)
		(end 194.891152 -27.7368)
		(stroke
			(width 0.508)
			(type default)
		)
		(layer "In1.Cu")
	)
	(gr_line
		(start 194.910202 -26.598372)
		(end 194.910202 -25.252172)
		(stroke
			(width 0.508)
			(type default)
		)
		(layer "In1.Cu")
	)
	(gr_line
		(start 194.916552 -29.083)
		(end 194.916552 -27.7368)
		(stroke
			(width 0.508)
			(type default)
		)
		(layer "In1.Cu")
	)
	(gr_line
		(start 194.935602 -26.598372)
		(end 195.596002 -26.598372)
		(stroke
			(width 0.508)
			(type default)
		)
		(layer "In1.Cu")
	)
	(gr_line
		(start 194.935602 -26.572972)
		(end 194.935602 -25.226772)
		(stroke
			(width 0.508)
			(type default)
		)
		(layer "In1.Cu")
	)
	(gr_line
		(start 194.935602 -25.201372)
		(end 195.570602 -25.201372)
		(stroke
			(width 0.508)
			(type default)
		)
		(layer "In1.Cu")
	)
	(gr_line
		(start 194.941952 -29.1084)
		(end 194.941952 -27.7622)
		(stroke
			(width 0.508)
			(type default)
		)
		(layer "In1.Cu")
	)
	(gr_line
		(start 194.961002 -26.572972)
		(end 194.961002 -25.226772)
		(stroke
			(width 0.508)
			(type default)
		)
		(layer "In1.Cu")
	)
	(gr_line
		(start 194.967352 -29.1084)
		(end 194.967352 -27.7622)
		(stroke
			(width 0.508)
			(type default)
		)
		(layer "In1.Cu")
	)
	(gr_line
		(start 194.967352 -29.083)
		(end 194.967352 -27.7368)
		(stroke
			(width 0.508)
			(type default)
		)
		(layer "In1.Cu")
	)
	(gr_line
		(start 194.986402 -26.572972)
		(end 194.986402 -25.226772)
		(stroke
			(width 0.508)
			(type default)
		)
		(layer "In1.Cu")
	)
	(gr_line
		(start 194.992752 -29.083)
		(end 194.992752 -27.7368)
		(stroke
			(width 0.508)
			(type default)
		)
		(layer "In1.Cu")
	)
	(gr_line
		(start 195.018152 -29.083)
		(end 195.018152 -27.7368)
		(stroke
			(width 0.508)
			(type default)
		)
		(layer "In1.Cu")
	)
	(gr_line
		(start 195.037202 -26.598372)
		(end 195.037202 -25.252172)
		(stroke
			(width 0.508)
			(type default)
		)
		(layer "In1.Cu")
	)
	(gr_line
		(start 195.037202 -26.572972)
		(end 195.037202 -25.226772)
		(stroke
			(width 0.508)
			(type default)
		)
		(layer "In1.Cu")
	)
	(gr_line
		(start 195.043552 -29.083)
		(end 195.043552 -27.7368)
		(stroke
			(width 0.508)
			(type default)
		)
		(layer "In1.Cu")
	)
	(gr_line
		(start 195.068952 -29.1084)
		(end 195.068952 -27.7622)
		(stroke
			(width 0.508)
			(type default)
		)
		(layer "In1.Cu")
	)
	(gr_line
		(start 195.068952 -29.083)
		(end 195.068952 -27.7368)
		(stroke
			(width 0.508)
			(type default)
		)
		(layer "In1.Cu")
	)
	(gr_line
		(start 195.088002 -26.572972)
		(end 195.088002 -25.226772)
		(stroke
			(width 0.508)
			(type default)
		)
		(layer "In1.Cu")
	)
	(gr_line
		(start 195.094352 -29.1084)
		(end 195.094352 -27.7622)
		(stroke
			(width 0.508)
			(type default)
		)
		(layer "In1.Cu")
	)
	(gr_line
		(start 195.094352 -29.083)
		(end 195.094352 -27.7368)
		(stroke
			(width 0.508)
			(type default)
		)
		(layer "In1.Cu")
	)
	(gr_line
		(start 195.113402 -26.547572)
		(end 195.113402 -25.201372)
		(stroke
			(width 0.508)
			(type default)
		)
		(layer "In1.Cu")
	)
	(gr_line
		(start 195.119752 -29.1084)
		(end 195.119752 -27.7622)
		(stroke
			(width 0.508)
			(type default)
		)
		(layer "In1.Cu")
	)
	(gr_line
		(start 195.138802 -26.572972)
		(end 195.138802 -25.226772)
		(stroke
			(width 0.508)
			(type default)
		)
		(layer "In1.Cu")
	)
	(gr_line
		(start 195.145152 -29.337)
		(end 195.475352 -29.337)
		(stroke
			(width 0.1016)
			(type default)
		)
		(layer "In1.Cu")
	)
	(gr_line
		(start 195.145152 -29.083)
		(end 195.145152 -27.7368)
		(stroke
			(width 0.508)
			(type default)
		)
		(layer "In1.Cu")
	)
	(gr_line
		(start 195.164202 -26.572972)
		(end 195.164202 -25.226772)
		(stroke
			(width 0.508)
			(type default)
		)
		(layer "In1.Cu")
	)
	(gr_line
		(start 195.170552 -29.1084)
		(end 195.170552 -27.7622)
		(stroke
			(width 0.508)
			(type default)
		)
		(layer "In1.Cu")
	)
	(gr_line
		(start 195.170552 -29.083)
		(end 195.170552 -27.7368)
		(stroke
			(width 0.508)
			(type default)
		)
		(layer "In1.Cu")
	)
	(gr_line
		(start 195.189602 -26.572972)
		(end 195.189602 -25.226772)
		(stroke
			(width 0.508)
			(type default)
		)
		(layer "In1.Cu")
	)
	(gr_line
		(start 195.195952 -29.1084)
		(end 195.195952 -27.7622)
		(stroke
			(width 0.508)
			(type default)
		)
		(layer "In1.Cu")
	)
	(gr_line
		(start 195.240402 -26.572972)
		(end 195.240402 -25.226772)
		(stroke
			(width 0.508)
			(type default)
		)
		(layer "In1.Cu")
	)
	(gr_line
		(start 195.265802 -26.572972)
		(end 195.265802 -25.226772)
		(stroke
			(width 0.508)
			(type default)
		)
		(layer "In1.Cu")
	)
	(gr_line
		(start 195.272152 -29.1084)
		(end 195.272152 -27.7622)
		(stroke
			(width 0.508)
			(type default)
		)
		(layer "In1.Cu")
	)
	(gr_line
		(start 195.291202 -26.572972)
		(end 195.291202 -25.226772)
		(stroke
			(width 0.508)
			(type default)
		)
		(layer "In1.Cu")
	)
	(gr_line
		(start 195.316602 -26.572972)
		(end 195.316602 -25.226772)
		(stroke
			(width 0.508)
			(type default)
		)
		(layer "In1.Cu")
	)
	(gr_line
		(start 195.342002 -26.598372)
		(end 195.342002 -25.252172)
		(stroke
			(width 0.508)
			(type default)
		)
		(layer "In1.Cu")
	)
	(gr_line
		(start 195.367402 -26.598372)
		(end 195.367402 -25.252172)
		(stroke
			(width 0.508)
			(type default)
		)
		(layer "In1.Cu")
	)
	(gr_line
		(start 195.367402 -26.572972)
		(end 195.367402 -25.226772)
		(stroke
			(width 0.508)
			(type default)
		)
		(layer "In1.Cu")
	)
	(gr_line
		(start 195.373752 -29.2608)
		(end 195.373752 -27.6098)
		(stroke
			(width 0.2032)
			(type default)
		)
		(layer "In1.Cu")
	)
	(gr_line
		(start 195.373752 -29.2354)
		(end 194.357752 -29.2354)
		(stroke
			(width 0.2032)
			(type default)
		)
		(layer "In1.Cu")
	)
	(gr_line
		(start 195.373752 -29.1846)
		(end 195.373752 -29.2354)
		(stroke
			(width 0.2032)
			(type default)
		)
		(layer "In1.Cu")
	)
	(gr_line
		(start 195.373752 -27.6098)
		(end 194.433952 -27.6098)
		(stroke
			(width 0.2032)
			(type default)
		)
		(layer "In1.Cu")
	)
	(gr_line
		(start 195.392802 -26.572972)
		(end 195.392802 -25.226772)
		(stroke
			(width 0.508)
			(type default)
		)
		(layer "In1.Cu")
	)
	(gr_line
		(start 195.418202 -26.572972)
		(end 195.418202 -25.226772)
		(stroke
			(width 0.508)
			(type default)
		)
		(layer "In1.Cu")
	)
	(gr_line
		(start 195.424552 -29.2354)
		(end 194.383152 -29.2354)
		(stroke
			(width 0.2032)
			(type default)
		)
		(layer "In1.Cu")
	)
	(gr_line
		(start 195.424552 -27.559)
		(end 195.424552 -29.2354)
		(stroke
			(width 0.2032)
			(type default)
		)
		(layer "In1.Cu")
	)
	(gr_line
		(start 195.443602 -26.572972)
		(end 195.443602 -25.226772)
		(stroke
			(width 0.508)
			(type default)
		)
		(layer "In1.Cu")
	)
	(gr_line
		(start 195.469002 -26.598372)
		(end 195.469002 -25.252172)
		(stroke
			(width 0.508)
			(type default)
		)
		(layer "In1.Cu")
	)
	(gr_line
		(start 195.469002 -26.572972)
		(end 195.469002 -25.226772)
		(stroke
			(width 0.508)
			(type default)
		)
		(layer "In1.Cu")
	)
	(gr_line
		(start 195.475352 -29.337)
		(end 195.475352 -27.4828)
		(stroke
			(width 0.1016)
			(type default)
		)
		(layer "In1.Cu")
	)
	(gr_line
		(start 195.475352 -27.4828)
		(end 194.306952 -27.4828)
		(stroke
			(width 0.1016)
			(type default)
		)
		(layer "In1.Cu")
	)
	(gr_line
		(start 195.494402 -26.598372)
		(end 195.494402 -25.252172)
		(stroke
			(width 0.508)
			(type default)
		)
		(layer "In1.Cu")
	)
	(gr_line
		(start 195.494402 -26.572972)
		(end 195.494402 -25.226772)
		(stroke
			(width 0.508)
			(type default)
		)
		(layer "In1.Cu")
	)
	(gr_line
		(start 195.519802 -26.598372)
		(end 195.519802 -25.252172)
		(stroke
			(width 0.508)
			(type default)
		)
		(layer "In1.Cu")
	)
	(gr_line
		(start 195.545202 -26.826972)
		(end 195.875402 -26.826972)
		(stroke
			(width 0.1016)
			(type default)
		)
		(layer "In1.Cu")
	)
	(gr_line
		(start 195.545202 -26.572972)
		(end 195.545202 -25.226772)
		(stroke
			(width 0.508)
			(type default)
		)
		(layer "In1.Cu")
	)
	(gr_line
		(start 195.570602 -26.598372)
		(end 195.570602 -25.252172)
		(stroke
			(width 0.508)
			(type default)
		)
		(layer "In1.Cu")
	)
	(gr_line
		(start 195.570602 -26.572972)
		(end 195.570602 -25.226772)
		(stroke
			(width 0.508)
			(type default)
		)
		(layer "In1.Cu")
	)
	(gr_line
		(start 195.596002 -26.598372)
		(end 195.596002 -25.252172)
		(stroke
			(width 0.508)
			(type default)
		)
		(layer "In1.Cu")
	)
	(gr_line
		(start 195.672202 -26.598372)
		(end 195.672202 -25.252172)
		(stroke
			(width 0.508)
			(type default)
		)
		(layer "In1.Cu")
	)
	(gr_line
		(start 195.773802 -26.750772)
		(end 195.773802 -25.099772)
		(stroke
			(width 0.2032)
			(type default)
		)
		(layer "In1.Cu")
	)
	(gr_line
		(start 195.773802 -26.725372)
		(end 194.757802 -26.725372)
		(stroke
			(width 0.2032)
			(type default)
		)
		(layer "In1.Cu")
	)
	(gr_line
		(start 195.773802 -26.674572)
		(end 195.773802 -26.725372)
		(stroke
			(width 0.2032)
			(type default)
		)
		(layer "In1.Cu")
	)
	(gr_line
		(start 195.773802 -25.099772)
		(end 194.834002 -25.099772)
		(stroke
			(width 0.2032)
			(type default)
		)
		(layer "In1.Cu")
	)
	(gr_line
		(start 195.824602 -26.725372)
		(end 194.783202 -26.725372)
		(stroke
			(width 0.2032)
			(type default)
		)
		(layer "In1.Cu")
	)
	(gr_line
		(start 195.824602 -25.048972)
		(end 195.824602 -26.725372)
		(stroke
			(width 0.2032)
			(type default)
		)
		(layer "In1.Cu")
	)
	(gr_line
		(start 195.875402 -26.826972)
		(end 195.875402 -24.972772)
		(stroke
			(width 0.1016)
			(type default)
		)
		(layer "In1.Cu")
	)
	(gr_line
		(start 195.875402 -24.972772)
		(end 194.707002 -24.972772)
		(stroke
			(width 0.1016)
			(type default)
		)
		(layer "In1.Cu")
	)
	(gr_arc
		(start 197.300088 -8.263382)
		(mid 198.922885 -13.697276)
		(end 201.00036 -8.420608)
		(stroke
			(width 1.016)
			(type default)
		)
		(layer "In1.Cu")
	)
	(gr_line
		(start 197.300088 -4.907788)
		(end 197.300088 -8.263382)
		(stroke
			(width 1.016)
			(type default)
		)
		(layer "In1.Cu")
	)
	(gr_line
		(start 197.310756 -4.89712)
		(end 197.300088 -4.907788)
		(stroke
			(width 1.016)
			(type default)
		)
		(layer "In1.Cu")
	)
	(gr_line
		(start 197.6628 -24.67102)
		(end 197.6628 -23.40102)
		(stroke
			(width 0.7874)
			(type default)
		)
		(layer "In1.Cu")
	)
	(gr_line
		(start 199.04964 -10.700004)
		(end 199.049894 -10.700258)
		(stroke
			(width 4.064)
			(type default)
		)
		(layer "In1.Cu")
	)
	(gr_line
		(start 199.04964 -4.699762)
		(end 199.04964 -10.700004)
		(stroke
			(width 4.064)
			(type default)
		)
		(layer "In1.Cu")
	)
	(gr_line
		(start 199.049894 -10.700258)
		(end 199.049894 -10.700004)
		(stroke
			(width 6.604)
			(type default)
		)
		(layer "In1.Cu")
	)
	(gr_line
		(start 200.799954 -8.220202)
		(end 200.799954 -4.700016)
		(stroke
			(width 1.016)
			(type default)
		)
		(layer "In1.Cu")
	)
	(gr_arc
		(start 200.799954 -4.700016)
		(mid 198.951198 -2.952487)
		(end 197.310756 -4.89712)
		(stroke
			(width 1.016)
			(type default)
		)
		(layer "In1.Cu")
	)
	(gr_line
		(start 201.00036 -8.420608)
		(end 200.799954 -8.220202)
		(stroke
			(width 1.016)
			(type default)
		)
		(layer "In1.Cu")
	)
	(gr_line
		(start 202.989942 -50.390044)
		(end 203.36891 -50.464466)
		(stroke
			(width 1.016)
			(type default)
		)
		(layer "In1.Cu")
	)
	(gr_line
		(start 203.36891 -50.464466)
		(end 203.691236 -50.677064)
		(stroke
			(width 1.016)
			(type default)
		)
		(layer "In1.Cu")
	)
	(gr_line
		(start 203.691236 -50.677064)
		(end 203.909168 -50.996088)
		(stroke
			(width 1.016)
			(type default)
		)
		(layer "In1.Cu")
	)
	(gr_line
		(start 203.909168 -50.996088)
		(end 203.997814 -51.376072)
		(stroke
			(width 1.016)
			(type default)
		)
		(layer "In1.Cu")
	)
	(gr_line
		(start 203.997814 -51.376072)
		(end 204.06614 -51.702716)
		(stroke
			(width 1.016)
			(type default)
		)
		(layer "In1.Cu")
	)
	(gr_line
		(start 204.06614 -51.702716)
		(end 204.282802 -52.027074)
		(stroke
			(width 1.016)
			(type default)
		)
		(layer "In1.Cu")
	)
	(gr_line
		(start 204.282802 -52.027074)
		(end 204.607414 -52.24399)
		(stroke
			(width 1.016)
			(type default)
		)
		(layer "In1.Cu")
	)
	(gr_line
		(start 204.68336 -52.319936)
		(end 204.607414 -52.24399)
		(stroke
			(width 1.016)
			(type default)
		)
		(layer "In1.Cu")
	)
	(gr_arc
		(start 208.060036 -45.06341)
		(mid 209.682833 -50.497304)
		(end 211.760308 -45.220636)
		(stroke
			(width 1.016)
			(type default)
		)
		(layer "In1.Cu")
	)
	(gr_line
		(start 208.060036 -41.707816)
		(end 208.060036 -45.06341)
		(stroke
			(width 1.016)
			(type default)
		)
		(layer "In1.Cu")
	)
	(gr_line
		(start 208.070704 -41.697148)
		(end 208.060036 -41.707816)
		(stroke
			(width 1.016)
			(type default)
		)
		(layer "In1.Cu")
	)
	(gr_line
		(start 209.809588 -47.500032)
		(end 209.809842 -47.500286)
		(stroke
			(width 4.064)
			(type default)
		)
		(layer "In1.Cu")
	)
	(gr_line
		(start 209.809588 -41.49979)
		(end 209.809588 -47.500032)
		(stroke
			(width 4.064)
			(type default)
		)
		(layer "In1.Cu")
	)
	(gr_line
		(start 209.809842 -47.500286)
		(end 209.809842 -47.500032)
		(stroke
			(width 6.604)
			(type default)
		)
		(layer "In1.Cu")
	)
	(gr_line
		(start 211.559902 -45.02023)
		(end 211.559902 -41.500044)
		(stroke
			(width 1.016)
			(type default)
		)
		(layer "In1.Cu")
	)
	(gr_arc
		(start 211.559902 -41.500044)
		(mid 209.711146 -39.752515)
		(end 208.070704 -41.697148)
		(stroke
			(width 1.016)
			(type default)
		)
		(layer "In1.Cu")
	)
	(gr_line
		(start 211.760308 -45.220636)
		(end 211.559902 -45.02023)
		(stroke
			(width 1.016)
			(type default)
		)
		(layer "In1.Cu")
	)
	(gr_arc
		(start 278.06015 -8.263128)
		(mid 279.682947 -13.697022)
		(end 281.760422 -8.420354)
		(stroke
			(width 1.016)
			(type default)
		)
		(layer "In1.Cu")
	)
	(gr_line
		(start 278.06015 -4.907534)
		(end 278.06015 -8.263128)
		(stroke
			(width 1.016)
			(type default)
		)
		(layer "In1.Cu")
	)
	(gr_line
		(start 278.070818 -4.896866)
		(end 278.06015 -4.907534)
		(stroke
			(width 1.016)
			(type default)
		)
		(layer "In1.Cu")
	)
	(gr_line
		(start 279.809702 -10.69975)
		(end 279.809956 -10.700004)
		(stroke
			(width 4.064)
			(type default)
		)
		(layer "In1.Cu")
	)
	(gr_line
		(start 279.809702 -4.699508)
		(end 279.809702 -10.69975)
		(stroke
			(width 4.064)
			(type default)
		)
		(layer "In1.Cu")
	)
	(gr_line
		(start 279.809956 -10.700004)
		(end 279.809956 -10.69975)
		(stroke
			(width 6.604)
			(type default)
		)
		(layer "In1.Cu")
	)
	(gr_line
		(start 281.560016 -8.219948)
		(end 281.560016 -4.699762)
		(stroke
			(width 1.016)
			(type default)
		)
		(layer "In1.Cu")
	)
	(gr_arc
		(start 281.560016 -4.699762)
		(mid 279.71126 -2.952233)
		(end 278.070818 -4.896866)
		(stroke
			(width 1.016)
			(type default)
		)
		(layer "In1.Cu")
	)
	(gr_line
		(start 281.760422 -8.420354)
		(end 281.560016 -8.219948)
		(stroke
			(width 1.016)
			(type default)
		)
		(layer "In1.Cu")
	)
	(gr_arc
		(start 299.060108 -45.06341)
		(mid 300.682905 -50.497304)
		(end 302.76038 -45.220636)
		(stroke
			(width 1.016)
			(type default)
		)
		(layer "In1.Cu")
	)
	(gr_line
		(start 299.060108 -41.707816)
		(end 299.060108 -45.06341)
		(stroke
			(width 1.016)
			(type default)
		)
		(layer "In1.Cu")
	)
	(gr_line
		(start 299.070776 -41.697148)
		(end 299.060108 -41.707816)
		(stroke
			(width 1.016)
			(type default)
		)
		(layer "In1.Cu")
	)
	(gr_line
		(start 300.80966 -47.500032)
		(end 300.809914 -47.500286)
		(stroke
			(width 4.064)
			(type default)
		)
		(layer "In1.Cu")
	)
	(gr_line
		(start 300.80966 -41.49979)
		(end 300.80966 -47.500032)
		(stroke
			(width 4.064)
			(type default)
		)
		(layer "In1.Cu")
	)
	(gr_line
		(start 300.809914 -47.500286)
		(end 300.809914 -47.500032)
		(stroke
			(width 6.604)
			(type default)
		)
		(layer "In1.Cu")
	)
	(gr_line
		(start 302.559974 -45.02023)
		(end 302.559974 -41.500044)
		(stroke
			(width 1.016)
			(type default)
		)
		(layer "In1.Cu")
	)
	(gr_arc
		(start 302.559974 -41.500044)
		(mid 300.711218 -39.752515)
		(end 299.070776 -41.697148)
		(stroke
			(width 1.016)
			(type default)
		)
		(layer "In1.Cu")
	)
	(gr_line
		(start 302.76038 -45.220636)
		(end 302.559974 -45.02023)
		(stroke
			(width 1.016)
			(type default)
		)
		(layer "In1.Cu")
	)
	(gr_line
		(start 316.06998 -52.319936)
		(end 204.68336 -52.319936)
		(stroke
			(width 1.016)
			(type default)
		)
		(layer "In1.Cu")
	)
	(gr_arc
		(start 316.06998 -52.319936)
		(mid 316.777112 -52.027053)
		(end 317.069978 -51.319938)
		(stroke
			(width 1.016)
			(type default)
		)
		(layer "In1.Cu")
	)
	(gr_line
		(start 317.069978 -50.8)
		(end 317.069978 -51.319938)
		(stroke
			(width 1.016)
			(type default)
		)
		(layer "In1.Cu")
	)
	(gr_arc
		(start 318.069976 -49.800002)
		(mid 317.362871 -50.092895)
		(end 317.069978 -50.8)
		(stroke
			(width 1.016)
			(type default)
		)
		(layer "In1.Cu")
	)
	(gr_line
		(start 322.576698 -11.3792)
		(end 322.576698 -9.1948)
		(stroke
			(width 0.254)
			(type default)
		)
		(layer "In1.Cu")
	)
	(gr_line
		(start 322.576698 -9.1948)
		(end 324.151498 -9.1948)
		(stroke
			(width 0.254)
			(type default)
		)
		(layer "In1.Cu")
	)
	(gr_line
		(start 322.602098 -11.3792)
		(end 322.602098 -9.2456)
		(stroke
			(width 0.254)
			(type default)
		)
		(layer "In1.Cu")
	)
	(gr_line
		(start 322.602098 -9.2456)
		(end 324.126098 -9.2456)
		(stroke
			(width 0.254)
			(type default)
		)
		(layer "In1.Cu")
	)
	(gr_line
		(start 322.652898 -11.3538)
		(end 322.652898 -9.3726)
		(stroke
			(width 0.254)
			(type default)
		)
		(layer "In1.Cu")
	)
	(gr_line
		(start 322.652898 -9.3726)
		(end 324.100698 -9.3726)
		(stroke
			(width 0.254)
			(type default)
		)
		(layer "In1.Cu")
	)
	(gr_line
		(start 322.707 -11.303)
		(end 323.0118 -11.303)
		(stroke
			(width 0.1016)
			(type default)
		)
		(layer "In1.Cu")
	)
	(gr_line
		(start 322.707 -9.2964)
		(end 322.707 -11.303)
		(stroke
			(width 0.1016)
			(type default)
		)
		(layer "In1.Cu")
	)
	(gr_line
		(start 322.73494 -5.57784)
		(end 324.00494 -5.57784)
		(stroke
			(width 1.016)
			(type default)
		)
		(layer "In1.Cu")
	)
	(gr_line
		(start 322.7578 -11.2268)
		(end 323.85 -11.2268)
		(stroke
			(width 0.2032)
			(type default)
		)
		(layer "In1.Cu")
	)
	(gr_line
		(start 322.7578 -9.3726)
		(end 322.7578 -11.2268)
		(stroke
			(width 0.2032)
			(type default)
		)
		(layer "In1.Cu")
	)
	(gr_line
		(start 322.7832 -11.2268)
		(end 323.9516 -11.2268)
		(stroke
			(width 0.2032)
			(type default)
		)
		(layer "In1.Cu")
	)
	(gr_line
		(start 322.7832 -9.4234)
		(end 322.7832 -11.2268)
		(stroke
			(width 0.2032)
			(type default)
		)
		(layer "In1.Cu")
	)
	(gr_line
		(start 322.830698 -11.1252)
		(end 322.830698 -9.5758)
		(stroke
			(width 0.762)
			(type default)
		)
		(layer "In1.Cu")
	)
	(gr_line
		(start 322.830698 -11.1252)
		(end 323.745098 -11.1252)
		(stroke
			(width 0.762)
			(type default)
		)
		(layer "In1.Cu")
	)
	(gr_line
		(start 322.830698 -11.0998)
		(end 322.830698 -9.5504)
		(stroke
			(width 0.762)
			(type default)
		)
		(layer "In1.Cu")
	)
	(gr_line
		(start 322.830698 -10.9982)
		(end 322.830698 -9.4488)
		(stroke
			(width 0.762)
			(type default)
		)
		(layer "In1.Cu")
	)
	(gr_line
		(start 322.830698 -9.4488)
		(end 323.745098 -9.4488)
		(stroke
			(width 0.762)
			(type default)
		)
		(layer "In1.Cu")
	)
	(gr_line
		(start 322.834 -11.176)
		(end 323.9262 -11.176)
		(stroke
			(width 0.2032)
			(type default)
		)
		(layer "In1.Cu")
	)
	(gr_line
		(start 322.834 -9.4742)
		(end 322.834 -11.176)
		(stroke
			(width 0.2032)
			(type default)
		)
		(layer "In1.Cu")
	)
	(gr_line
		(start 322.856098 -10.9982)
		(end 323.770498 -10.9982)
		(stroke
			(width 0.762)
			(type default)
		)
		(layer "In1.Cu")
	)
	(gr_line
		(start 322.856098 -9.5758)
		(end 323.770498 -9.5758)
		(stroke
			(width 0.762)
			(type default)
		)
		(layer "In1.Cu")
	)
	(gr_line
		(start 322.9356 -11.0744)
		(end 323.723 -11.0744)
		(stroke
			(width 0.508)
			(type default)
		)
		(layer "In1.Cu")
	)
	(gr_line
		(start 322.9356 -11.049)
		(end 322.9356 -9.525)
		(stroke
			(width 0.508)
			(type default)
		)
		(layer "In1.Cu")
	)
	(gr_line
		(start 322.961 -11.0744)
		(end 322.961 -9.5504)
		(stroke
			(width 0.508)
			(type default)
		)
		(layer "In1.Cu")
	)
	(gr_line
		(start 322.983098 -11.1252)
		(end 323.897498 -11.1252)
		(stroke
			(width 0.762)
			(type default)
		)
		(layer "In1.Cu")
	)
	(gr_line
		(start 322.983098 -9.4488)
		(end 323.897498 -9.4488)
		(stroke
			(width 0.762)
			(type default)
		)
		(layer "In1.Cu")
	)
	(gr_line
		(start 322.9864 -9.525)
		(end 323.723 -9.525)
		(stroke
			(width 0.508)
			(type default)
		)
		(layer "In1.Cu")
	)
	(gr_line
		(start 323.0118 -11.303)
		(end 324.0024 -11.303)
		(stroke
			(width 0.1016)
			(type default)
		)
		(layer "In1.Cu")
	)
	(gr_line
		(start 323.0118 -11.0744)
		(end 323.0118 -9.5504)
		(stroke
			(width 0.508)
			(type default)
		)
		(layer "In1.Cu")
	)
	(gr_line
		(start 323.0372 -11.0744)
		(end 323.0372 -9.5504)
		(stroke
			(width 0.508)
			(type default)
		)
		(layer "In1.Cu")
	)
	(gr_line
		(start 323.0626 -11.0744)
		(end 323.0626 -9.5504)
		(stroke
			(width 0.508)
			(type default)
		)
		(layer "In1.Cu")
	)
	(gr_line
		(start 323.088 -11.0744)
		(end 323.088 -9.5504)
		(stroke
			(width 0.508)
			(type default)
		)
		(layer "In1.Cu")
	)
	(gr_line
		(start 323.088 -11.049)
		(end 323.088 -9.525)
		(stroke
			(width 0.508)
			(type default)
		)
		(layer "In1.Cu")
	)
	(gr_line
		(start 323.1134 -11.0744)
		(end 323.1134 -9.5504)
		(stroke
			(width 0.508)
			(type default)
		)
		(layer "In1.Cu")
	)
	(gr_line
		(start 323.1388 -11.0744)
		(end 323.1388 -9.5504)
		(stroke
			(width 0.508)
			(type default)
		)
		(layer "In1.Cu")
	)
	(gr_line
		(start 323.1896 -11.0744)
		(end 323.1896 -9.5504)
		(stroke
			(width 0.508)
			(type default)
		)
		(layer "In1.Cu")
	)
	(gr_line
		(start 323.1896 -11.049)
		(end 323.1896 -9.525)
		(stroke
			(width 0.508)
			(type default)
		)
		(layer "In1.Cu")
	)
	(gr_line
		(start 323.215 -11.0744)
		(end 323.215 -9.5504)
		(stroke
			(width 0.508)
			(type default)
		)
		(layer "In1.Cu")
	)
	(gr_line
		(start 323.2404 -11.0744)
		(end 323.2404 -9.5504)
		(stroke
			(width 0.508)
			(type default)
		)
		(layer "In1.Cu")
	)
	(gr_line
		(start 323.2658 -11.0744)
		(end 323.2658 -9.5504)
		(stroke
			(width 0.508)
			(type default)
		)
		(layer "In1.Cu")
	)
	(gr_line
		(start 323.3166 -11.0744)
		(end 323.3166 -9.5504)
		(stroke
			(width 0.508)
			(type default)
		)
		(layer "In1.Cu")
	)
	(gr_line
		(start 323.342 -11.0744)
		(end 323.342 -9.5504)
		(stroke
			(width 0.508)
			(type default)
		)
		(layer "In1.Cu")
	)
	(gr_line
		(start 323.342 -11.049)
		(end 323.342 -9.525)
		(stroke
			(width 0.508)
			(type default)
		)
		(layer "In1.Cu")
	)
	(gr_line
		(start 323.3674 -11.0744)
		(end 323.3674 -9.5504)
		(stroke
			(width 0.508)
			(type default)
		)
		(layer "In1.Cu")
	)
	(gr_line
		(start 323.3928 -11.0744)
		(end 323.3928 -9.5504)
		(stroke
			(width 0.508)
			(type default)
		)
		(layer "In1.Cu")
	)
	(gr_line
		(start 323.4182 -11.0744)
		(end 323.4182 -9.5504)
		(stroke
			(width 0.508)
			(type default)
		)
		(layer "In1.Cu")
	)
	(gr_line
		(start 323.4182 -11.049)
		(end 323.4182 -9.525)
		(stroke
			(width 0.508)
			(type default)
		)
		(layer "In1.Cu")
	)
	(gr_line
		(start 323.4436 -11.0744)
		(end 323.4436 -9.5504)
		(stroke
			(width 0.508)
			(type default)
		)
		(layer "In1.Cu")
	)
	(gr_line
		(start 323.469 -11.0744)
		(end 323.469 -9.5504)
		(stroke
			(width 0.508)
			(type default)
		)
		(layer "In1.Cu")
	)
	(gr_line
		(start 323.469 -11.049)
		(end 323.469 -9.525)
		(stroke
			(width 0.508)
			(type default)
		)
		(layer "In1.Cu")
	)
	(gr_line
		(start 323.4944 -11.0744)
		(end 323.4944 -9.5504)
		(stroke
			(width 0.508)
			(type default)
		)
		(layer "In1.Cu")
	)
	(gr_line
		(start 323.4944 -11.049)
		(end 323.4944 -9.525)
		(stroke
			(width 0.508)
			(type default)
		)
		(layer "In1.Cu")
	)
	(gr_line
		(start 323.5198 -11.049)
		(end 323.5198 -9.525)
		(stroke
			(width 0.508)
			(type default)
		)
		(layer "In1.Cu")
	)
	(gr_line
		(start 323.5452 -11.0744)
		(end 323.5452 -9.5504)
		(stroke
			(width 0.508)
			(type default)
		)
		(layer "In1.Cu")
	)
	(gr_line
		(start 323.567298 -11.3792)
		(end 322.576698 -11.3792)
		(stroke
			(width 0.254)
			(type default)
		)
		(layer "In1.Cu")
	)
	(gr_line
		(start 323.5706 -11.049)
		(end 323.5706 -9.525)
		(stroke
			(width 0.508)
			(type default)
		)
		(layer "In1.Cu")
	)
	(gr_line
		(start 323.596 -11.049)
		(end 323.596 -9.525)
		(stroke
			(width 0.508)
			(type default)
		)
		(layer "In1.Cu")
	)
	(gr_line
		(start 323.6214 -11.0744)
		(end 323.6214 -9.5504)
		(stroke
			(width 0.508)
			(type default)
		)
		(layer "In1.Cu")
	)
	(gr_line
		(start 323.6468 -11.0744)
		(end 323.6468 -9.5504)
		(stroke
			(width 0.508)
			(type default)
		)
		(layer "In1.Cu")
	)
	(gr_line
		(start 323.6468 -11.049)
		(end 323.6468 -9.525)
		(stroke
			(width 0.508)
			(type default)
		)
		(layer "In1.Cu")
	)
	(gr_line
		(start 323.6976 -11.0744)
		(end 323.6976 -9.5504)
		(stroke
			(width 0.508)
			(type default)
		)
		(layer "In1.Cu")
	)
	(gr_line
		(start 323.6976 -11.049)
		(end 323.6976 -9.525)
		(stroke
			(width 0.508)
			(type default)
		)
		(layer "In1.Cu")
	)
	(gr_line
		(start 323.7484 -11.0744)
		(end 323.7484 -9.5504)
		(stroke
			(width 0.508)
			(type default)
		)
		(layer "In1.Cu")
	)
	(gr_line
		(start 323.7484 -11.049)
		(end 323.7484 -9.525)
		(stroke
			(width 0.508)
			(type default)
		)
		(layer "In1.Cu")
	)
	(gr_line
		(start 323.770498 -11.0998)
		(end 323.770498 -9.5504)
		(stroke
			(width 0.762)
			(type default)
		)
		(layer "In1.Cu")
	)
	(gr_line
		(start 323.7738 -11.0744)
		(end 323.7738 -9.5504)
		(stroke
			(width 0.508)
			(type default)
		)
		(layer "In1.Cu")
	)
	(gr_line
		(start 323.7992 -11.0744)
		(end 323.7992 -9.5504)
		(stroke
			(width 0.508)
			(type default)
		)
		(layer "In1.Cu")
	)
	(gr_line
		(start 323.85 -11.2268)
		(end 323.8754 -11.2268)
		(stroke
			(width 0.2032)
			(type default)
		)
		(layer "In1.Cu")
	)
	(gr_line
		(start 323.8754 -11.2268)
		(end 323.8754 -9.4742)
		(stroke
			(width 0.2032)
			(type default)
		)
		(layer "In1.Cu")
	)
	(gr_line
		(start 323.8754 -9.4742)
		(end 322.834 -9.4742)
		(stroke
			(width 0.2032)
			(type default)
		)
		(layer "In1.Cu")
	)
	(gr_line
		(start 323.897498 -11.1252)
		(end 323.897498 -9.5758)
		(stroke
			(width 0.762)
			(type default)
		)
		(layer "In1.Cu")
	)
	(gr_line
		(start 323.897498 -11.0998)
		(end 323.897498 -9.6012)
		(stroke
			(width 0.762)
			(type default)
		)
		(layer "In1.Cu")
	)
	(gr_line
		(start 323.897498 -10.9982)
		(end 323.897498 -9.4488)
		(stroke
			(width 0.762)
			(type default)
		)
		(layer "In1.Cu")
	)
	(gr_line
		(start 323.9262 -11.176)
		(end 323.9262 -9.4234)
		(stroke
			(width 0.2032)
			(type default)
		)
		(layer "In1.Cu")
	)
	(gr_line
		(start 323.9262 -9.4234)
		(end 322.7832 -9.4234)
		(stroke
			(width 0.2032)
			(type default)
		)
		(layer "In1.Cu")
	)
	(gr_line
		(start 323.9516 -11.2268)
		(end 323.9516 -9.3726)
		(stroke
			(width 0.2032)
			(type default)
		)
		(layer "In1.Cu")
	)
	(gr_line
		(start 323.9516 -9.3726)
		(end 322.7578 -9.3726)
		(stroke
			(width 0.2032)
			(type default)
		)
		(layer "In1.Cu")
	)
	(gr_line
		(start 324.0024 -11.303)
		(end 324.0024 -9.2964)
		(stroke
			(width 0.1016)
			(type default)
		)
		(layer "In1.Cu")
	)
	(gr_line
		(start 324.0024 -9.2964)
		(end 322.707 -9.2964)
		(stroke
			(width 0.1016)
			(type default)
		)
		(layer "In1.Cu")
	)
	(gr_line
		(start 324.100698 -11.2268)
		(end 323.85 -11.2268)
		(stroke
			(width 0.254)
			(type default)
		)
		(layer "In1.Cu")
	)
	(gr_line
		(start 324.100698 -9.3726)
		(end 324.100698 -11.2268)
		(stroke
			(width 0.254)
			(type default)
		)
		(layer "In1.Cu")
	)
	(gr_line
		(start 324.126098 -11.3538)
		(end 322.652898 -11.3538)
		(stroke
			(width 0.254)
			(type default)
		)
		(layer "In1.Cu")
	)
	(gr_line
		(start 324.126098 -9.2456)
		(end 324.126098 -11.3538)
		(stroke
			(width 0.254)
			(type default)
		)
		(layer "In1.Cu")
	)
	(gr_line
		(start 324.151498 -11.3792)
		(end 322.602098 -11.3792)
		(stroke
			(width 0.254)
			(type default)
		)
		(layer "In1.Cu")
	)
	(gr_line
		(start 324.151498 -9.1948)
		(end 324.151498 -11.3792)
		(stroke
			(width 0.254)
			(type default)
		)
		(layer "In1.Cu")
	)
	(gr_line
		(start 327.37679 -11.3792)
		(end 327.37679 -9.1948)
		(stroke
			(width 0.254)
			(type default)
		)
		(layer "In1.Cu")
	)
	(gr_line
		(start 327.37679 -9.1948)
		(end 328.95159 -9.1948)
		(stroke
			(width 0.254)
			(type default)
		)
		(layer "In1.Cu")
	)
	(gr_line
		(start 327.40219 -11.3792)
		(end 327.40219 -9.2456)
		(stroke
			(width 0.254)
			(type default)
		)
		(layer "In1.Cu")
	)
	(gr_line
		(start 327.40219 -9.2456)
		(end 328.92619 -9.2456)
		(stroke
			(width 0.254)
			(type default)
		)
		(layer "In1.Cu")
	)
	(gr_line
		(start 327.45299 -11.3538)
		(end 327.45299 -9.3726)
		(stroke
			(width 0.254)
			(type default)
		)
		(layer "In1.Cu")
	)
	(gr_line
		(start 327.45299 -9.3726)
		(end 328.90079 -9.3726)
		(stroke
			(width 0.254)
			(type default)
		)
		(layer "In1.Cu")
	)
	(gr_line
		(start 327.507092 -11.303)
		(end 327.811892 -11.303)
		(stroke
			(width 0.1016)
			(type default)
		)
		(layer "In1.Cu")
	)
	(gr_line
		(start 327.507092 -9.2964)
		(end 327.507092 -11.303)
		(stroke
			(width 0.1016)
			(type default)
		)
		(layer "In1.Cu")
	)
	(gr_line
		(start 327.557892 -11.2268)
		(end 328.650092 -11.2268)
		(stroke
			(width 0.2032)
			(type default)
		)
		(layer "In1.Cu")
	)
	(gr_line
		(start 327.557892 -9.3726)
		(end 327.557892 -11.2268)
		(stroke
			(width 0.2032)
			(type default)
		)
		(layer "In1.Cu")
	)
	(gr_line
		(start 327.583292 -11.2268)
		(end 328.751692 -11.2268)
		(stroke
			(width 0.2032)
			(type default)
		)
		(layer "In1.Cu")
	)
	(gr_line
		(start 327.583292 -9.4234)
		(end 327.583292 -11.2268)
		(stroke
			(width 0.2032)
			(type default)
		)
		(layer "In1.Cu")
	)
	(gr_line
		(start 327.63079 -11.1252)
		(end 327.63079 -9.5758)
		(stroke
			(width 0.762)
			(type default)
		)
		(layer "In1.Cu")
	)
	(gr_line
		(start 327.63079 -11.1252)
		(end 328.54519 -11.1252)
		(stroke
			(width 0.762)
			(type default)
		)
		(layer "In1.Cu")
	)
	(gr_line
		(start 327.63079 -11.0998)
		(end 327.63079 -9.5504)
		(stroke
			(width 0.762)
			(type default)
		)
		(layer "In1.Cu")
	)
	(gr_line
		(start 327.63079 -10.9982)
		(end 327.63079 -9.4488)
		(stroke
			(width 0.762)
			(type default)
		)
		(layer "In1.Cu")
	)
	(gr_line
		(start 327.63079 -9.4488)
		(end 328.54519 -9.4488)
		(stroke
			(width 0.762)
			(type default)
		)
		(layer "In1.Cu")
	)
	(gr_line
		(start 327.634092 -11.176)
		(end 328.726292 -11.176)
		(stroke
			(width 0.2032)
			(type default)
		)
		(layer "In1.Cu")
	)
	(gr_line
		(start 327.634092 -9.4742)
		(end 327.634092 -11.176)
		(stroke
			(width 0.2032)
			(type default)
		)
		(layer "In1.Cu")
	)
	(gr_line
		(start 327.65619 -10.9982)
		(end 328.57059 -10.9982)
		(stroke
			(width 0.762)
			(type default)
		)
		(layer "In1.Cu")
	)
	(gr_line
		(start 327.65619 -9.5758)
		(end 328.57059 -9.5758)
		(stroke
			(width 0.762)
			(type default)
		)
		(layer "In1.Cu")
	)
	(gr_line
		(start 327.735692 -11.0744)
		(end 328.523092 -11.0744)
		(stroke
			(width 0.508)
			(type default)
		)
		(layer "In1.Cu")
	)
	(gr_line
		(start 327.735692 -11.049)
		(end 327.735692 -9.525)
		(stroke
			(width 0.508)
			(type default)
		)
		(layer "In1.Cu")
	)
	(gr_line
		(start 327.761092 -11.0744)
		(end 327.761092 -9.5504)
		(stroke
			(width 0.508)
			(type default)
		)
		(layer "In1.Cu")
	)
	(gr_line
		(start 327.78319 -11.1252)
		(end 328.69759 -11.1252)
		(stroke
			(width 0.762)
			(type default)
		)
		(layer "In1.Cu")
	)
	(gr_line
		(start 327.78319 -9.4488)
		(end 328.69759 -9.4488)
		(stroke
			(width 0.762)
			(type default)
		)
		(layer "In1.Cu")
	)
	(gr_line
		(start 327.786492 -9.525)
		(end 328.523092 -9.525)
		(stroke
			(width 0.508)
			(type default)
		)
		(layer "In1.Cu")
	)
	(gr_line
		(start 327.811892 -11.303)
		(end 328.802492 -11.303)
		(stroke
			(width 0.1016)
			(type default)
		)
		(layer "In1.Cu")
	)
	(gr_line
		(start 327.811892 -11.0744)
		(end 327.811892 -9.5504)
		(stroke
			(width 0.508)
			(type default)
		)
		(layer "In1.Cu")
	)
	(gr_line
		(start 327.837292 -11.0744)
		(end 327.837292 -9.5504)
		(stroke
			(width 0.508)
			(type default)
		)
		(layer "In1.Cu")
	)
	(gr_line
		(start 327.862692 -11.0744)
		(end 327.862692 -9.5504)
		(stroke
			(width 0.508)
			(type default)
		)
		(layer "In1.Cu")
	)
	(gr_line
		(start 327.888092 -11.0744)
		(end 327.888092 -9.5504)
		(stroke
			(width 0.508)
			(type default)
		)
		(layer "In1.Cu")
	)
	(gr_line
		(start 327.888092 -11.049)
		(end 327.888092 -9.525)
		(stroke
			(width 0.508)
			(type default)
		)
		(layer "In1.Cu")
	)
	(gr_line
		(start 327.913492 -11.0744)
		(end 327.913492 -9.5504)
		(stroke
			(width 0.508)
			(type default)
		)
		(layer "In1.Cu")
	)
	(gr_line
		(start 327.938892 -11.0744)
		(end 327.938892 -9.5504)
		(stroke
			(width 0.508)
			(type default)
		)
		(layer "In1.Cu")
	)
	(gr_line
		(start 327.989692 -11.0744)
		(end 327.989692 -9.5504)
		(stroke
			(width 0.508)
			(type default)
		)
		(layer "In1.Cu")
	)
	(gr_line
		(start 327.989692 -11.049)
		(end 327.989692 -9.525)
		(stroke
			(width 0.508)
			(type default)
		)
		(layer "In1.Cu")
	)
	(gr_line
		(start 328.015092 -11.0744)
		(end 328.015092 -9.5504)
		(stroke
			(width 0.508)
			(type default)
		)
		(layer "In1.Cu")
	)
	(gr_line
		(start 328.040492 -11.0744)
		(end 328.040492 -9.5504)
		(stroke
			(width 0.508)
			(type default)
		)
		(layer "In1.Cu")
	)
	(gr_line
		(start 328.065892 -11.0744)
		(end 328.065892 -9.5504)
		(stroke
			(width 0.508)
			(type default)
		)
		(layer "In1.Cu")
	)
	(gr_line
		(start 328.116692 -11.0744)
		(end 328.116692 -9.5504)
		(stroke
			(width 0.508)
			(type default)
		)
		(layer "In1.Cu")
	)
	(gr_line
		(start 328.142092 -11.0744)
		(end 328.142092 -9.5504)
		(stroke
			(width 0.508)
			(type default)
		)
		(layer "In1.Cu")
	)
	(gr_line
		(start 328.142092 -11.049)
		(end 328.142092 -9.525)
		(stroke
			(width 0.508)
			(type default)
		)
		(layer "In1.Cu")
	)
	(gr_line
		(start 328.167492 -11.0744)
		(end 328.167492 -9.5504)
		(stroke
			(width 0.508)
			(type default)
		)
		(layer "In1.Cu")
	)
	(gr_line
		(start 328.192892 -11.0744)
		(end 328.192892 -9.5504)
		(stroke
			(width 0.508)
			(type default)
		)
		(layer "In1.Cu")
	)
	(gr_line
		(start 328.218292 -11.0744)
		(end 328.218292 -9.5504)
		(stroke
			(width 0.508)
			(type default)
		)
		(layer "In1.Cu")
	)
	(gr_line
		(start 328.218292 -11.049)
		(end 328.218292 -9.525)
		(stroke
			(width 0.508)
			(type default)
		)
		(layer "In1.Cu")
	)
	(gr_line
		(start 328.243692 -11.0744)
		(end 328.243692 -9.5504)
		(stroke
			(width 0.508)
			(type default)
		)
		(layer "In1.Cu")
	)
	(gr_line
		(start 328.269092 -11.0744)
		(end 328.269092 -9.5504)
		(stroke
			(width 0.508)
			(type default)
		)
		(layer "In1.Cu")
	)
	(gr_line
		(start 328.269092 -11.049)
		(end 328.269092 -9.525)
		(stroke
			(width 0.508)
			(type default)
		)
		(layer "In1.Cu")
	)
	(gr_line
		(start 328.294492 -11.0744)
		(end 328.294492 -9.5504)
		(stroke
			(width 0.508)
			(type default)
		)
		(layer "In1.Cu")
	)
	(gr_line
		(start 328.294492 -11.049)
		(end 328.294492 -9.525)
		(stroke
			(width 0.508)
			(type default)
		)
		(layer "In1.Cu")
	)
	(gr_line
		(start 328.319892 -11.049)
		(end 328.319892 -9.525)
		(stroke
			(width 0.508)
			(type default)
		)
		(layer "In1.Cu")
	)
	(gr_line
		(start 328.345292 -11.0744)
		(end 328.345292 -9.5504)
		(stroke
			(width 0.508)
			(type default)
		)
		(layer "In1.Cu")
	)
	(gr_line
		(start 328.36739 -11.3792)
		(end 327.37679 -11.3792)
		(stroke
			(width 0.254)
			(type default)
		)
		(layer "In1.Cu")
	)
	(gr_line
		(start 328.370692 -11.049)
		(end 328.370692 -9.525)
		(stroke
			(width 0.508)
			(type default)
		)
		(layer "In1.Cu")
	)
	(gr_line
		(start 328.396092 -11.049)
		(end 328.396092 -9.525)
		(stroke
			(width 0.508)
			(type default)
		)
		(layer "In1.Cu")
	)
	(gr_line
		(start 328.421492 -11.0744)
		(end 328.421492 -9.5504)
		(stroke
			(width 0.508)
			(type default)
		)
		(layer "In1.Cu")
	)
	(gr_line
		(start 328.446892 -11.0744)
		(end 328.446892 -9.5504)
		(stroke
			(width 0.508)
			(type default)
		)
		(layer "In1.Cu")
	)
	(gr_line
		(start 328.446892 -11.049)
		(end 328.446892 -9.525)
		(stroke
			(width 0.508)
			(type default)
		)
		(layer "In1.Cu")
	)
	(gr_line
		(start 328.497692 -11.0744)
		(end 328.497692 -9.5504)
		(stroke
			(width 0.508)
			(type default)
		)
		(layer "In1.Cu")
	)
	(gr_line
		(start 328.497692 -11.049)
		(end 328.497692 -9.525)
		(stroke
			(width 0.508)
			(type default)
		)
		(layer "In1.Cu")
	)
	(gr_line
		(start 328.548492 -11.0744)
		(end 328.548492 -9.5504)
		(stroke
			(width 0.508)
			(type default)
		)
		(layer "In1.Cu")
	)
	(gr_line
		(start 328.548492 -11.049)
		(end 328.548492 -9.525)
		(stroke
			(width 0.508)
			(type default)
		)
		(layer "In1.Cu")
	)
	(gr_line
		(start 328.57059 -11.0998)
		(end 328.57059 -9.5504)
		(stroke
			(width 0.762)
			(type default)
		)
		(layer "In1.Cu")
	)
	(gr_line
		(start 328.573892 -11.0744)
		(end 328.573892 -9.5504)
		(stroke
			(width 0.508)
			(type default)
		)
		(layer "In1.Cu")
	)
	(gr_line
		(start 328.599292 -11.0744)
		(end 328.599292 -9.5504)
		(stroke
			(width 0.508)
			(type default)
		)
		(layer "In1.Cu")
	)
	(gr_line
		(start 328.650092 -11.2268)
		(end 328.675492 -11.2268)
		(stroke
			(width 0.2032)
			(type default)
		)
		(layer "In1.Cu")
	)
	(gr_line
		(start 328.675492 -11.2268)
		(end 328.675492 -9.4742)
		(stroke
			(width 0.2032)
			(type default)
		)
		(layer "In1.Cu")
	)
	(gr_line
		(start 328.675492 -9.4742)
		(end 327.634092 -9.4742)
		(stroke
			(width 0.2032)
			(type default)
		)
		(layer "In1.Cu")
	)
	(gr_line
		(start 328.69759 -11.1252)
		(end 328.69759 -9.5758)
		(stroke
			(width 0.762)
			(type default)
		)
		(layer "In1.Cu")
	)
	(gr_line
		(start 328.69759 -11.0998)
		(end 328.69759 -9.6012)
		(stroke
			(width 0.762)
			(type default)
		)
		(layer "In1.Cu")
	)
	(gr_line
		(start 328.69759 -10.9982)
		(end 328.69759 -9.4488)
		(stroke
			(width 0.762)
			(type default)
		)
		(layer "In1.Cu")
	)
	(gr_line
		(start 328.726292 -11.176)
		(end 328.726292 -9.4234)
		(stroke
			(width 0.2032)
			(type default)
		)
		(layer "In1.Cu")
	)
	(gr_line
		(start 328.726292 -9.4234)
		(end 327.583292 -9.4234)
		(stroke
			(width 0.2032)
			(type default)
		)
		(layer "In1.Cu")
	)
	(gr_line
		(start 328.751692 -11.2268)
		(end 328.751692 -9.3726)
		(stroke
			(width 0.2032)
			(type default)
		)
		(layer "In1.Cu")
	)
	(gr_line
		(start 328.751692 -9.3726)
		(end 327.557892 -9.3726)
		(stroke
			(width 0.2032)
			(type default)
		)
		(layer "In1.Cu")
	)
	(gr_line
		(start 328.802492 -11.303)
		(end 328.802492 -9.2964)
		(stroke
			(width 0.1016)
			(type default)
		)
		(layer "In1.Cu")
	)
	(gr_line
		(start 328.802492 -9.2964)
		(end 327.507092 -9.2964)
		(stroke
			(width 0.1016)
			(type default)
		)
		(layer "In1.Cu")
	)
	(gr_line
		(start 328.90079 -11.2268)
		(end 328.650092 -11.2268)
		(stroke
			(width 0.254)
			(type default)
		)
		(layer "In1.Cu")
	)
	(gr_line
		(start 328.90079 -9.3726)
		(end 328.90079 -11.2268)
		(stroke
			(width 0.254)
			(type default)
		)
		(layer "In1.Cu")
	)
	(gr_line
		(start 328.92619 -11.3538)
		(end 327.45299 -11.3538)
		(stroke
			(width 0.254)
			(type default)
		)
		(layer "In1.Cu")
	)
	(gr_line
		(start 328.92619 -9.2456)
		(end 328.92619 -11.3538)
		(stroke
			(width 0.254)
			(type default)
		)
		(layer "In1.Cu")
	)
	(gr_line
		(start 328.95159 -11.3792)
		(end 327.40219 -11.3792)
		(stroke
			(width 0.254)
			(type default)
		)
		(layer "In1.Cu")
	)
	(gr_line
		(start 328.95159 -9.1948)
		(end 328.95159 -11.3792)
		(stroke
			(width 0.254)
			(type default)
		)
		(layer "In1.Cu")
	)
	(gr_line
		(start 333.069946 -49.800002)
		(end 318.069976 -49.800002)
		(stroke
			(width 1.016)
			(type default)
		)
		(layer "In1.Cu")
	)
	(gr_line
		(start 334.069944 -51.319938)
		(end 334.069944 -50.8)
		(stroke
			(width 1.016)
			(type default)
		)
		(layer "In1.Cu")
	)
	(gr_arc
		(start 334.069944 -51.319938)
		(mid 334.362853 -52.027004)
		(end 335.069942 -52.319936)
		(stroke
			(width 1.016)
			(type default)
		)
		(layer "In1.Cu")
	)
	(gr_arc
		(start 334.069944 -50.8)
		(mid 333.777051 -50.092895)
		(end 333.069946 -49.800002)
		(stroke
			(width 1.016)
			(type default)
		)
		(layer "In1.Cu")
	)
	(gr_line
		(start 334.761586 -9.1948)
		(end 336.183986 -9.1948)
		(stroke
			(width 1.016)
			(type default)
		)
		(layer "In1.Cu")
	)
	(gr_line
		(start 338.856066 -13.843)
		(end 339.694266 -13.843)
		(stroke
			(width 0.1016)
			(type default)
		)
		(layer "In1.Cu")
	)
	(gr_line
		(start 338.856066 -11.1252)
		(end 338.856066 -13.843)
		(stroke
			(width 0.1016)
			(type default)
		)
		(layer "In1.Cu")
	)
	(gr_line
		(start 338.856066 -9.64311)
		(end 339.694266 -9.64311)
		(stroke
			(width 0.1016)
			(type default)
		)
		(layer "In1.Cu")
	)
	(gr_line
		(start 338.856066 -6.92531)
		(end 338.856066 -9.64311)
		(stroke
			(width 0.1016)
			(type default)
		)
		(layer "In1.Cu")
	)
	(gr_line
		(start 338.881466 -13.8176)
		(end 338.881466 -11.1506)
		(stroke
			(width 0.127)
			(type default)
		)
		(layer "In1.Cu")
	)
	(gr_line
		(start 338.881466 -11.1506)
		(end 340.176866 -11.1506)
		(stroke
			(width 0.127)
			(type default)
		)
		(layer "In1.Cu")
	)
	(gr_line
		(start 338.881466 -9.61771)
		(end 338.881466 -6.95071)
		(stroke
			(width 0.127)
			(type default)
		)
		(layer "In1.Cu")
	)
	(gr_line
		(start 338.881466 -6.95071)
		(end 340.176866 -6.95071)
		(stroke
			(width 0.127)
			(type default)
		)
		(layer "In1.Cu")
	)
	(gr_line
		(start 338.906866 -13.8176)
		(end 338.906866 -11.176)
		(stroke
			(width 0.127)
			(type default)
		)
		(layer "In1.Cu")
	)
	(gr_line
		(start 338.906866 -13.7922)
		(end 338.906866 -11.176)
		(stroke
			(width 0.1778)
			(type default)
		)
		(layer "In1.Cu")
	)
	(gr_line
		(start 338.906866 -11.176)
		(end 340.151466 -11.176)
		(stroke
			(width 0.127)
			(type default)
		)
		(layer "In1.Cu")
	)
	(gr_line
		(start 338.906866 -11.176)
		(end 340.151466 -11.176)
		(stroke
			(width 0.1778)
			(type default)
		)
		(layer "In1.Cu")
	)
	(gr_line
		(start 338.906866 -9.61771)
		(end 338.906866 -6.97611)
		(stroke
			(width 0.127)
			(type default)
		)
		(layer "In1.Cu")
	)
	(gr_line
		(start 338.906866 -9.59231)
		(end 338.906866 -6.97611)
		(stroke
			(width 0.1778)
			(type default)
		)
		(layer "In1.Cu")
	)
	(gr_line
		(start 338.906866 -6.97611)
		(end 340.151466 -6.97611)
		(stroke
			(width 0.127)
			(type default)
		)
		(layer "In1.Cu")
	)
	(gr_line
		(start 338.906866 -6.97611)
		(end 340.151466 -6.97611)
		(stroke
			(width 0.1778)
			(type default)
		)
		(layer "In1.Cu")
	)
	(gr_line
		(start 338.932266 -13.7922)
		(end 338.932266 -11.2014)
		(stroke
			(width 0.1778)
			(type default)
		)
		(layer "In1.Cu")
	)
	(gr_line
		(start 338.932266 -11.2014)
		(end 340.126066 -11.2014)
		(stroke
			(width 0.1778)
			(type default)
		)
		(layer "In1.Cu")
	)
	(gr_line
		(start 338.932266 -9.59231)
		(end 338.932266 -7.00151)
		(stroke
			(width 0.1778)
			(type default)
		)
		(layer "In1.Cu")
	)
	(gr_line
		(start 338.932266 -7.00151)
		(end 340.126066 -7.00151)
		(stroke
			(width 0.1778)
			(type default)
		)
		(layer "In1.Cu")
	)
	(gr_line
		(start 338.957666 -13.7668)
		(end 338.957666 -11.2268)
		(stroke
			(width 0.254)
			(type default)
		)
		(layer "In1.Cu")
	)
	(gr_line
		(start 338.957666 -11.2268)
		(end 340.126066 -11.2268)
		(stroke
			(width 0.254)
			(type default)
		)
		(layer "In1.Cu")
	)
	(gr_line
		(start 338.957666 -9.56691)
		(end 338.957666 -7.02691)
		(stroke
			(width 0.254)
			(type default)
		)
		(layer "In1.Cu")
	)
	(gr_line
		(start 338.957666 -7.02691)
		(end 340.126066 -7.02691)
		(stroke
			(width 0.254)
			(type default)
		)
		(layer "In1.Cu")
	)
	(gr_line
		(start 338.983066 -13.7668)
		(end 338.983066 -11.2522)
		(stroke
			(width 0.254)
			(type default)
		)
		(layer "In1.Cu")
	)
	(gr_line
		(start 338.983066 -11.2522)
		(end 340.100666 -11.2522)
		(stroke
			(width 0.254)
			(type default)
		)
		(layer "In1.Cu")
	)
	(gr_line
		(start 338.983066 -9.56691)
		(end 338.983066 -7.05231)
		(stroke
			(width 0.254)
			(type default)
		)
		(layer "In1.Cu")
	)
	(gr_line
		(start 338.983066 -7.05231)
		(end 340.100666 -7.05231)
		(stroke
			(width 0.254)
			(type default)
		)
		(layer "In1.Cu")
	)
	(gr_line
		(start 339.008466 -13.716)
		(end 339.008466 -11.2776)
		(stroke
			(width 0.3556)
			(type default)
		)
		(layer "In1.Cu")
	)
	(gr_line
		(start 339.008466 -11.2776)
		(end 340.049866 -11.2776)
		(stroke
			(width 0.3556)
			(type default)
		)
		(layer "In1.Cu")
	)
	(gr_line
		(start 339.008466 -9.51611)
		(end 339.008466 -7.07771)
		(stroke
			(width 0.3556)
			(type default)
		)
		(layer "In1.Cu")
	)
	(gr_line
		(start 339.008466 -7.07771)
		(end 340.049866 -7.07771)
		(stroke
			(width 0.3556)
			(type default)
		)
		(layer "In1.Cu")
	)
	(gr_line
		(start 339.059266 -13.6906)
		(end 339.059266 -11.3284)
		(stroke
			(width 0.381)
			(type default)
		)
		(layer "In1.Cu")
	)
	(gr_line
		(start 339.059266 -11.3284)
		(end 339.999066 -11.3284)
		(stroke
			(width 0.381)
			(type default)
		)
		(layer "In1.Cu")
	)
	(gr_line
		(start 339.059266 -9.49071)
		(end 339.059266 -7.12851)
		(stroke
			(width 0.381)
			(type default)
		)
		(layer "In1.Cu")
	)
	(gr_line
		(start 339.059266 -7.12851)
		(end 339.999066 -7.12851)
		(stroke
			(width 0.381)
			(type default)
		)
		(layer "In1.Cu")
	)
	(gr_line
		(start 339.135466 -13.6398)
		(end 339.135466 -11.3792)
		(stroke
			(width 0.381)
			(type default)
		)
		(layer "In1.Cu")
	)
	(gr_line
		(start 339.135466 -11.3792)
		(end 339.948266 -11.3792)
		(stroke
			(width 0.381)
			(type default)
		)
		(layer "In1.Cu")
	)
	(gr_line
		(start 339.135466 -9.43991)
		(end 339.135466 -7.17931)
		(stroke
			(width 0.381)
			(type default)
		)
		(layer "In1.Cu")
	)
	(gr_line
		(start 339.135466 -7.17931)
		(end 339.948266 -7.17931)
		(stroke
			(width 0.381)
			(type default)
		)
		(layer "In1.Cu")
	)
	(gr_line
		(start 339.160866 -13.5636)
		(end 339.160866 -11.3792)
		(stroke
			(width 0.508)
			(type default)
		)
		(layer "In1.Cu")
	)
	(gr_line
		(start 339.160866 -11.3792)
		(end 339.922866 -11.3792)
		(stroke
			(width 0.508)
			(type default)
		)
		(layer "In1.Cu")
	)
	(gr_line
		(start 339.160866 -9.36371)
		(end 339.160866 -7.17931)
		(stroke
			(width 0.508)
			(type default)
		)
		(layer "In1.Cu")
	)
	(gr_line
		(start 339.160866 -7.17931)
		(end 339.922866 -7.17931)
		(stroke
			(width 0.508)
			(type default)
		)
		(layer "In1.Cu")
	)
	(gr_line
		(start 339.186266 -13.4112)
		(end 339.770466 -13.4112)
		(stroke
			(width 0.762)
			(type default)
		)
		(layer "In1.Cu")
	)
	(gr_line
		(start 339.186266 -11.5824)
		(end 339.770466 -11.5824)
		(stroke
			(width 0.762)
			(type default)
		)
		(layer "In1.Cu")
	)
	(gr_line
		(start 339.186266 -9.21131)
		(end 339.770466 -9.21131)
		(stroke
			(width 0.762)
			(type default)
		)
		(layer "In1.Cu")
	)
	(gr_line
		(start 339.186266 -7.38251)
		(end 339.770466 -7.38251)
		(stroke
			(width 0.762)
			(type default)
		)
		(layer "In1.Cu")
	)
	(gr_line
		(start 339.211666 -13.5636)
		(end 339.211666 -11.43)
		(stroke
			(width 0.635)
			(type default)
		)
		(layer "In1.Cu")
	)
	(gr_line
		(start 339.211666 -13.5128)
		(end 339.211666 -11.4808)
		(stroke
			(width 0.762)
			(type default)
		)
		(layer "In1.Cu")
	)
	(gr_line
		(start 339.211666 -11.43)
		(end 339.897466 -11.43)
		(stroke
			(width 0.635)
			(type default)
		)
		(layer "In1.Cu")
	)
	(gr_line
		(start 339.211666 -9.36371)
		(end 339.211666 -7.23011)
		(stroke
			(width 0.635)
			(type default)
		)
		(layer "In1.Cu")
	)
	(gr_line
		(start 339.211666 -9.31291)
		(end 339.211666 -7.28091)
		(stroke
			(width 0.762)
			(type default)
		)
		(layer "In1.Cu")
	)
	(gr_line
		(start 339.211666 -7.23011)
		(end 339.897466 -7.23011)
		(stroke
			(width 0.635)
			(type default)
		)
		(layer "In1.Cu")
	)
	(gr_line
		(start 339.237066 -13.5128)
		(end 339.237066 -11.4808)
		(stroke
			(width 0.762)
			(type default)
		)
		(layer "In1.Cu")
	)
	(gr_line
		(start 339.237066 -11.4808)
		(end 339.821266 -11.4808)
		(stroke
			(width 0.762)
			(type default)
		)
		(layer "In1.Cu")
	)
	(gr_line
		(start 339.237066 -9.31291)
		(end 339.237066 -7.28091)
		(stroke
			(width 0.762)
			(type default)
		)
		(layer "In1.Cu")
	)
	(gr_line
		(start 339.237066 -7.28091)
		(end 339.821266 -7.28091)
		(stroke
			(width 0.762)
			(type default)
		)
		(layer "In1.Cu")
	)
	(gr_line
		(start 339.262466 -13.5128)
		(end 339.262466 -11.4808)
		(stroke
			(width 0.762)
			(type default)
		)
		(layer "In1.Cu")
	)
	(gr_line
		(start 339.262466 -13.5128)
		(end 339.846666 -13.5128)
		(stroke
			(width 0.762)
			(type default)
		)
		(layer "In1.Cu")
	)
	(gr_line
		(start 339.262466 -13.4874)
		(end 339.262466 -11.4554)
		(stroke
			(width 0.762)
			(type default)
		)
		(layer "In1.Cu")
	)
	(gr_line
		(start 339.262466 -9.31291)
		(end 339.262466 -7.28091)
		(stroke
			(width 0.762)
			(type default)
		)
		(layer "In1.Cu")
	)
	(gr_line
		(start 339.262466 -9.31291)
		(end 339.846666 -9.31291)
		(stroke
			(width 0.762)
			(type default)
		)
		(layer "In1.Cu")
	)
	(gr_line
		(start 339.262466 -9.28751)
		(end 339.262466 -7.25551)
		(stroke
			(width 0.762)
			(type default)
		)
		(layer "In1.Cu")
	)
	(gr_line
		(start 339.287866 -13.5128)
		(end 339.287866 -11.4808)
		(stroke
			(width 0.762)
			(type default)
		)
		(layer "In1.Cu")
	)
	(gr_line
		(start 339.287866 -9.31291)
		(end 339.287866 -7.28091)
		(stroke
			(width 0.762)
			(type default)
		)
		(layer "In1.Cu")
	)
	(gr_line
		(start 339.313266 -13.5128)
		(end 339.313266 -11.4808)
		(stroke
			(width 0.762)
			(type default)
		)
		(layer "In1.Cu")
	)
	(gr_line
		(start 339.313266 -9.31291)
		(end 339.313266 -7.28091)
		(stroke
			(width 0.762)
			(type default)
		)
		(layer "In1.Cu")
	)
	(gr_line
		(start 339.338666 -13.5128)
		(end 339.338666 -11.4808)
		(stroke
			(width 0.762)
			(type default)
		)
		(layer "In1.Cu")
	)
	(gr_line
		(start 339.338666 -9.31291)
		(end 339.338666 -7.28091)
		(stroke
			(width 0.762)
			(type default)
		)
		(layer "In1.Cu")
	)
	(gr_line
		(start 339.389466 -13.5128)
		(end 339.389466 -11.4808)
		(stroke
			(width 0.762)
			(type default)
		)
		(layer "In1.Cu")
	)
	(gr_line
		(start 339.389466 -9.31291)
		(end 339.389466 -7.28091)
		(stroke
			(width 0.762)
			(type default)
		)
		(layer "In1.Cu")
	)
	(gr_line
		(start 339.414866 -13.5128)
		(end 339.414866 -11.4808)
		(stroke
			(width 0.762)
			(type default)
		)
		(layer "In1.Cu")
	)
	(gr_line
		(start 339.414866 -9.31291)
		(end 339.414866 -7.28091)
		(stroke
			(width 0.762)
			(type default)
		)
		(layer "In1.Cu")
	)
	(gr_line
		(start 339.440266 -13.5128)
		(end 339.440266 -11.7094)
		(stroke
			(width 0.635)
			(type default)
		)
		(layer "In1.Cu")
	)
	(gr_line
		(start 339.440266 -11.7094)
		(end 339.541866 -11.7094)
		(stroke
			(width 0.635)
			(type default)
		)
		(layer "In1.Cu")
	)
	(gr_line
		(start 339.440266 -9.31291)
		(end 339.440266 -7.50951)
		(stroke
			(width 0.635)
			(type default)
		)
		(layer "In1.Cu")
	)
	(gr_line
		(start 339.440266 -7.50951)
		(end 339.541866 -7.50951)
		(stroke
			(width 0.635)
			(type default)
		)
		(layer "In1.Cu")
	)
	(gr_line
		(start 339.465666 -13.5128)
		(end 339.465666 -11.4808)
		(stroke
			(width 0.762)
			(type default)
		)
		(layer "In1.Cu")
	)
	(gr_line
		(start 339.465666 -13.4874)
		(end 339.465666 -11.4554)
		(stroke
			(width 0.762)
			(type default)
		)
		(layer "In1.Cu")
	)
	(gr_line
		(start 339.465666 -13.4366)
		(end 339.465666 -11.6586)
		(stroke
			(width 0.635)
			(type default)
		)
		(layer "In1.Cu")
	)
	(gr_line
		(start 339.465666 -9.31291)
		(end 339.465666 -7.28091)
		(stroke
			(width 0.762)
			(type default)
		)
		(layer "In1.Cu")
	)
	(gr_line
		(start 339.465666 -9.28751)
		(end 339.465666 -7.25551)
		(stroke
			(width 0.762)
			(type default)
		)
		(layer "In1.Cu")
	)
	(gr_line
		(start 339.465666 -9.23671)
		(end 339.465666 -7.45871)
		(stroke
			(width 0.635)
			(type default)
		)
		(layer "In1.Cu")
	)
	(gr_line
		(start 339.516466 -13.5128)
		(end 339.516466 -11.4808)
		(stroke
			(width 0.762)
			(type default)
		)
		(layer "In1.Cu")
	)
	(gr_line
		(start 339.516466 -9.31291)
		(end 339.516466 -7.28091)
		(stroke
			(width 0.762)
			(type default)
		)
		(layer "In1.Cu")
	)
	(gr_line
		(start 339.541866 -13.5128)
		(end 339.541866 -11.4808)
		(stroke
			(width 0.762)
			(type default)
		)
		(layer "In1.Cu")
	)
	(gr_line
		(start 339.541866 -13.4874)
		(end 339.541866 -11.4554)
		(stroke
			(width 0.762)
			(type default)
		)
		(layer "In1.Cu")
	)
	(gr_line
		(start 339.541866 -13.4366)
		(end 339.465666 -13.4366)
		(stroke
			(width 0.635)
			(type default)
		)
		(layer "In1.Cu")
	)
	(gr_line
		(start 339.541866 -11.7094)
		(end 339.541866 -13.4366)
		(stroke
			(width 0.635)
			(type default)
		)
		(layer "In1.Cu")
	)
	(gr_line
		(start 339.541866 -9.31291)
		(end 339.541866 -7.28091)
		(stroke
			(width 0.762)
			(type default)
		)
		(layer "In1.Cu")
	)
	(gr_line
		(start 339.541866 -9.28751)
		(end 339.541866 -7.25551)
		(stroke
			(width 0.762)
			(type default)
		)
		(layer "In1.Cu")
	)
	(gr_line
		(start 339.541866 -9.23671)
		(end 339.465666 -9.23671)
		(stroke
			(width 0.635)
			(type default)
		)
		(layer "In1.Cu")
	)
	(gr_line
		(start 339.541866 -7.50951)
		(end 339.541866 -9.23671)
		(stroke
			(width 0.635)
			(type default)
		)
		(layer "In1.Cu")
	)
	(gr_line
		(start 339.592666 -13.4874)
		(end 339.592666 -11.4554)
		(stroke
			(width 0.762)
			(type default)
		)
		(layer "In1.Cu")
	)
	(gr_line
		(start 339.592666 -9.28751)
		(end 339.592666 -7.25551)
		(stroke
			(width 0.762)
			(type default)
		)
		(layer "In1.Cu")
	)
	(gr_line
		(start 339.618066 -13.4874)
		(end 339.618066 -11.4554)
		(stroke
			(width 0.762)
			(type default)
		)
		(layer "In1.Cu")
	)
	(gr_line
		(start 339.618066 -9.28751)
		(end 339.618066 -7.25551)
		(stroke
			(width 0.762)
			(type default)
		)
		(layer "In1.Cu")
	)
	(gr_line
		(start 339.668866 -13.5128)
		(end 339.668866 -11.4808)
		(stroke
			(width 0.762)
			(type default)
		)
		(layer "In1.Cu")
	)
	(gr_line
		(start 339.668866 -9.31291)
		(end 339.668866 -7.28091)
		(stroke
			(width 0.762)
			(type default)
		)
		(layer "In1.Cu")
	)
	(gr_line
		(start 339.694266 -13.843)
		(end 340.202266 -13.843)
		(stroke
			(width 0.1016)
			(type default)
		)
		(layer "In1.Cu")
	)
	(gr_line
		(start 339.694266 -13.4874)
		(end 339.694266 -11.4554)
		(stroke
			(width 0.762)
			(type default)
		)
		(layer "In1.Cu")
	)
	(gr_line
		(start 339.694266 -9.64311)
		(end 340.202266 -9.64311)
		(stroke
			(width 0.1016)
			(type default)
		)
		(layer "In1.Cu")
	)
	(gr_line
		(start 339.694266 -9.28751)
		(end 339.694266 -7.25551)
		(stroke
			(width 0.762)
			(type default)
		)
		(layer "In1.Cu")
	)
	(gr_line
		(start 339.745066 -13.5128)
		(end 339.745066 -11.4808)
		(stroke
			(width 0.762)
			(type default)
		)
		(layer "In1.Cu")
	)
	(gr_line
		(start 339.745066 -13.4874)
		(end 339.745066 -11.4554)
		(stroke
			(width 0.762)
			(type default)
		)
		(layer "In1.Cu")
	)
	(gr_line
		(start 339.745066 -9.31291)
		(end 339.745066 -7.28091)
		(stroke
			(width 0.762)
			(type default)
		)
		(layer "In1.Cu")
	)
	(gr_line
		(start 339.745066 -9.28751)
		(end 339.745066 -7.25551)
		(stroke
			(width 0.762)
			(type default)
		)
		(layer "In1.Cu")
	)
	(gr_line
		(start 339.770466 -13.4874)
		(end 339.770466 -11.4554)
		(stroke
			(width 0.762)
			(type default)
		)
		(layer "In1.Cu")
	)
	(gr_line
		(start 339.770466 -9.28751)
		(end 339.770466 -7.25551)
		(stroke
			(width 0.762)
			(type default)
		)
		(layer "In1.Cu")
	)
	(gr_line
		(start 339.795866 -13.5636)
		(end 339.160866 -13.5636)
		(stroke
			(width 0.508)
			(type default)
		)
		(layer "In1.Cu")
	)
	(gr_line
		(start 339.795866 -13.5636)
		(end 339.211666 -13.5636)
		(stroke
			(width 0.635)
			(type default)
		)
		(layer "In1.Cu")
	)
	(gr_line
		(start 339.795866 -9.36371)
		(end 339.160866 -9.36371)
		(stroke
			(width 0.508)
			(type default)
		)
		(layer "In1.Cu")
	)
	(gr_line
		(start 339.795866 -9.36371)
		(end 339.211666 -9.36371)
		(stroke
			(width 0.635)
			(type default)
		)
		(layer "In1.Cu")
	)
	(gr_line
		(start 339.821266 -13.4874)
		(end 339.821266 -11.4554)
		(stroke
			(width 0.762)
			(type default)
		)
		(layer "In1.Cu")
	)
	(gr_line
		(start 339.821266 -9.28751)
		(end 339.821266 -7.25551)
		(stroke
			(width 0.762)
			(type default)
		)
		(layer "In1.Cu")
	)
	(gr_line
		(start 339.846666 -13.716)
		(end 339.008466 -13.716)
		(stroke
			(width 0.3556)
			(type default)
		)
		(layer "In1.Cu")
	)
	(gr_line
		(start 339.846666 -13.6906)
		(end 339.059266 -13.6906)
		(stroke
			(width 0.381)
			(type default)
		)
		(layer "In1.Cu")
	)
	(gr_line
		(start 339.846666 -9.51611)
		(end 339.008466 -9.51611)
		(stroke
			(width 0.3556)
			(type default)
		)
		(layer "In1.Cu")
	)
	(gr_line
		(start 339.846666 -9.49071)
		(end 339.059266 -9.49071)
		(stroke
			(width 0.381)
			(type default)
		)
		(layer "In1.Cu")
	)
	(gr_line
		(start 339.872066 -13.5128)
		(end 339.872066 -11.4808)
		(stroke
			(width 0.762)
			(type default)
		)
		(layer "In1.Cu")
	)
	(gr_line
		(start 339.872066 -9.31291)
		(end 339.872066 -7.28091)
		(stroke
			(width 0.762)
			(type default)
		)
		(layer "In1.Cu")
	)
	(gr_line
		(start 339.897466 -13.7668)
		(end 338.957666 -13.7668)
		(stroke
			(width 0.254)
			(type default)
		)
		(layer "In1.Cu")
	)
	(gr_line
		(start 339.897466 -13.5128)
		(end 339.440266 -13.5128)
		(stroke
			(width 0.635)
			(type default)
		)
		(layer "In1.Cu")
	)
	(gr_line
		(start 339.897466 -11.43)
		(end 339.897466 -13.5128)
		(stroke
			(width 0.635)
			(type default)
		)
		(layer "In1.Cu")
	)
	(gr_line
		(start 339.897466 -9.56691)
		(end 338.957666 -9.56691)
		(stroke
			(width 0.254)
			(type default)
		)
		(layer "In1.Cu")
	)
	(gr_line
		(start 339.897466 -9.31291)
		(end 339.440266 -9.31291)
		(stroke
			(width 0.635)
			(type default)
		)
		(layer "In1.Cu")
	)
	(gr_line
		(start 339.897466 -7.23011)
		(end 339.897466 -9.31291)
		(stroke
			(width 0.635)
			(type default)
		)
		(layer "In1.Cu")
	)
	(gr_line
		(start 339.922866 -13.7922)
		(end 338.906866 -13.7922)
		(stroke
			(width 0.1778)
			(type default)
		)
		(layer "In1.Cu")
	)
	(gr_line
		(start 339.922866 -13.5636)
		(end 339.795866 -13.5636)
		(stroke
			(width 0.508)
			(type default)
		)
		(layer "In1.Cu")
	)
	(gr_line
		(start 339.922866 -11.3792)
		(end 339.922866 -13.5636)
		(stroke
			(width 0.508)
			(type default)
		)
		(layer "In1.Cu")
	)
	(gr_line
		(start 339.922866 -9.59231)
		(end 338.906866 -9.59231)
		(stroke
			(width 0.1778)
			(type default)
		)
		(layer "In1.Cu")
	)
	(gr_line
		(start 339.922866 -9.36371)
		(end 339.795866 -9.36371)
		(stroke
			(width 0.508)
			(type default)
		)
		(layer "In1.Cu")
	)
	(gr_line
		(start 339.922866 -7.17931)
		(end 339.922866 -9.36371)
		(stroke
			(width 0.508)
			(type default)
		)
		(layer "In1.Cu")
	)
	(gr_line
		(start 339.948266 -13.5636)
		(end 339.795866 -13.5636)
		(stroke
			(width 0.381)
			(type default)
		)
		(layer "In1.Cu")
	)
	(gr_line
		(start 339.948266 -11.3792)
		(end 339.948266 -13.5636)
		(stroke
			(width 0.381)
			(type default)
		)
		(layer "In1.Cu")
	)
	(gr_line
		(start 339.948266 -9.36371)
		(end 339.795866 -9.36371)
		(stroke
			(width 0.381)
			(type default)
		)
		(layer "In1.Cu")
	)
	(gr_line
		(start 339.948266 -7.17931)
		(end 339.948266 -9.36371)
		(stroke
			(width 0.381)
			(type default)
		)
		(layer "In1.Cu")
	)
	(gr_line
		(start 339.999066 -13.6398)
		(end 339.135466 -13.6398)
		(stroke
			(width 0.381)
			(type default)
		)
		(layer "In1.Cu")
	)
	(gr_line
		(start 339.999066 -11.3284)
		(end 339.999066 -13.6398)
		(stroke
			(width 0.381)
			(type default)
		)
		(layer "In1.Cu")
	)
	(gr_line
		(start 339.999066 -9.43991)
		(end 339.135466 -9.43991)
		(stroke
			(width 0.381)
			(type default)
		)
		(layer "In1.Cu")
	)
	(gr_line
		(start 339.999066 -7.12851)
		(end 339.999066 -9.43991)
		(stroke
			(width 0.381)
			(type default)
		)
		(layer "In1.Cu")
	)
	(gr_line
		(start 340.049866 -13.6906)
		(end 339.846666 -13.6906)
		(stroke
			(width 0.3556)
			(type default)
		)
		(layer "In1.Cu")
	)
	(gr_line
		(start 340.049866 -11.2776)
		(end 340.049866 -13.6906)
		(stroke
			(width 0.3556)
			(type default)
		)
		(layer "In1.Cu")
	)
	(gr_line
		(start 340.049866 -9.49071)
		(end 339.846666 -9.49071)
		(stroke
			(width 0.3556)
			(type default)
		)
		(layer "In1.Cu")
	)
	(gr_line
		(start 340.049866 -7.07771)
		(end 340.049866 -9.49071)
		(stroke
			(width 0.3556)
			(type default)
		)
		(layer "In1.Cu")
	)
	(gr_line
		(start 340.075266 -13.8176)
		(end 338.881466 -13.8176)
		(stroke
			(width 0.127)
			(type default)
		)
		(layer "In1.Cu")
	)
	(gr_line
		(start 340.075266 -9.61771)
		(end 338.881466 -9.61771)
		(stroke
			(width 0.127)
			(type default)
		)
		(layer "In1.Cu")
	)
	(gr_line
		(start 340.100666 -13.716)
		(end 339.846666 -13.716)
		(stroke
			(width 0.254)
			(type default)
		)
		(layer "In1.Cu")
	)
	(gr_line
		(start 340.100666 -11.2522)
		(end 340.100666 -13.716)
		(stroke
			(width 0.254)
			(type default)
		)
		(layer "In1.Cu")
	)
	(gr_line
		(start 340.100666 -9.51611)
		(end 339.846666 -9.51611)
		(stroke
			(width 0.254)
			(type default)
		)
		(layer "In1.Cu")
	)
	(gr_line
		(start 340.100666 -7.05231)
		(end 340.100666 -9.51611)
		(stroke
			(width 0.254)
			(type default)
		)
		(layer "In1.Cu")
	)
	(gr_line
		(start 340.126066 -13.7668)
		(end 338.983066 -13.7668)
		(stroke
			(width 0.254)
			(type default)
		)
		(layer "In1.Cu")
	)
	(gr_line
		(start 340.126066 -13.7668)
		(end 339.897466 -13.7668)
		(stroke
			(width 0.1778)
			(type default)
		)
		(layer "In1.Cu")
	)
	(gr_line
		(start 340.126066 -11.2268)
		(end 340.126066 -13.7668)
		(stroke
			(width 0.254)
			(type default)
		)
		(layer "In1.Cu")
	)
	(gr_line
		(start 340.126066 -11.2014)
		(end 340.126066 -13.7668)
		(stroke
			(width 0.1778)
			(type default)
		)
		(layer "In1.Cu")
	)
	(gr_line
		(start 340.126066 -9.56691)
		(end 338.983066 -9.56691)
		(stroke
			(width 0.254)
			(type default)
		)
		(layer "In1.Cu")
	)
	(gr_line
		(start 340.126066 -9.56691)
		(end 339.897466 -9.56691)
		(stroke
			(width 0.1778)
			(type default)
		)
		(layer "In1.Cu")
	)
	(gr_line
		(start 340.126066 -7.02691)
		(end 340.126066 -9.56691)
		(stroke
			(width 0.254)
			(type default)
		)
		(layer "In1.Cu")
	)
	(gr_line
		(start 340.126066 -7.00151)
		(end 340.126066 -9.56691)
		(stroke
			(width 0.1778)
			(type default)
		)
		(layer "In1.Cu")
	)
	(gr_line
		(start 340.151466 -13.7922)
		(end 338.932266 -13.7922)
		(stroke
			(width 0.1778)
			(type default)
		)
		(layer "In1.Cu")
	)
	(gr_line
		(start 340.151466 -13.7922)
		(end 339.922866 -13.7922)
		(stroke
			(width 0.127)
			(type default)
		)
		(layer "In1.Cu")
	)
	(gr_line
		(start 340.151466 -11.176)
		(end 340.151466 -13.7922)
		(stroke
			(width 0.127)
			(type default)
		)
		(layer "In1.Cu")
	)
	(gr_line
		(start 340.151466 -11.176)
		(end 340.151466 -13.7922)
		(stroke
			(width 0.1778)
			(type default)
		)
		(layer "In1.Cu")
	)
	(gr_line
		(start 340.151466 -9.59231)
		(end 338.932266 -9.59231)
		(stroke
			(width 0.1778)
			(type default)
		)
		(layer "In1.Cu")
	)
	(gr_line
		(start 340.151466 -9.59231)
		(end 339.922866 -9.59231)
		(stroke
			(width 0.127)
			(type default)
		)
		(layer "In1.Cu")
	)
	(gr_line
		(start 340.151466 -6.97611)
		(end 340.151466 -9.59231)
		(stroke
			(width 0.127)
			(type default)
		)
		(layer "In1.Cu")
	)
	(gr_line
		(start 340.151466 -6.97611)
		(end 340.151466 -9.59231)
		(stroke
			(width 0.1778)
			(type default)
		)
		(layer "In1.Cu")
	)
	(gr_line
		(start 340.176866 -13.8176)
		(end 338.906866 -13.8176)
		(stroke
			(width 0.127)
			(type default)
		)
		(layer "In1.Cu")
	)
	(gr_line
		(start 340.176866 -11.1506)
		(end 340.176866 -13.8176)
		(stroke
			(width 0.127)
			(type default)
		)
		(layer "In1.Cu")
	)
	(gr_line
		(start 340.176866 -9.61771)
		(end 338.906866 -9.61771)
		(stroke
			(width 0.127)
			(type default)
		)
		(layer "In1.Cu")
	)
	(gr_line
		(start 340.176866 -6.95071)
		(end 340.176866 -9.61771)
		(stroke
			(width 0.127)
			(type default)
		)
		(layer "In1.Cu")
	)
	(gr_line
		(start 340.202266 -13.843)
		(end 340.202266 -11.1252)
		(stroke
			(width 0.1016)
			(type default)
		)
		(layer "In1.Cu")
	)
	(gr_line
		(start 340.202266 -11.1252)
		(end 338.856066 -11.1252)
		(stroke
			(width 0.1016)
			(type default)
		)
		(layer "In1.Cu")
	)
	(gr_line
		(start 340.202266 -9.64311)
		(end 340.202266 -6.92531)
		(stroke
			(width 0.1016)
			(type default)
		)
		(layer "In1.Cu")
	)
	(gr_line
		(start 340.202266 -6.92531)
		(end 338.856066 -6.92531)
		(stroke
			(width 0.1016)
			(type default)
		)
		(layer "In1.Cu")
	)
	(gr_line
		(start 348.856046 -12.543028)
		(end 349.694246 -12.543028)
		(stroke
			(width 0.1016)
			(type default)
		)
		(layer "In1.Cu")
	)
	(gr_line
		(start 348.856046 -9.825228)
		(end 348.856046 -12.543028)
		(stroke
			(width 0.1016)
			(type default)
		)
		(layer "In1.Cu")
	)
	(gr_line
		(start 348.856046 -8.343138)
		(end 349.694246 -8.343138)
		(stroke
			(width 0.1016)
			(type default)
		)
		(layer "In1.Cu")
	)
	(gr_line
		(start 348.856046 -5.625338)
		(end 348.856046 -8.343138)
		(stroke
			(width 0.1016)
			(type default)
		)
		(layer "In1.Cu")
	)
	(gr_line
		(start 348.881446 -12.517628)
		(end 348.881446 -9.850628)
		(stroke
			(width 0.127)
			(type default)
		)
		(layer "In1.Cu")
	)
	(gr_line
		(start 348.881446 -9.850628)
		(end 350.176846 -9.850628)
		(stroke
			(width 0.127)
			(type default)
		)
		(layer "In1.Cu")
	)
	(gr_line
		(start 348.881446 -8.317738)
		(end 348.881446 -5.650738)
		(stroke
			(width 0.127)
			(type default)
		)
		(layer "In1.Cu")
	)
	(gr_line
		(start 348.881446 -5.650738)
		(end 350.176846 -5.650738)
		(stroke
			(width 0.127)
			(type default)
		)
		(layer "In1.Cu")
	)
	(gr_line
		(start 348.906846 -12.517628)
		(end 348.906846 -9.876028)
		(stroke
			(width 0.127)
			(type default)
		)
		(layer "In1.Cu")
	)
	(gr_line
		(start 348.906846 -12.492228)
		(end 348.906846 -9.876028)
		(stroke
			(width 0.1778)
			(type default)
		)
		(layer "In1.Cu")
	)
	(gr_line
		(start 348.906846 -9.876028)
		(end 350.151446 -9.876028)
		(stroke
			(width 0.127)
			(type default)
		)
		(layer "In1.Cu")
	)
	(gr_line
		(start 348.906846 -9.876028)
		(end 350.151446 -9.876028)
		(stroke
			(width 0.1778)
			(type default)
		)
		(layer "In1.Cu")
	)
	(gr_line
		(start 348.906846 -8.317738)
		(end 348.906846 -5.676138)
		(stroke
			(width 0.127)
			(type default)
		)
		(layer "In1.Cu")
	)
	(gr_line
		(start 348.906846 -8.292338)
		(end 348.906846 -5.676138)
		(stroke
			(width 0.1778)
			(type default)
		)
		(layer "In1.Cu")
	)
	(gr_line
		(start 348.906846 -5.676138)
		(end 350.151446 -5.676138)
		(stroke
			(width 0.127)
			(type default)
		)
		(layer "In1.Cu")
	)
	(gr_line
		(start 348.906846 -5.676138)
		(end 350.151446 -5.676138)
		(stroke
			(width 0.1778)
			(type default)
		)
		(layer "In1.Cu")
	)
	(gr_line
		(start 348.932246 -12.492228)
		(end 348.932246 -9.901428)
		(stroke
			(width 0.1778)
			(type default)
		)
		(layer "In1.Cu")
	)
	(gr_line
		(start 348.932246 -9.901428)
		(end 350.126046 -9.901428)
		(stroke
			(width 0.1778)
			(type default)
		)
		(layer "In1.Cu")
	)
	(gr_line
		(start 348.932246 -8.292338)
		(end 348.932246 -5.701538)
		(stroke
			(width 0.1778)
			(type default)
		)
		(layer "In1.Cu")
	)
	(gr_line
		(start 348.932246 -5.701538)
		(end 350.126046 -5.701538)
		(stroke
			(width 0.1778)
			(type default)
		)
		(layer "In1.Cu")
	)
	(gr_line
		(start 348.957646 -12.466828)
		(end 348.957646 -9.926828)
		(stroke
			(width 0.254)
			(type default)
		)
		(layer "In1.Cu")
	)
	(gr_line
		(start 348.957646 -9.926828)
		(end 350.126046 -9.926828)
		(stroke
			(width 0.254)
			(type default)
		)
		(layer "In1.Cu")
	)
	(gr_line
		(start 348.957646 -8.266938)
		(end 348.957646 -5.726938)
		(stroke
			(width 0.254)
			(type default)
		)
		(layer "In1.Cu")
	)
	(gr_line
		(start 348.957646 -5.726938)
		(end 350.126046 -5.726938)
		(stroke
			(width 0.254)
			(type default)
		)
		(layer "In1.Cu")
	)
	(gr_line
		(start 348.983046 -12.466828)
		(end 348.983046 -9.952228)
		(stroke
			(width 0.254)
			(type default)
		)
		(layer "In1.Cu")
	)
	(gr_line
		(start 348.983046 -9.952228)
		(end 350.100646 -9.952228)
		(stroke
			(width 0.254)
			(type default)
		)
		(layer "In1.Cu")
	)
	(gr_line
		(start 348.983046 -8.266938)
		(end 348.983046 -5.752338)
		(stroke
			(width 0.254)
			(type default)
		)
		(layer "In1.Cu")
	)
	(gr_line
		(start 348.983046 -5.752338)
		(end 350.100646 -5.752338)
		(stroke
			(width 0.254)
			(type default)
		)
		(layer "In1.Cu")
	)
	(gr_line
		(start 349.008446 -12.416028)
		(end 349.008446 -9.977628)
		(stroke
			(width 0.3556)
			(type default)
		)
		(layer "In1.Cu")
	)
	(gr_line
		(start 349.008446 -9.977628)
		(end 350.049846 -9.977628)
		(stroke
			(width 0.3556)
			(type default)
		)
		(layer "In1.Cu")
	)
	(gr_line
		(start 349.008446 -8.216138)
		(end 349.008446 -5.777738)
		(stroke
			(width 0.3556)
			(type default)
		)
		(layer "In1.Cu")
	)
	(gr_line
		(start 349.008446 -5.777738)
		(end 350.049846 -5.777738)
		(stroke
			(width 0.3556)
			(type default)
		)
		(layer "In1.Cu")
	)
	(gr_line
		(start 349.059246 -12.390628)
		(end 349.059246 -10.028428)
		(stroke
			(width 0.381)
			(type default)
		)
		(layer "In1.Cu")
	)
	(gr_line
		(start 349.059246 -10.028428)
		(end 349.999046 -10.028428)
		(stroke
			(width 0.381)
			(type default)
		)
		(layer "In1.Cu")
	)
	(gr_line
		(start 349.059246 -8.190738)
		(end 349.059246 -5.828538)
		(stroke
			(width 0.381)
			(type default)
		)
		(layer "In1.Cu")
	)
	(gr_line
		(start 349.059246 -5.828538)
		(end 349.999046 -5.828538)
		(stroke
			(width 0.381)
			(type default)
		)
		(layer "In1.Cu")
	)
	(gr_line
		(start 349.135446 -12.339828)
		(end 349.135446 -10.079228)
		(stroke
			(width 0.381)
			(type default)
		)
		(layer "In1.Cu")
	)
	(gr_line
		(start 349.135446 -10.079228)
		(end 349.948246 -10.079228)
		(stroke
			(width 0.381)
			(type default)
		)
		(layer "In1.Cu")
	)
	(gr_line
		(start 349.135446 -8.139938)
		(end 349.135446 -5.879338)
		(stroke
			(width 0.381)
			(type default)
		)
		(layer "In1.Cu")
	)
	(gr_line
		(start 349.135446 -5.879338)
		(end 349.948246 -5.879338)
		(stroke
			(width 0.381)
			(type default)
		)
		(layer "In1.Cu")
	)
	(gr_line
		(start 349.160846 -12.263628)
		(end 349.160846 -10.079228)
		(stroke
			(width 0.508)
			(type default)
		)
		(layer "In1.Cu")
	)
	(gr_line
		(start 349.160846 -10.079228)
		(end 349.922846 -10.079228)
		(stroke
			(width 0.508)
			(type default)
		)
		(layer "In1.Cu")
	)
	(gr_line
		(start 349.160846 -8.063738)
		(end 349.160846 -5.879338)
		(stroke
			(width 0.508)
			(type default)
		)
		(layer "In1.Cu")
	)
	(gr_line
		(start 349.160846 -5.879338)
		(end 349.922846 -5.879338)
		(stroke
			(width 0.508)
			(type default)
		)
		(layer "In1.Cu")
	)
	(gr_line
		(start 349.186246 -12.111228)
		(end 349.770446 -12.111228)
		(stroke
			(width 0.762)
			(type default)
		)
		(layer "In1.Cu")
	)
	(gr_line
		(start 349.186246 -10.282428)
		(end 349.770446 -10.282428)
		(stroke
			(width 0.762)
			(type default)
		)
		(layer "In1.Cu")
	)
	(gr_line
		(start 349.186246 -7.911338)
		(end 349.770446 -7.911338)
		(stroke
			(width 0.762)
			(type default)
		)
		(layer "In1.Cu")
	)
	(gr_line
		(start 349.186246 -6.082538)
		(end 349.770446 -6.082538)
		(stroke
			(width 0.762)
			(type default)
		)
		(layer "In1.Cu")
	)
	(gr_line
		(start 349.211646 -12.263628)
		(end 349.211646 -10.130028)
		(stroke
			(width 0.635)
			(type default)
		)
		(layer "In1.Cu")
	)
	(gr_line
		(start 349.211646 -12.212828)
		(end 349.211646 -10.180828)
		(stroke
			(width 0.762)
			(type default)
		)
		(layer "In1.Cu")
	)
	(gr_line
		(start 349.211646 -10.130028)
		(end 349.897446 -10.130028)
		(stroke
			(width 0.635)
			(type default)
		)
		(layer "In1.Cu")
	)
	(gr_line
		(start 349.211646 -8.063738)
		(end 349.211646 -5.930138)
		(stroke
			(width 0.635)
			(type default)
		)
		(layer "In1.Cu")
	)
	(gr_line
		(start 349.211646 -8.012938)
		(end 349.211646 -5.980938)
		(stroke
			(width 0.762)
			(type default)
		)
		(layer "In1.Cu")
	)
	(gr_line
		(start 349.211646 -5.930138)
		(end 349.897446 -5.930138)
		(stroke
			(width 0.635)
			(type default)
		)
		(layer "In1.Cu")
	)
	(gr_line
		(start 349.237046 -12.212828)
		(end 349.237046 -10.180828)
		(stroke
			(width 0.762)
			(type default)
		)
		(layer "In1.Cu")
	)
	(gr_line
		(start 349.237046 -10.180828)
		(end 349.821246 -10.180828)
		(stroke
			(width 0.762)
			(type default)
		)
		(layer "In1.Cu")
	)
	(gr_line
		(start 349.237046 -8.012938)
		(end 349.237046 -5.980938)
		(stroke
			(width 0.762)
			(type default)
		)
		(layer "In1.Cu")
	)
	(gr_line
		(start 349.237046 -5.980938)
		(end 349.821246 -5.980938)
		(stroke
			(width 0.762)
			(type default)
		)
		(layer "In1.Cu")
	)
	(gr_line
		(start 349.262446 -12.212828)
		(end 349.262446 -10.180828)
		(stroke
			(width 0.762)
			(type default)
		)
		(layer "In1.Cu")
	)
	(gr_line
		(start 349.262446 -12.212828)
		(end 349.846646 -12.212828)
		(stroke
			(width 0.762)
			(type default)
		)
		(layer "In1.Cu")
	)
	(gr_line
		(start 349.262446 -12.187428)
		(end 349.262446 -10.155428)
		(stroke
			(width 0.762)
			(type default)
		)
		(layer "In1.Cu")
	)
	(gr_line
		(start 349.262446 -8.012938)
		(end 349.262446 -5.980938)
		(stroke
			(width 0.762)
			(type default)
		)
		(layer "In1.Cu")
	)
	(gr_line
		(start 349.262446 -8.012938)
		(end 349.846646 -8.012938)
		(stroke
			(width 0.762)
			(type default)
		)
		(layer "In1.Cu")
	)
	(gr_line
		(start 349.262446 -7.987538)
		(end 349.262446 -5.955538)
		(stroke
			(width 0.762)
			(type default)
		)
		(layer "In1.Cu")
	)
	(gr_line
		(start 349.287846 -12.212828)
		(end 349.287846 -10.180828)
		(stroke
			(width 0.762)
			(type default)
		)
		(layer "In1.Cu")
	)
	(gr_line
		(start 349.287846 -8.012938)
		(end 349.287846 -5.980938)
		(stroke
			(width 0.762)
			(type default)
		)
		(layer "In1.Cu")
	)
	(gr_line
		(start 349.313246 -12.212828)
		(end 349.313246 -10.180828)
		(stroke
			(width 0.762)
			(type default)
		)
		(layer "In1.Cu")
	)
	(gr_line
		(start 349.313246 -8.012938)
		(end 349.313246 -5.980938)
		(stroke
			(width 0.762)
			(type default)
		)
		(layer "In1.Cu")
	)
	(gr_line
		(start 349.338646 -12.212828)
		(end 349.338646 -10.180828)
		(stroke
			(width 0.762)
			(type default)
		)
		(layer "In1.Cu")
	)
	(gr_line
		(start 349.338646 -8.012938)
		(end 349.338646 -5.980938)
		(stroke
			(width 0.762)
			(type default)
		)
		(layer "In1.Cu")
	)
	(gr_line
		(start 349.389446 -12.212828)
		(end 349.389446 -10.180828)
		(stroke
			(width 0.762)
			(type default)
		)
		(layer "In1.Cu")
	)
	(gr_line
		(start 349.389446 -8.012938)
		(end 349.389446 -5.980938)
		(stroke
			(width 0.762)
			(type default)
		)
		(layer "In1.Cu")
	)
	(gr_line
		(start 349.414846 -12.212828)
		(end 349.414846 -10.180828)
		(stroke
			(width 0.762)
			(type default)
		)
		(layer "In1.Cu")
	)
	(gr_line
		(start 349.414846 -8.012938)
		(end 349.414846 -5.980938)
		(stroke
			(width 0.762)
			(type default)
		)
		(layer "In1.Cu")
	)
	(gr_line
		(start 349.440246 -12.212828)
		(end 349.440246 -10.409428)
		(stroke
			(width 0.635)
			(type default)
		)
		(layer "In1.Cu")
	)
	(gr_line
		(start 349.440246 -10.409428)
		(end 349.541846 -10.409428)
		(stroke
			(width 0.635)
			(type default)
		)
		(layer "In1.Cu")
	)
	(gr_line
		(start 349.440246 -8.012938)
		(end 349.440246 -6.209538)
		(stroke
			(width 0.635)
			(type default)
		)
		(layer "In1.Cu")
	)
	(gr_line
		(start 349.440246 -6.209538)
		(end 349.541846 -6.209538)
		(stroke
			(width 0.635)
			(type default)
		)
		(layer "In1.Cu")
	)
	(gr_line
		(start 349.465646 -12.212828)
		(end 349.465646 -10.180828)
		(stroke
			(width 0.762)
			(type default)
		)
		(layer "In1.Cu")
	)
	(gr_line
		(start 349.465646 -12.187428)
		(end 349.465646 -10.155428)
		(stroke
			(width 0.762)
			(type default)
		)
		(layer "In1.Cu")
	)
	(gr_line
		(start 349.465646 -12.136628)
		(end 349.465646 -10.358628)
		(stroke
			(width 0.635)
			(type default)
		)
		(layer "In1.Cu")
	)
	(gr_line
		(start 349.465646 -8.012938)
		(end 349.465646 -5.980938)
		(stroke
			(width 0.762)
			(type default)
		)
		(layer "In1.Cu")
	)
	(gr_line
		(start 349.465646 -7.987538)
		(end 349.465646 -5.955538)
		(stroke
			(width 0.762)
			(type default)
		)
		(layer "In1.Cu")
	)
	(gr_line
		(start 349.465646 -7.936738)
		(end 349.465646 -6.158738)
		(stroke
			(width 0.635)
			(type default)
		)
		(layer "In1.Cu")
	)
	(gr_line
		(start 349.516446 -12.212828)
		(end 349.516446 -10.180828)
		(stroke
			(width 0.762)
			(type default)
		)
		(layer "In1.Cu")
	)
	(gr_line
		(start 349.516446 -8.012938)
		(end 349.516446 -5.980938)
		(stroke
			(width 0.762)
			(type default)
		)
		(layer "In1.Cu")
	)
	(gr_line
		(start 349.541846 -12.212828)
		(end 349.541846 -10.180828)
		(stroke
			(width 0.762)
			(type default)
		)
		(layer "In1.Cu")
	)
	(gr_line
		(start 349.541846 -12.187428)
		(end 349.541846 -10.155428)
		(stroke
			(width 0.762)
			(type default)
		)
		(layer "In1.Cu")
	)
	(gr_line
		(start 349.541846 -12.136628)
		(end 349.465646 -12.136628)
		(stroke
			(width 0.635)
			(type default)
		)
		(layer "In1.Cu")
	)
	(gr_line
		(start 349.541846 -10.409428)
		(end 349.541846 -12.136628)
		(stroke
			(width 0.635)
			(type default)
		)
		(layer "In1.Cu")
	)
	(gr_line
		(start 349.541846 -8.012938)
		(end 349.541846 -5.980938)
		(stroke
			(width 0.762)
			(type default)
		)
		(layer "In1.Cu")
	)
	(gr_line
		(start 349.541846 -7.987538)
		(end 349.541846 -5.955538)
		(stroke
			(width 0.762)
			(type default)
		)
		(layer "In1.Cu")
	)
	(gr_line
		(start 349.541846 -7.936738)
		(end 349.465646 -7.936738)
		(stroke
			(width 0.635)
			(type default)
		)
		(layer "In1.Cu")
	)
	(gr_line
		(start 349.541846 -6.209538)
		(end 349.541846 -7.936738)
		(stroke
			(width 0.635)
			(type default)
		)
		(layer "In1.Cu")
	)
	(gr_line
		(start 349.592646 -12.187428)
		(end 349.592646 -10.155428)
		(stroke
			(width 0.762)
			(type default)
		)
		(layer "In1.Cu")
	)
	(gr_line
		(start 349.592646 -7.987538)
		(end 349.592646 -5.955538)
		(stroke
			(width 0.762)
			(type default)
		)
		(layer "In1.Cu")
	)
	(gr_line
		(start 349.618046 -12.187428)
		(end 349.618046 -10.155428)
		(stroke
			(width 0.762)
			(type default)
		)
		(layer "In1.Cu")
	)
	(gr_line
		(start 349.618046 -7.987538)
		(end 349.618046 -5.955538)
		(stroke
			(width 0.762)
			(type default)
		)
		(layer "In1.Cu")
	)
	(gr_line
		(start 349.668846 -12.212828)
		(end 349.668846 -10.180828)
		(stroke
			(width 0.762)
			(type default)
		)
		(layer "In1.Cu")
	)
	(gr_line
		(start 349.668846 -8.012938)
		(end 349.668846 -5.980938)
		(stroke
			(width 0.762)
			(type default)
		)
		(layer "In1.Cu")
	)
	(gr_line
		(start 349.694246 -12.543028)
		(end 350.202246 -12.543028)
		(stroke
			(width 0.1016)
			(type default)
		)
		(layer "In1.Cu")
	)
	(gr_line
		(start 349.694246 -12.187428)
		(end 349.694246 -10.155428)
		(stroke
			(width 0.762)
			(type default)
		)
		(layer "In1.Cu")
	)
	(gr_line
		(start 349.694246 -8.343138)
		(end 350.202246 -8.343138)
		(stroke
			(width 0.1016)
			(type default)
		)
		(layer "In1.Cu")
	)
	(gr_line
		(start 349.694246 -7.987538)
		(end 349.694246 -5.955538)
		(stroke
			(width 0.762)
			(type default)
		)
		(layer "In1.Cu")
	)
	(gr_line
		(start 349.745046 -12.212828)
		(end 349.745046 -10.180828)
		(stroke
			(width 0.762)
			(type default)
		)
		(layer "In1.Cu")
	)
	(gr_line
		(start 349.745046 -12.187428)
		(end 349.745046 -10.155428)
		(stroke
			(width 0.762)
			(type default)
		)
		(layer "In1.Cu")
	)
	(gr_line
		(start 349.745046 -8.012938)
		(end 349.745046 -5.980938)
		(stroke
			(width 0.762)
			(type default)
		)
		(layer "In1.Cu")
	)
	(gr_line
		(start 349.745046 -7.987538)
		(end 349.745046 -5.955538)
		(stroke
			(width 0.762)
			(type default)
		)
		(layer "In1.Cu")
	)
	(gr_line
		(start 349.770446 -12.187428)
		(end 349.770446 -10.155428)
		(stroke
			(width 0.762)
			(type default)
		)
		(layer "In1.Cu")
	)
	(gr_line
		(start 349.770446 -7.987538)
		(end 349.770446 -5.955538)
		(stroke
			(width 0.762)
			(type default)
		)
		(layer "In1.Cu")
	)
	(gr_line
		(start 349.795846 -12.263628)
		(end 349.160846 -12.263628)
		(stroke
			(width 0.508)
			(type default)
		)
		(layer "In1.Cu")
	)
	(gr_line
		(start 349.795846 -12.263628)
		(end 349.211646 -12.263628)
		(stroke
			(width 0.635)
			(type default)
		)
		(layer "In1.Cu")
	)
	(gr_line
		(start 349.795846 -8.063738)
		(end 349.160846 -8.063738)
		(stroke
			(width 0.508)
			(type default)
		)
		(layer "In1.Cu")
	)
	(gr_line
		(start 349.795846 -8.063738)
		(end 349.211646 -8.063738)
		(stroke
			(width 0.635)
			(type default)
		)
		(layer "In1.Cu")
	)
	(gr_line
		(start 349.821246 -12.187428)
		(end 349.821246 -10.155428)
		(stroke
			(width 0.762)
			(type default)
		)
		(layer "In1.Cu")
	)
	(gr_line
		(start 349.821246 -7.987538)
		(end 349.821246 -5.955538)
		(stroke
			(width 0.762)
			(type default)
		)
		(layer "In1.Cu")
	)
	(gr_line
		(start 349.846646 -12.416028)
		(end 349.008446 -12.416028)
		(stroke
			(width 0.3556)
			(type default)
		)
		(layer "In1.Cu")
	)
	(gr_line
		(start 349.846646 -12.390628)
		(end 349.059246 -12.390628)
		(stroke
			(width 0.381)
			(type default)
		)
		(layer "In1.Cu")
	)
	(gr_line
		(start 349.846646 -8.216138)
		(end 349.008446 -8.216138)
		(stroke
			(width 0.3556)
			(type default)
		)
		(layer "In1.Cu")
	)
	(gr_line
		(start 349.846646 -8.190738)
		(end 349.059246 -8.190738)
		(stroke
			(width 0.381)
			(type default)
		)
		(layer "In1.Cu")
	)
	(gr_line
		(start 349.872046 -12.212828)
		(end 349.872046 -10.180828)
		(stroke
			(width 0.762)
			(type default)
		)
		(layer "In1.Cu")
	)
	(gr_line
		(start 349.872046 -8.012938)
		(end 349.872046 -5.980938)
		(stroke
			(width 0.762)
			(type default)
		)
		(layer "In1.Cu")
	)
	(gr_line
		(start 349.897446 -12.466828)
		(end 348.957646 -12.466828)
		(stroke
			(width 0.254)
			(type default)
		)
		(layer "In1.Cu")
	)
	(gr_line
		(start 349.897446 -12.212828)
		(end 349.440246 -12.212828)
		(stroke
			(width 0.635)
			(type default)
		)
		(layer "In1.Cu")
	)
	(gr_line
		(start 349.897446 -10.130028)
		(end 349.897446 -12.212828)
		(stroke
			(width 0.635)
			(type default)
		)
		(layer "In1.Cu")
	)
	(gr_line
		(start 349.897446 -8.266938)
		(end 348.957646 -8.266938)
		(stroke
			(width 0.254)
			(type default)
		)
		(layer "In1.Cu")
	)
	(gr_line
		(start 349.897446 -8.012938)
		(end 349.440246 -8.012938)
		(stroke
			(width 0.635)
			(type default)
		)
		(layer "In1.Cu")
	)
	(gr_line
		(start 349.897446 -5.930138)
		(end 349.897446 -8.012938)
		(stroke
			(width 0.635)
			(type default)
		)
		(layer "In1.Cu")
	)
	(gr_line
		(start 349.922846 -12.492228)
		(end 348.906846 -12.492228)
		(stroke
			(width 0.1778)
			(type default)
		)
		(layer "In1.Cu")
	)
	(gr_line
		(start 349.922846 -12.263628)
		(end 349.795846 -12.263628)
		(stroke
			(width 0.508)
			(type default)
		)
		(layer "In1.Cu")
	)
	(gr_line
		(start 349.922846 -10.079228)
		(end 349.922846 -12.263628)
		(stroke
			(width 0.508)
			(type default)
		)
		(layer "In1.Cu")
	)
	(gr_line
		(start 349.922846 -8.292338)
		(end 348.906846 -8.292338)
		(stroke
			(width 0.1778)
			(type default)
		)
		(layer "In1.Cu")
	)
	(gr_line
		(start 349.922846 -8.063738)
		(end 349.795846 -8.063738)
		(stroke
			(width 0.508)
			(type default)
		)
		(layer "In1.Cu")
	)
	(gr_line
		(start 349.922846 -5.879338)
		(end 349.922846 -8.063738)
		(stroke
			(width 0.508)
			(type default)
		)
		(layer "In1.Cu")
	)
	(gr_line
		(start 349.948246 -12.263628)
		(end 349.795846 -12.263628)
		(stroke
			(width 0.381)
			(type default)
		)
		(layer "In1.Cu")
	)
	(gr_line
		(start 349.948246 -10.079228)
		(end 349.948246 -12.263628)
		(stroke
			(width 0.381)
			(type default)
		)
		(layer "In1.Cu")
	)
	(gr_line
		(start 349.948246 -8.063738)
		(end 349.795846 -8.063738)
		(stroke
			(width 0.381)
			(type default)
		)
		(layer "In1.Cu")
	)
	(gr_line
		(start 349.948246 -5.879338)
		(end 349.948246 -8.063738)
		(stroke
			(width 0.381)
			(type default)
		)
		(layer "In1.Cu")
	)
	(gr_line
		(start 349.999046 -12.339828)
		(end 349.135446 -12.339828)
		(stroke
			(width 0.381)
			(type default)
		)
		(layer "In1.Cu")
	)
	(gr_line
		(start 349.999046 -10.028428)
		(end 349.999046 -12.339828)
		(stroke
			(width 0.381)
			(type default)
		)
		(layer "In1.Cu")
	)
	(gr_line
		(start 349.999046 -8.139938)
		(end 349.135446 -8.139938)
		(stroke
			(width 0.381)
			(type default)
		)
		(layer "In1.Cu")
	)
	(gr_line
		(start 349.999046 -5.828538)
		(end 349.999046 -8.139938)
		(stroke
			(width 0.381)
			(type default)
		)
		(layer "In1.Cu")
	)
	(gr_line
		(start 350.049846 -12.390628)
		(end 349.846646 -12.390628)
		(stroke
			(width 0.3556)
			(type default)
		)
		(layer "In1.Cu")
	)
	(gr_line
		(start 350.049846 -9.977628)
		(end 350.049846 -12.390628)
		(stroke
			(width 0.3556)
			(type default)
		)
		(layer "In1.Cu")
	)
	(gr_line
		(start 350.049846 -8.190738)
		(end 349.846646 -8.190738)
		(stroke
			(width 0.3556)
			(type default)
		)
		(layer "In1.Cu")
	)
	(gr_line
		(start 350.049846 -5.777738)
		(end 350.049846 -8.190738)
		(stroke
			(width 0.3556)
			(type default)
		)
		(layer "In1.Cu")
	)
	(gr_line
		(start 350.075246 -12.517628)
		(end 348.881446 -12.517628)
		(stroke
			(width 0.127)
			(type default)
		)
		(layer "In1.Cu")
	)
	(gr_line
		(start 350.075246 -8.317738)
		(end 348.881446 -8.317738)
		(stroke
			(width 0.127)
			(type default)
		)
		(layer "In1.Cu")
	)
	(gr_line
		(start 350.100646 -12.416028)
		(end 349.846646 -12.416028)
		(stroke
			(width 0.254)
			(type default)
		)
		(layer "In1.Cu")
	)
	(gr_line
		(start 350.100646 -9.952228)
		(end 350.100646 -12.416028)
		(stroke
			(width 0.254)
			(type default)
		)
		(layer "In1.Cu")
	)
	(gr_line
		(start 350.100646 -8.216138)
		(end 349.846646 -8.216138)
		(stroke
			(width 0.254)
			(type default)
		)
		(layer "In1.Cu")
	)
	(gr_line
		(start 350.100646 -5.752338)
		(end 350.100646 -8.216138)
		(stroke
			(width 0.254)
			(type default)
		)
		(layer "In1.Cu")
	)
	(gr_line
		(start 350.126046 -12.466828)
		(end 348.983046 -12.466828)
		(stroke
			(width 0.254)
			(type default)
		)
		(layer "In1.Cu")
	)
	(gr_line
		(start 350.126046 -12.466828)
		(end 349.897446 -12.466828)
		(stroke
			(width 0.1778)
			(type default)
		)
		(layer "In1.Cu")
	)
	(gr_line
		(start 350.126046 -9.926828)
		(end 350.126046 -12.466828)
		(stroke
			(width 0.254)
			(type default)
		)
		(layer "In1.Cu")
	)
	(gr_line
		(start 350.126046 -9.901428)
		(end 350.126046 -12.466828)
		(stroke
			(width 0.1778)
			(type default)
		)
		(layer "In1.Cu")
	)
	(gr_line
		(start 350.126046 -8.266938)
		(end 348.983046 -8.266938)
		(stroke
			(width 0.254)
			(type default)
		)
		(layer "In1.Cu")
	)
	(gr_line
		(start 350.126046 -8.266938)
		(end 349.897446 -8.266938)
		(stroke
			(width 0.1778)
			(type default)
		)
		(layer "In1.Cu")
	)
	(gr_line
		(start 350.126046 -5.726938)
		(end 350.126046 -8.266938)
		(stroke
			(width 0.254)
			(type default)
		)
		(layer "In1.Cu")
	)
	(gr_line
		(start 350.126046 -5.701538)
		(end 350.126046 -8.266938)
		(stroke
			(width 0.1778)
			(type default)
		)
		(layer "In1.Cu")
	)
	(gr_line
		(start 350.151446 -12.492228)
		(end 348.932246 -12.492228)
		(stroke
			(width 0.1778)
			(type default)
		)
		(layer "In1.Cu")
	)
	(gr_line
		(start 350.151446 -12.492228)
		(end 349.922846 -12.492228)
		(stroke
			(width 0.127)
			(type default)
		)
		(layer "In1.Cu")
	)
	(gr_line
		(start 350.151446 -9.876028)
		(end 350.151446 -12.492228)
		(stroke
			(width 0.127)
			(type default)
		)
		(layer "In1.Cu")
	)
	(gr_line
		(start 350.151446 -9.876028)
		(end 350.151446 -12.492228)
		(stroke
			(width 0.1778)
			(type default)
		)
		(layer "In1.Cu")
	)
	(gr_line
		(start 350.151446 -8.292338)
		(end 348.932246 -8.292338)
		(stroke
			(width 0.1778)
			(type default)
		)
		(layer "In1.Cu")
	)
	(gr_line
		(start 350.151446 -8.292338)
		(end 349.922846 -8.292338)
		(stroke
			(width 0.127)
			(type default)
		)
		(layer "In1.Cu")
	)
	(gr_line
		(start 350.151446 -5.676138)
		(end 350.151446 -8.292338)
		(stroke
			(width 0.127)
			(type default)
		)
		(layer "In1.Cu")
	)
	(gr_line
		(start 350.151446 -5.676138)
		(end 350.151446 -8.292338)
		(stroke
			(width 0.1778)
			(type default)
		)
		(layer "In1.Cu")
	)
	(gr_line
		(start 350.176846 -12.517628)
		(end 348.906846 -12.517628)
		(stroke
			(width 0.127)
			(type default)
		)
		(layer "In1.Cu")
	)
	(gr_line
		(start 350.176846 -9.850628)
		(end 350.176846 -12.517628)
		(stroke
			(width 0.127)
			(type default)
		)
		(layer "In1.Cu")
	)
	(gr_line
		(start 350.176846 -8.317738)
		(end 348.906846 -8.317738)
		(stroke
			(width 0.127)
			(type default)
		)
		(layer "In1.Cu")
	)
	(gr_line
		(start 350.176846 -5.650738)
		(end 350.176846 -8.317738)
		(stroke
			(width 0.127)
			(type default)
		)
		(layer "In1.Cu")
	)
	(gr_line
		(start 350.202246 -12.543028)
		(end 350.202246 -9.825228)
		(stroke
			(width 0.1016)
			(type default)
		)
		(layer "In1.Cu")
	)
	(gr_line
		(start 350.202246 -9.825228)
		(end 348.856046 -9.825228)
		(stroke
			(width 0.1016)
			(type default)
		)
		(layer "In1.Cu")
	)
	(gr_line
		(start 350.202246 -8.343138)
		(end 350.202246 -5.625338)
		(stroke
			(width 0.1016)
			(type default)
		)
		(layer "In1.Cu")
	)
	(gr_line
		(start 350.202246 -5.625338)
		(end 348.856046 -5.625338)
		(stroke
			(width 0.1016)
			(type default)
		)
		(layer "In1.Cu")
	)
	(gr_line
		(start 353.918266 -3.95732)
		(end 353.918266 -5.22732)
		(stroke
			(width 1.016)
			(type default)
		)
		(layer "In1.Cu")
	)
	(gr_line
		(start 353.989894 -52.319936)
		(end 335.069942 -52.319936)
		(stroke
			(width 1.016)
			(type default)
		)
		(layer "In1.Cu")
	)
	(gr_arc
		(start 353.989894 -52.319936)
		(mid 354.697017 -52.027048)
		(end 354.989892 -51.319938)
		(stroke
			(width 1.016)
			(type default)
		)
		(layer "In1.Cu")
	)
	(gr_line
		(start 354.989892 -50.8)
		(end 354.989892 -51.319938)
		(stroke
			(width 1.016)
			(type default)
		)
		(layer "In1.Cu")
	)
	(gr_arc
		(start 355.98989 -49.800002)
		(mid 355.282785 -50.092895)
		(end 354.989892 -50.8)
		(stroke
			(width 1.016)
			(type default)
		)
		(layer "In1.Cu")
	)
	(gr_line
		(start 360.496866 -11.378946)
		(end 360.496866 -9.194546)
		(stroke
			(width 0.254)
			(type default)
		)
		(layer "In1.Cu")
	)
	(gr_line
		(start 360.496866 -9.194546)
		(end 362.071666 -9.194546)
		(stroke
			(width 0.254)
			(type default)
		)
		(layer "In1.Cu")
	)
	(gr_line
		(start 360.522266 -11.378946)
		(end 360.522266 -9.245346)
		(stroke
			(width 0.254)
			(type default)
		)
		(layer "In1.Cu")
	)
	(gr_line
		(start 360.522266 -9.245346)
		(end 362.046266 -9.245346)
		(stroke
			(width 0.254)
			(type default)
		)
		(layer "In1.Cu")
	)
	(gr_line
		(start 360.573066 -11.353546)
		(end 360.573066 -9.372346)
		(stroke
			(width 0.254)
			(type default)
		)
		(layer "In1.Cu")
	)
	(gr_line
		(start 360.573066 -9.372346)
		(end 362.020866 -9.372346)
		(stroke
			(width 0.254)
			(type default)
		)
		(layer "In1.Cu")
	)
	(gr_line
		(start 360.627168 -11.302746)
		(end 360.931968 -11.302746)
		(stroke
			(width 0.1016)
			(type default)
		)
		(layer "In1.Cu")
	)
	(gr_line
		(start 360.627168 -9.296146)
		(end 360.627168 -11.302746)
		(stroke
			(width 0.1016)
			(type default)
		)
		(layer "In1.Cu")
	)
	(gr_line
		(start 360.677968 -11.226546)
		(end 361.770168 -11.226546)
		(stroke
			(width 0.2032)
			(type default)
		)
		(layer "In1.Cu")
	)
	(gr_line
		(start 360.677968 -9.372346)
		(end 360.677968 -11.226546)
		(stroke
			(width 0.2032)
			(type default)
		)
		(layer "In1.Cu")
	)
	(gr_line
		(start 360.703368 -11.226546)
		(end 361.871768 -11.226546)
		(stroke
			(width 0.2032)
			(type default)
		)
		(layer "In1.Cu")
	)
	(gr_line
		(start 360.703368 -9.423146)
		(end 360.703368 -11.226546)
		(stroke
			(width 0.2032)
			(type default)
		)
		(layer "In1.Cu")
	)
	(gr_line
		(start 360.750866 -11.124946)
		(end 360.750866 -9.575546)
		(stroke
			(width 0.762)
			(type default)
		)
		(layer "In1.Cu")
	)
	(gr_line
		(start 360.750866 -11.124946)
		(end 361.665266 -11.124946)
		(stroke
			(width 0.762)
			(type default)
		)
		(layer "In1.Cu")
	)
	(gr_line
		(start 360.750866 -11.099546)
		(end 360.750866 -9.550146)
		(stroke
			(width 0.762)
			(type default)
		)
		(layer "In1.Cu")
	)
	(gr_line
		(start 360.750866 -10.997946)
		(end 360.750866 -9.448546)
		(stroke
			(width 0.762)
			(type default)
		)
		(layer "In1.Cu")
	)
	(gr_line
		(start 360.750866 -9.448546)
		(end 361.665266 -9.448546)
		(stroke
			(width 0.762)
			(type default)
		)
		(layer "In1.Cu")
	)
	(gr_line
		(start 360.754168 -11.175746)
		(end 361.846368 -11.175746)
		(stroke
			(width 0.2032)
			(type default)
		)
		(layer "In1.Cu")
	)
	(gr_line
		(start 360.754168 -9.473946)
		(end 360.754168 -11.175746)
		(stroke
			(width 0.2032)
			(type default)
		)
		(layer "In1.Cu")
	)
	(gr_line
		(start 360.776266 -10.997946)
		(end 361.690666 -10.997946)
		(stroke
			(width 0.762)
			(type default)
		)
		(layer "In1.Cu")
	)
	(gr_line
		(start 360.776266 -9.575546)
		(end 361.690666 -9.575546)
		(stroke
			(width 0.762)
			(type default)
		)
		(layer "In1.Cu")
	)
	(gr_line
		(start 360.855768 -11.074146)
		(end 361.643168 -11.074146)
		(stroke
			(width 0.508)
			(type default)
		)
		(layer "In1.Cu")
	)
	(gr_line
		(start 360.855768 -11.048746)
		(end 360.855768 -9.524746)
		(stroke
			(width 0.508)
			(type default)
		)
		(layer "In1.Cu")
	)
	(gr_line
		(start 360.881168 -11.074146)
		(end 360.881168 -9.550146)
		(stroke
			(width 0.508)
			(type default)
		)
		(layer "In1.Cu")
	)
	(gr_line
		(start 360.903266 -11.124946)
		(end 361.817666 -11.124946)
		(stroke
			(width 0.762)
			(type default)
		)
		(layer "In1.Cu")
	)
	(gr_line
		(start 360.903266 -9.448546)
		(end 361.817666 -9.448546)
		(stroke
			(width 0.762)
			(type default)
		)
		(layer "In1.Cu")
	)
	(gr_line
		(start 360.906568 -9.524746)
		(end 361.643168 -9.524746)
		(stroke
			(width 0.508)
			(type default)
		)
		(layer "In1.Cu")
	)
	(gr_line
		(start 360.931968 -11.302746)
		(end 361.922568 -11.302746)
		(stroke
			(width 0.1016)
			(type default)
		)
		(layer "In1.Cu")
	)
	(gr_line
		(start 360.931968 -11.074146)
		(end 360.931968 -9.550146)
		(stroke
			(width 0.508)
			(type default)
		)
		(layer "In1.Cu")
	)
	(gr_line
		(start 360.957368 -11.074146)
		(end 360.957368 -9.550146)
		(stroke
			(width 0.508)
			(type default)
		)
		(layer "In1.Cu")
	)
	(gr_line
		(start 360.982768 -11.074146)
		(end 360.982768 -9.550146)
		(stroke
			(width 0.508)
			(type default)
		)
		(layer "In1.Cu")
	)
	(gr_line
		(start 361.008168 -11.074146)
		(end 361.008168 -9.550146)
		(stroke
			(width 0.508)
			(type default)
		)
		(layer "In1.Cu")
	)
	(gr_line
		(start 361.008168 -11.048746)
		(end 361.008168 -9.524746)
		(stroke
			(width 0.508)
			(type default)
		)
		(layer "In1.Cu")
	)
	(gr_line
		(start 361.033568 -11.074146)
		(end 361.033568 -9.550146)
		(stroke
			(width 0.508)
			(type default)
		)
		(layer "In1.Cu")
	)
	(gr_line
		(start 361.058968 -11.074146)
		(end 361.058968 -9.550146)
		(stroke
			(width 0.508)
			(type default)
		)
		(layer "In1.Cu")
	)
	(gr_line
		(start 361.109768 -11.074146)
		(end 361.109768 -9.550146)
		(stroke
			(width 0.508)
			(type default)
		)
		(layer "In1.Cu")
	)
	(gr_line
		(start 361.109768 -11.048746)
		(end 361.109768 -9.524746)
		(stroke
			(width 0.508)
			(type default)
		)
		(layer "In1.Cu")
	)
	(gr_line
		(start 361.135168 -11.074146)
		(end 361.135168 -9.550146)
		(stroke
			(width 0.508)
			(type default)
		)
		(layer "In1.Cu")
	)
	(gr_line
		(start 361.160568 -11.074146)
		(end 361.160568 -9.550146)
		(stroke
			(width 0.508)
			(type default)
		)
		(layer "In1.Cu")
	)
	(gr_line
		(start 361.185968 -11.074146)
		(end 361.185968 -9.550146)
		(stroke
			(width 0.508)
			(type default)
		)
		(layer "In1.Cu")
	)
	(gr_line
		(start 361.236768 -11.074146)
		(end 361.236768 -9.550146)
		(stroke
			(width 0.508)
			(type default)
		)
		(layer "In1.Cu")
	)
	(gr_line
		(start 361.262168 -11.074146)
		(end 361.262168 -9.550146)
		(stroke
			(width 0.508)
			(type default)
		)
		(layer "In1.Cu")
	)
	(gr_line
		(start 361.262168 -11.048746)
		(end 361.262168 -9.524746)
		(stroke
			(width 0.508)
			(type default)
		)
		(layer "In1.Cu")
	)
	(gr_line
		(start 361.287568 -11.074146)
		(end 361.287568 -9.550146)
		(stroke
			(width 0.508)
			(type default)
		)
		(layer "In1.Cu")
	)
	(gr_line
		(start 361.312968 -11.074146)
		(end 361.312968 -9.550146)
		(stroke
			(width 0.508)
			(type default)
		)
		(layer "In1.Cu")
	)
	(gr_line
		(start 361.338368 -11.074146)
		(end 361.338368 -9.550146)
		(stroke
			(width 0.508)
			(type default)
		)
		(layer "In1.Cu")
	)
	(gr_line
		(start 361.338368 -11.048746)
		(end 361.338368 -9.524746)
		(stroke
			(width 0.508)
			(type default)
		)
		(layer "In1.Cu")
	)
	(gr_line
		(start 361.363768 -11.074146)
		(end 361.363768 -9.550146)
		(stroke
			(width 0.508)
			(type default)
		)
		(layer "In1.Cu")
	)
	(gr_line
		(start 361.389168 -11.074146)
		(end 361.389168 -9.550146)
		(stroke
			(width 0.508)
			(type default)
		)
		(layer "In1.Cu")
	)
	(gr_line
		(start 361.389168 -11.048746)
		(end 361.389168 -9.524746)
		(stroke
			(width 0.508)
			(type default)
		)
		(layer "In1.Cu")
	)
	(gr_line
		(start 361.414568 -11.074146)
		(end 361.414568 -9.550146)
		(stroke
			(width 0.508)
			(type default)
		)
		(layer "In1.Cu")
	)
	(gr_line
		(start 361.414568 -11.048746)
		(end 361.414568 -9.524746)
		(stroke
			(width 0.508)
			(type default)
		)
		(layer "In1.Cu")
	)
	(gr_line
		(start 361.439968 -11.048746)
		(end 361.439968 -9.524746)
		(stroke
			(width 0.508)
			(type default)
		)
		(layer "In1.Cu")
	)
	(gr_line
		(start 361.465368 -11.074146)
		(end 361.465368 -9.550146)
		(stroke
			(width 0.508)
			(type default)
		)
		(layer "In1.Cu")
	)
	(gr_line
		(start 361.487466 -11.378946)
		(end 360.496866 -11.378946)
		(stroke
			(width 0.254)
			(type default)
		)
		(layer "In1.Cu")
	)
	(gr_line
		(start 361.490768 -11.048746)
		(end 361.490768 -9.524746)
		(stroke
			(width 0.508)
			(type default)
		)
		(layer "In1.Cu")
	)
	(gr_line
		(start 361.516168 -11.048746)
		(end 361.516168 -9.524746)
		(stroke
			(width 0.508)
			(type default)
		)
		(layer "In1.Cu")
	)
	(gr_line
		(start 361.541568 -11.074146)
		(end 361.541568 -9.550146)
		(stroke
			(width 0.508)
			(type default)
		)
		(layer "In1.Cu")
	)
	(gr_line
		(start 361.566968 -11.074146)
		(end 361.566968 -9.550146)
		(stroke
			(width 0.508)
			(type default)
		)
		(layer "In1.Cu")
	)
	(gr_line
		(start 361.566968 -11.048746)
		(end 361.566968 -9.524746)
		(stroke
			(width 0.508)
			(type default)
		)
		(layer "In1.Cu")
	)
	(gr_line
		(start 361.617768 -11.074146)
		(end 361.617768 -9.550146)
		(stroke
			(width 0.508)
			(type default)
		)
		(layer "In1.Cu")
	)
	(gr_line
		(start 361.617768 -11.048746)
		(end 361.617768 -9.524746)
		(stroke
			(width 0.508)
			(type default)
		)
		(layer "In1.Cu")
	)
	(gr_line
		(start 361.668568 -11.074146)
		(end 361.668568 -9.550146)
		(stroke
			(width 0.508)
			(type default)
		)
		(layer "In1.Cu")
	)
	(gr_line
		(start 361.668568 -11.048746)
		(end 361.668568 -9.524746)
		(stroke
			(width 0.508)
			(type default)
		)
		(layer "In1.Cu")
	)
	(gr_line
		(start 361.690666 -11.099546)
		(end 361.690666 -9.550146)
		(stroke
			(width 0.762)
			(type default)
		)
		(layer "In1.Cu")
	)
	(gr_line
		(start 361.693968 -11.074146)
		(end 361.693968 -9.550146)
		(stroke
			(width 0.508)
			(type default)
		)
		(layer "In1.Cu")
	)
	(gr_line
		(start 361.719368 -11.074146)
		(end 361.719368 -9.550146)
		(stroke
			(width 0.508)
			(type default)
		)
		(layer "In1.Cu")
	)
	(gr_line
		(start 361.770168 -11.226546)
		(end 361.795568 -11.226546)
		(stroke
			(width 0.2032)
			(type default)
		)
		(layer "In1.Cu")
	)
	(gr_line
		(start 361.795568 -11.226546)
		(end 361.795568 -9.473946)
		(stroke
			(width 0.2032)
			(type default)
		)
		(layer "In1.Cu")
	)
	(gr_line
		(start 361.795568 -9.473946)
		(end 360.754168 -9.473946)
		(stroke
			(width 0.2032)
			(type default)
		)
		(layer "In1.Cu")
	)
	(gr_line
		(start 361.817666 -11.124946)
		(end 361.817666 -9.575546)
		(stroke
			(width 0.762)
			(type default)
		)
		(layer "In1.Cu")
	)
	(gr_line
		(start 361.817666 -11.099546)
		(end 361.817666 -9.600946)
		(stroke
			(width 0.762)
			(type default)
		)
		(layer "In1.Cu")
	)
	(gr_line
		(start 361.817666 -10.997946)
		(end 361.817666 -9.448546)
		(stroke
			(width 0.762)
			(type default)
		)
		(layer "In1.Cu")
	)
	(gr_line
		(start 361.846368 -11.175746)
		(end 361.846368 -9.423146)
		(stroke
			(width 0.2032)
			(type default)
		)
		(layer "In1.Cu")
	)
	(gr_line
		(start 361.846368 -9.423146)
		(end 360.703368 -9.423146)
		(stroke
			(width 0.2032)
			(type default)
		)
		(layer "In1.Cu")
	)
	(gr_line
		(start 361.871768 -11.226546)
		(end 361.871768 -9.372346)
		(stroke
			(width 0.2032)
			(type default)
		)
		(layer "In1.Cu")
	)
	(gr_line
		(start 361.871768 -9.372346)
		(end 360.677968 -9.372346)
		(stroke
			(width 0.2032)
			(type default)
		)
		(layer "In1.Cu")
	)
	(gr_line
		(start 361.922568 -11.302746)
		(end 361.922568 -9.296146)
		(stroke
			(width 0.1016)
			(type default)
		)
		(layer "In1.Cu")
	)
	(gr_line
		(start 361.922568 -9.296146)
		(end 360.627168 -9.296146)
		(stroke
			(width 0.1016)
			(type default)
		)
		(layer "In1.Cu")
	)
	(gr_line
		(start 362.020866 -11.226546)
		(end 361.770168 -11.226546)
		(stroke
			(width 0.254)
			(type default)
		)
		(layer "In1.Cu")
	)
	(gr_line
		(start 362.020866 -9.372346)
		(end 362.020866 -11.226546)
		(stroke
			(width 0.254)
			(type default)
		)
		(layer "In1.Cu")
	)
	(gr_line
		(start 362.046266 -11.353546)
		(end 360.573066 -11.353546)
		(stroke
			(width 0.254)
			(type default)
		)
		(layer "In1.Cu")
	)
	(gr_line
		(start 362.046266 -9.245346)
		(end 362.046266 -11.353546)
		(stroke
			(width 0.254)
			(type default)
		)
		(layer "In1.Cu")
	)
	(gr_line
		(start 362.071666 -11.378946)
		(end 360.522266 -11.378946)
		(stroke
			(width 0.254)
			(type default)
		)
		(layer "In1.Cu")
	)
	(gr_line
		(start 362.071666 -9.194546)
		(end 362.071666 -11.378946)
		(stroke
			(width 0.254)
			(type default)
		)
		(layer "In1.Cu")
	)
	(gr_line
		(start 365.296958 -11.378946)
		(end 365.296958 -9.194546)
		(stroke
			(width 0.254)
			(type default)
		)
		(layer "In1.Cu")
	)
	(gr_line
		(start 365.296958 -9.194546)
		(end 366.871758 -9.194546)
		(stroke
			(width 0.254)
			(type default)
		)
		(layer "In1.Cu")
	)
	(gr_line
		(start 365.322358 -11.378946)
		(end 365.322358 -9.245346)
		(stroke
			(width 0.254)
			(type default)
		)
		(layer "In1.Cu")
	)
	(gr_line
		(start 365.322358 -9.245346)
		(end 366.846358 -9.245346)
		(stroke
			(width 0.254)
			(type default)
		)
		(layer "In1.Cu")
	)
	(gr_line
		(start 365.373158 -11.353546)
		(end 365.373158 -9.372346)
		(stroke
			(width 0.254)
			(type default)
		)
		(layer "In1.Cu")
	)
	(gr_line
		(start 365.373158 -9.372346)
		(end 366.820958 -9.372346)
		(stroke
			(width 0.254)
			(type default)
		)
		(layer "In1.Cu")
	)
	(gr_line
		(start 365.42726 -11.302746)
		(end 365.73206 -11.302746)
		(stroke
			(width 0.1016)
			(type default)
		)
		(layer "In1.Cu")
	)
	(gr_line
		(start 365.42726 -9.296146)
		(end 365.42726 -11.302746)
		(stroke
			(width 0.1016)
			(type default)
		)
		(layer "In1.Cu")
	)
	(gr_line
		(start 365.4552 -5.715)
		(end 366.7252 -5.715)
		(stroke
			(width 1.016)
			(type default)
		)
		(layer "In1.Cu")
	)
	(gr_line
		(start 365.47806 -11.226546)
		(end 366.57026 -11.226546)
		(stroke
			(width 0.2032)
			(type default)
		)
		(layer "In1.Cu")
	)
	(gr_line
		(start 365.47806 -9.372346)
		(end 365.47806 -11.226546)
		(stroke
			(width 0.2032)
			(type default)
		)
		(layer "In1.Cu")
	)
	(gr_line
		(start 365.50346 -11.226546)
		(end 366.67186 -11.226546)
		(stroke
			(width 0.2032)
			(type default)
		)
		(layer "In1.Cu")
	)
	(gr_line
		(start 365.50346 -9.423146)
		(end 365.50346 -11.226546)
		(stroke
			(width 0.2032)
			(type default)
		)
		(layer "In1.Cu")
	)
	(gr_line
		(start 365.550958 -11.124946)
		(end 365.550958 -9.575546)
		(stroke
			(width 0.762)
			(type default)
		)
		(layer "In1.Cu")
	)
	(gr_line
		(start 365.550958 -11.124946)
		(end 366.465358 -11.124946)
		(stroke
			(width 0.762)
			(type default)
		)
		(layer "In1.Cu")
	)
	(gr_line
		(start 365.550958 -11.099546)
		(end 365.550958 -9.550146)
		(stroke
			(width 0.762)
			(type default)
		)
		(layer "In1.Cu")
	)
	(gr_line
		(start 365.550958 -10.997946)
		(end 365.550958 -9.448546)
		(stroke
			(width 0.762)
			(type default)
		)
		(layer "In1.Cu")
	)
	(gr_line
		(start 365.550958 -9.448546)
		(end 366.465358 -9.448546)
		(stroke
			(width 0.762)
			(type default)
		)
		(layer "In1.Cu")
	)
	(gr_line
		(start 365.55426 -11.175746)
		(end 366.64646 -11.175746)
		(stroke
			(width 0.2032)
			(type default)
		)
		(layer "In1.Cu")
	)
	(gr_line
		(start 365.55426 -9.473946)
		(end 365.55426 -11.175746)
		(stroke
			(width 0.2032)
			(type default)
		)
		(layer "In1.Cu")
	)
	(gr_line
		(start 365.576358 -10.997946)
		(end 366.490758 -10.997946)
		(stroke
			(width 0.762)
			(type default)
		)
		(layer "In1.Cu")
	)
	(gr_line
		(start 365.576358 -9.575546)
		(end 366.490758 -9.575546)
		(stroke
			(width 0.762)
			(type default)
		)
		(layer "In1.Cu")
	)
	(gr_line
		(start 365.65586 -11.074146)
		(end 366.44326 -11.074146)
		(stroke
			(width 0.508)
			(type default)
		)
		(layer "In1.Cu")
	)
	(gr_line
		(start 365.65586 -11.048746)
		(end 365.65586 -9.524746)
		(stroke
			(width 0.508)
			(type default)
		)
		(layer "In1.Cu")
	)
	(gr_line
		(start 365.68126 -11.074146)
		(end 365.68126 -9.550146)
		(stroke
			(width 0.508)
			(type default)
		)
		(layer "In1.Cu")
	)
	(gr_line
		(start 365.703358 -11.124946)
		(end 366.617758 -11.124946)
		(stroke
			(width 0.762)
			(type default)
		)
		(layer "In1.Cu")
	)
	(gr_line
		(start 365.703358 -9.448546)
		(end 366.617758 -9.448546)
		(stroke
			(width 0.762)
			(type default)
		)
		(layer "In1.Cu")
	)
	(gr_line
		(start 365.70666 -9.524746)
		(end 366.44326 -9.524746)
		(stroke
			(width 0.508)
			(type default)
		)
		(layer "In1.Cu")
	)
	(gr_line
		(start 365.73206 -11.302746)
		(end 366.72266 -11.302746)
		(stroke
			(width 0.1016)
			(type default)
		)
		(layer "In1.Cu")
	)
	(gr_line
		(start 365.73206 -11.074146)
		(end 365.73206 -9.550146)
		(stroke
			(width 0.508)
			(type default)
		)
		(layer "In1.Cu")
	)
	(gr_line
		(start 365.75746 -11.074146)
		(end 365.75746 -9.550146)
		(stroke
			(width 0.508)
			(type default)
		)
		(layer "In1.Cu")
	)
	(gr_line
		(start 365.78286 -11.074146)
		(end 365.78286 -9.550146)
		(stroke
			(width 0.508)
			(type default)
		)
		(layer "In1.Cu")
	)
	(gr_line
		(start 365.80826 -11.074146)
		(end 365.80826 -9.550146)
		(stroke
			(width 0.508)
			(type default)
		)
		(layer "In1.Cu")
	)
	(gr_line
		(start 365.80826 -11.048746)
		(end 365.80826 -9.524746)
		(stroke
			(width 0.508)
			(type default)
		)
		(layer "In1.Cu")
	)
	(gr_line
		(start 365.83366 -11.074146)
		(end 365.83366 -9.550146)
		(stroke
			(width 0.508)
			(type default)
		)
		(layer "In1.Cu")
	)
	(gr_line
		(start 365.85906 -11.074146)
		(end 365.85906 -9.550146)
		(stroke
			(width 0.508)
			(type default)
		)
		(layer "In1.Cu")
	)
	(gr_line
		(start 365.90986 -11.074146)
		(end 365.90986 -9.550146)
		(stroke
			(width 0.508)
			(type default)
		)
		(layer "In1.Cu")
	)
	(gr_line
		(start 365.90986 -11.048746)
		(end 365.90986 -9.524746)
		(stroke
			(width 0.508)
			(type default)
		)
		(layer "In1.Cu")
	)
	(gr_line
		(start 365.93526 -11.074146)
		(end 365.93526 -9.550146)
		(stroke
			(width 0.508)
			(type default)
		)
		(layer "In1.Cu")
	)
	(gr_line
		(start 365.96066 -11.074146)
		(end 365.96066 -9.550146)
		(stroke
			(width 0.508)
			(type default)
		)
		(layer "In1.Cu")
	)
	(gr_line
		(start 365.98606 -11.074146)
		(end 365.98606 -9.550146)
		(stroke
			(width 0.508)
			(type default)
		)
		(layer "In1.Cu")
	)
	(gr_line
		(start 366.03686 -11.074146)
		(end 366.03686 -9.550146)
		(stroke
			(width 0.508)
			(type default)
		)
		(layer "In1.Cu")
	)
	(gr_line
		(start 366.06226 -11.074146)
		(end 366.06226 -9.550146)
		(stroke
			(width 0.508)
			(type default)
		)
		(layer "In1.Cu")
	)
	(gr_line
		(start 366.06226 -11.048746)
		(end 366.06226 -9.524746)
		(stroke
			(width 0.508)
			(type default)
		)
		(layer "In1.Cu")
	)
	(gr_line
		(start 366.08766 -11.074146)
		(end 366.08766 -9.550146)
		(stroke
			(width 0.508)
			(type default)
		)
		(layer "In1.Cu")
	)
	(gr_line
		(start 366.11306 -11.074146)
		(end 366.11306 -9.550146)
		(stroke
			(width 0.508)
			(type default)
		)
		(layer "In1.Cu")
	)
	(gr_line
		(start 366.13846 -11.074146)
		(end 366.13846 -9.550146)
		(stroke
			(width 0.508)
			(type default)
		)
		(layer "In1.Cu")
	)
	(gr_line
		(start 366.13846 -11.048746)
		(end 366.13846 -9.524746)
		(stroke
			(width 0.508)
			(type default)
		)
		(layer "In1.Cu")
	)
	(gr_line
		(start 366.16386 -11.074146)
		(end 366.16386 -9.550146)
		(stroke
			(width 0.508)
			(type default)
		)
		(layer "In1.Cu")
	)
	(gr_line
		(start 366.18926 -11.074146)
		(end 366.18926 -9.550146)
		(stroke
			(width 0.508)
			(type default)
		)
		(layer "In1.Cu")
	)
	(gr_line
		(start 366.18926 -11.048746)
		(end 366.18926 -9.524746)
		(stroke
			(width 0.508)
			(type default)
		)
		(layer "In1.Cu")
	)
	(gr_line
		(start 366.21466 -11.074146)
		(end 366.21466 -9.550146)
		(stroke
			(width 0.508)
			(type default)
		)
		(layer "In1.Cu")
	)
	(gr_line
		(start 366.21466 -11.048746)
		(end 366.21466 -9.524746)
		(stroke
			(width 0.508)
			(type default)
		)
		(layer "In1.Cu")
	)
	(gr_line
		(start 366.24006 -11.048746)
		(end 366.24006 -9.524746)
		(stroke
			(width 0.508)
			(type default)
		)
		(layer "In1.Cu")
	)
	(gr_line
		(start 366.26546 -11.074146)
		(end 366.26546 -9.550146)
		(stroke
			(width 0.508)
			(type default)
		)
		(layer "In1.Cu")
	)
	(gr_line
		(start 366.287558 -11.378946)
		(end 365.296958 -11.378946)
		(stroke
			(width 0.254)
			(type default)
		)
		(layer "In1.Cu")
	)
	(gr_line
		(start 366.29086 -11.048746)
		(end 366.29086 -9.524746)
		(stroke
			(width 0.508)
			(type default)
		)
		(layer "In1.Cu")
	)
	(gr_line
		(start 366.31626 -11.048746)
		(end 366.31626 -9.524746)
		(stroke
			(width 0.508)
			(type default)
		)
		(layer "In1.Cu")
	)
	(gr_line
		(start 366.34166 -11.074146)
		(end 366.34166 -9.550146)
		(stroke
			(width 0.508)
			(type default)
		)
		(layer "In1.Cu")
	)
	(gr_line
		(start 366.36706 -11.074146)
		(end 366.36706 -9.550146)
		(stroke
			(width 0.508)
			(type default)
		)
		(layer "In1.Cu")
	)
	(gr_line
		(start 366.36706 -11.048746)
		(end 366.36706 -9.524746)
		(stroke
			(width 0.508)
			(type default)
		)
		(layer "In1.Cu")
	)
	(gr_line
		(start 366.41786 -11.074146)
		(end 366.41786 -9.550146)
		(stroke
			(width 0.508)
			(type default)
		)
		(layer "In1.Cu")
	)
	(gr_line
		(start 366.41786 -11.048746)
		(end 366.41786 -9.524746)
		(stroke
			(width 0.508)
			(type default)
		)
		(layer "In1.Cu")
	)
	(gr_line
		(start 366.46866 -11.074146)
		(end 366.46866 -9.550146)
		(stroke
			(width 0.508)
			(type default)
		)
		(layer "In1.Cu")
	)
	(gr_line
		(start 366.46866 -11.048746)
		(end 366.46866 -9.524746)
		(stroke
			(width 0.508)
			(type default)
		)
		(layer "In1.Cu")
	)
	(gr_line
		(start 366.490758 -11.099546)
		(end 366.490758 -9.550146)
		(stroke
			(width 0.762)
			(type default)
		)
		(layer "In1.Cu")
	)
	(gr_line
		(start 366.49406 -11.074146)
		(end 366.49406 -9.550146)
		(stroke
			(width 0.508)
			(type default)
		)
		(layer "In1.Cu")
	)
	(gr_line
		(start 366.51946 -11.074146)
		(end 366.51946 -9.550146)
		(stroke
			(width 0.508)
			(type default)
		)
		(layer "In1.Cu")
	)
	(gr_line
		(start 366.57026 -11.226546)
		(end 366.59566 -11.226546)
		(stroke
			(width 0.2032)
			(type default)
		)
		(layer "In1.Cu")
	)
	(gr_line
		(start 366.59566 -11.226546)
		(end 366.59566 -9.473946)
		(stroke
			(width 0.2032)
			(type default)
		)
		(layer "In1.Cu")
	)
	(gr_line
		(start 366.59566 -9.473946)
		(end 365.55426 -9.473946)
		(stroke
			(width 0.2032)
			(type default)
		)
		(layer "In1.Cu")
	)
	(gr_line
		(start 366.617758 -11.124946)
		(end 366.617758 -9.575546)
		(stroke
			(width 0.762)
			(type default)
		)
		(layer "In1.Cu")
	)
	(gr_line
		(start 366.617758 -11.099546)
		(end 366.617758 -9.600946)
		(stroke
			(width 0.762)
			(type default)
		)
		(layer "In1.Cu")
	)
	(gr_line
		(start 366.617758 -10.997946)
		(end 366.617758 -9.448546)
		(stroke
			(width 0.762)
			(type default)
		)
		(layer "In1.Cu")
	)
	(gr_line
		(start 366.64646 -11.175746)
		(end 366.64646 -9.423146)
		(stroke
			(width 0.2032)
			(type default)
		)
		(layer "In1.Cu")
	)
	(gr_line
		(start 366.64646 -9.423146)
		(end 365.50346 -9.423146)
		(stroke
			(width 0.2032)
			(type default)
		)
		(layer "In1.Cu")
	)
	(gr_line
		(start 366.67186 -11.226546)
		(end 366.67186 -9.372346)
		(stroke
			(width 0.2032)
			(type default)
		)
		(layer "In1.Cu")
	)
	(gr_line
		(start 366.67186 -9.372346)
		(end 365.47806 -9.372346)
		(stroke
			(width 0.2032)
			(type default)
		)
		(layer "In1.Cu")
	)
	(gr_line
		(start 366.72266 -11.302746)
		(end 366.72266 -9.296146)
		(stroke
			(width 0.1016)
			(type default)
		)
		(layer "In1.Cu")
	)
	(gr_line
		(start 366.72266 -9.296146)
		(end 365.42726 -9.296146)
		(stroke
			(width 0.1016)
			(type default)
		)
		(layer "In1.Cu")
	)
	(gr_line
		(start 366.820958 -11.226546)
		(end 366.57026 -11.226546)
		(stroke
			(width 0.254)
			(type default)
		)
		(layer "In1.Cu")
	)
	(gr_line
		(start 366.820958 -9.372346)
		(end 366.820958 -11.226546)
		(stroke
			(width 0.254)
			(type default)
		)
		(layer "In1.Cu")
	)
	(gr_line
		(start 366.846358 -11.353546)
		(end 365.373158 -11.353546)
		(stroke
			(width 0.254)
			(type default)
		)
		(layer "In1.Cu")
	)
	(gr_line
		(start 366.846358 -9.245346)
		(end 366.846358 -11.353546)
		(stroke
			(width 0.254)
			(type default)
		)
		(layer "In1.Cu")
	)
	(gr_line
		(start 366.871758 -11.378946)
		(end 365.322358 -11.378946)
		(stroke
			(width 0.254)
			(type default)
		)
		(layer "In1.Cu")
	)
	(gr_line
		(start 366.871758 -9.194546)
		(end 366.871758 -11.378946)
		(stroke
			(width 0.254)
			(type default)
		)
		(layer "In1.Cu")
	)
	(gr_line
		(start 370.98986 -49.800002)
		(end 355.98989 -49.800002)
		(stroke
			(width 1.016)
			(type default)
		)
		(layer "In1.Cu")
	)
	(gr_line
		(start 371.989858 -51.319938)
		(end 371.989858 -50.8)
		(stroke
			(width 1.016)
			(type default)
		)
		(layer "In1.Cu")
	)
	(gr_arc
		(start 371.989858 -51.319938)
		(mid 372.282761 -52.027034)
		(end 372.989856 -52.319936)
		(stroke
			(width 1.016)
			(type default)
		)
		(layer "In1.Cu")
	)
	(gr_arc
		(start 371.989858 -50.8)
		(mid 371.696965 -50.092895)
		(end 370.98986 -49.800002)
		(stroke
			(width 1.016)
			(type default)
		)
		(layer "In1.Cu")
	)
	(gr_line
		(start 379.990096 -52.319936)
		(end 372.989856 -52.319936)
		(stroke
			(width 1.016)
			(type default)
		)
		(layer "In1.Cu")
	)
	(gr_line
		(start 380.37262 -52.24399)
		(end 379.990096 -52.319936)
		(stroke
			(width 1.016)
			(type default)
		)
		(layer "In1.Cu")
	)
	(gr_line
		(start 380.697232 -52.027074)
		(end 380.37262 -52.24399)
		(stroke
			(width 1.016)
			(type default)
		)
		(layer "In1.Cu")
	)
	(gr_line
		(start 380.913894 -51.702716)
		(end 380.697232 -52.027074)
		(stroke
			(width 1.016)
			(type default)
		)
		(layer "In1.Cu")
	)
	(gr_line
		(start 380.98222 -51.376072)
		(end 380.913894 -51.702716)
		(stroke
			(width 1.016)
			(type default)
		)
		(layer "In1.Cu")
	)
	(gr_line
		(start 381.070866 -50.996088)
		(end 380.98222 -51.376072)
		(stroke
			(width 1.016)
			(type default)
		)
		(layer "In1.Cu")
	)
	(gr_line
		(start 381.288798 -50.677064)
		(end 381.070866 -50.996088)
		(stroke
			(width 1.016)
			(type default)
		)
		(layer "In1.Cu")
	)
	(gr_line
		(start 381.611124 -50.464466)
		(end 381.288798 -50.677064)
		(stroke
			(width 1.016)
			(type default)
		)
		(layer "In1.Cu")
	)
	(gr_line
		(start 381.990092 -50.390044)
		(end 381.611124 -50.464466)
		(stroke
			(width 1.016)
			(type default)
		)
		(layer "In1.Cu")
	)
	(gr_line
		(start 385.287266 -13.8176)
		(end 386.074666 -13.8176)
		(stroke
			(width 0.1016)
			(type default)
		)
		(layer "In1.Cu")
	)
	(gr_line
		(start 385.287266 -13.7668)
		(end 385.287266 -11.1506)
		(stroke
			(width 0.1016)
			(type default)
		)
		(layer "In1.Cu")
	)
	(gr_line
		(start 385.287266 -11.1506)
		(end 385.287266 -13.8176)
		(stroke
			(width 0.1016)
			(type default)
		)
		(layer "In1.Cu")
	)
	(gr_line
		(start 385.287266 -11.1506)
		(end 386.481066 -11.1506)
		(stroke
			(width 0.1016)
			(type default)
		)
		(layer "In1.Cu")
	)
	(gr_line
		(start 385.287266 -9.617456)
		(end 386.074666 -9.617456)
		(stroke
			(width 0.1016)
			(type default)
		)
		(layer "In1.Cu")
	)
	(gr_line
		(start 385.287266 -9.566656)
		(end 385.287266 -6.950456)
		(stroke
			(width 0.1016)
			(type default)
		)
		(layer "In1.Cu")
	)
	(gr_line
		(start 385.287266 -6.950456)
		(end 385.287266 -9.617456)
		(stroke
			(width 0.1016)
			(type default)
		)
		(layer "In1.Cu")
	)
	(gr_line
		(start 385.287266 -6.950456)
		(end 386.481066 -6.950456)
		(stroke
			(width 0.1016)
			(type default)
		)
		(layer "In1.Cu")
	)
	(gr_line
		(start 385.287266 -5.417312)
		(end 386.074666 -5.417312)
		(stroke
			(width 0.1016)
			(type default)
		)
		(layer "In1.Cu")
	)
	(gr_line
		(start 385.287266 -5.366512)
		(end 385.287266 -2.750312)
		(stroke
			(width 0.1016)
			(type default)
		)
		(layer "In1.Cu")
	)
	(gr_line
		(start 385.287266 -2.750312)
		(end 385.287266 -5.417312)
		(stroke
			(width 0.1016)
			(type default)
		)
		(layer "In1.Cu")
	)
	(gr_line
		(start 385.287266 -2.750312)
		(end 386.481066 -2.750312)
		(stroke
			(width 0.1016)
			(type default)
		)
		(layer "In1.Cu")
	)
	(gr_line
		(start 385.312666 -13.7668)
		(end 385.312666 -11.176)
		(stroke
			(width 0.1016)
			(type default)
		)
		(layer "In1.Cu")
	)
	(gr_line
		(start 385.312666 -11.176)
		(end 386.455666 -11.176)
		(stroke
			(width 0.1016)
			(type default)
		)
		(layer "In1.Cu")
	)
	(gr_line
		(start 385.312666 -9.566656)
		(end 385.312666 -6.975856)
		(stroke
			(width 0.1016)
			(type default)
		)
		(layer "In1.Cu")
	)
	(gr_line
		(start 385.312666 -6.975856)
		(end 386.455666 -6.975856)
		(stroke
			(width 0.1016)
			(type default)
		)
		(layer "In1.Cu")
	)
	(gr_line
		(start 385.312666 -5.366512)
		(end 385.312666 -2.775712)
		(stroke
			(width 0.1016)
			(type default)
		)
		(layer "In1.Cu")
	)
	(gr_line
		(start 385.312666 -2.775712)
		(end 386.455666 -2.775712)
		(stroke
			(width 0.1016)
			(type default)
		)
		(layer "In1.Cu")
	)
	(gr_line
		(start 385.338066 -13.7668)
		(end 385.338066 -11.2014)
		(stroke
			(width 0.1016)
			(type default)
		)
		(layer "In1.Cu")
	)
	(gr_line
		(start 385.338066 -11.2014)
		(end 385.592066 -11.2014)
		(stroke
			(width 0.1016)
			(type default)
		)
		(layer "In1.Cu")
	)
	(gr_line
		(start 385.338066 -9.566656)
		(end 385.338066 -7.001256)
		(stroke
			(width 0.1016)
			(type default)
		)
		(layer "In1.Cu")
	)
	(gr_line
		(start 385.338066 -7.001256)
		(end 385.592066 -7.001256)
		(stroke
			(width 0.1016)
			(type default)
		)
		(layer "In1.Cu")
	)
	(gr_line
		(start 385.338066 -5.366512)
		(end 385.338066 -2.801112)
		(stroke
			(width 0.1016)
			(type default)
		)
		(layer "In1.Cu")
	)
	(gr_line
		(start 385.338066 -2.801112)
		(end 385.592066 -2.801112)
		(stroke
			(width 0.1016)
			(type default)
		)
		(layer "In1.Cu")
	)
	(gr_line
		(start 385.363466 -13.7668)
		(end 385.363466 -11.2014)
		(stroke
			(width 0.2032)
			(type default)
		)
		(layer "In1.Cu")
	)
	(gr_line
		(start 385.363466 -11.2014)
		(end 386.379466 -11.2014)
		(stroke
			(width 0.2032)
			(type default)
		)
		(layer "In1.Cu")
	)
	(gr_line
		(start 385.363466 -9.566656)
		(end 385.363466 -7.001256)
		(stroke
			(width 0.2032)
			(type default)
		)
		(layer "In1.Cu")
	)
	(gr_line
		(start 385.363466 -7.001256)
		(end 386.379466 -7.001256)
		(stroke
			(width 0.2032)
			(type default)
		)
		(layer "In1.Cu")
	)
	(gr_line
		(start 385.363466 -5.366512)
		(end 385.363466 -2.801112)
		(stroke
			(width 0.2032)
			(type default)
		)
		(layer "In1.Cu")
	)
	(gr_line
		(start 385.363466 -2.801112)
		(end 386.379466 -2.801112)
		(stroke
			(width 0.2032)
			(type default)
		)
		(layer "In1.Cu")
	)
	(gr_line
		(start 385.414266 -13.7414)
		(end 385.414266 -11.2522)
		(stroke
			(width 0.2032)
			(type default)
		)
		(layer "In1.Cu")
	)
	(gr_line
		(start 385.414266 -13.7414)
		(end 385.414266 -11.2522)
		(stroke
			(width 0.254)
			(type default)
		)
		(layer "In1.Cu")
	)
	(gr_line
		(start 385.414266 -11.2522)
		(end 385.617466 -11.2522)
		(stroke
			(width 0.2032)
			(type default)
		)
		(layer "In1.Cu")
	)
	(gr_line
		(start 385.414266 -11.2522)
		(end 386.303266 -11.2522)
		(stroke
			(width 0.254)
			(type default)
		)
		(layer "In1.Cu")
	)
	(gr_line
		(start 385.414266 -9.541256)
		(end 385.414266 -7.052056)
		(stroke
			(width 0.2032)
			(type default)
		)
		(layer "In1.Cu")
	)
	(gr_line
		(start 385.414266 -9.541256)
		(end 385.414266 -7.052056)
		(stroke
			(width 0.254)
			(type default)
		)
		(layer "In1.Cu")
	)
	(gr_line
		(start 385.414266 -7.052056)
		(end 385.617466 -7.052056)
		(stroke
			(width 0.2032)
			(type default)
		)
		(layer "In1.Cu")
	)
	(gr_line
		(start 385.414266 -7.052056)
		(end 386.303266 -7.052056)
		(stroke
			(width 0.254)
			(type default)
		)
		(layer "In1.Cu")
	)
	(gr_line
		(start 385.414266 -5.341112)
		(end 385.414266 -2.851912)
		(stroke
			(width 0.2032)
			(type default)
		)
		(layer "In1.Cu")
	)
	(gr_line
		(start 385.414266 -5.341112)
		(end 385.414266 -2.851912)
		(stroke
			(width 0.254)
			(type default)
		)
		(layer "In1.Cu")
	)
	(gr_line
		(start 385.414266 -2.851912)
		(end 385.617466 -2.851912)
		(stroke
			(width 0.2032)
			(type default)
		)
		(layer "In1.Cu")
	)
	(gr_line
		(start 385.414266 -2.851912)
		(end 386.303266 -2.851912)
		(stroke
			(width 0.254)
			(type default)
		)
		(layer "In1.Cu")
	)
	(gr_line
		(start 385.439666 -13.716)
		(end 385.439666 -11.2776)
		(stroke
			(width 0.254)
			(type default)
		)
		(layer "In1.Cu")
	)
	(gr_line
		(start 385.439666 -11.2776)
		(end 386.277866 -11.2776)
		(stroke
			(width 0.254)
			(type default)
		)
		(layer "In1.Cu")
	)
	(gr_line
		(start 385.439666 -9.515856)
		(end 385.439666 -7.077456)
		(stroke
			(width 0.254)
			(type default)
		)
		(layer "In1.Cu")
	)
	(gr_line
		(start 385.439666 -7.077456)
		(end 386.277866 -7.077456)
		(stroke
			(width 0.254)
			(type default)
		)
		(layer "In1.Cu")
	)
	(gr_line
		(start 385.439666 -5.315712)
		(end 385.439666 -2.877312)
		(stroke
			(width 0.254)
			(type default)
		)
		(layer "In1.Cu")
	)
	(gr_line
		(start 385.439666 -2.877312)
		(end 386.277866 -2.877312)
		(stroke
			(width 0.254)
			(type default)
		)
		(layer "In1.Cu")
	)
	(gr_line
		(start 385.465066 -13.6906)
		(end 385.465066 -11.303)
		(stroke
			(width 0.254)
			(type default)
		)
		(layer "In1.Cu")
	)
	(gr_line
		(start 385.465066 -11.303)
		(end 386.252466 -11.303)
		(stroke
			(width 0.254)
			(type default)
		)
		(layer "In1.Cu")
	)
	(gr_line
		(start 385.465066 -9.490456)
		(end 385.465066 -7.102856)
		(stroke
			(width 0.254)
			(type default)
		)
		(layer "In1.Cu")
	)
	(gr_line
		(start 385.465066 -7.102856)
		(end 386.252466 -7.102856)
		(stroke
			(width 0.254)
			(type default)
		)
		(layer "In1.Cu")
	)
	(gr_line
		(start 385.465066 -5.290312)
		(end 385.465066 -2.902712)
		(stroke
			(width 0.254)
			(type default)
		)
		(layer "In1.Cu")
	)
	(gr_line
		(start 385.465066 -2.902712)
		(end 386.252466 -2.902712)
		(stroke
			(width 0.254)
			(type default)
		)
		(layer "In1.Cu")
	)
	(gr_line
		(start 385.490466 -13.6144)
		(end 386.125466 -13.6144)
		(stroke
			(width 0.508)
			(type default)
		)
		(layer "In1.Cu")
	)
	(gr_line
		(start 385.490466 -11.43)
		(end 386.125466 -11.43)
		(stroke
			(width 0.508)
			(type default)
		)
		(layer "In1.Cu")
	)
	(gr_line
		(start 385.490466 -11.3792)
		(end 386.125466 -11.3792)
		(stroke
			(width 0.508)
			(type default)
		)
		(layer "In1.Cu")
	)
	(gr_line
		(start 385.490466 -9.414256)
		(end 386.125466 -9.414256)
		(stroke
			(width 0.508)
			(type default)
		)
		(layer "In1.Cu")
	)
	(gr_line
		(start 385.490466 -7.229856)
		(end 386.125466 -7.229856)
		(stroke
			(width 0.508)
			(type default)
		)
		(layer "In1.Cu")
	)
	(gr_line
		(start 385.490466 -7.179056)
		(end 386.125466 -7.179056)
		(stroke
			(width 0.508)
			(type default)
		)
		(layer "In1.Cu")
	)
	(gr_line
		(start 385.490466 -5.214112)
		(end 386.125466 -5.214112)
		(stroke
			(width 0.508)
			(type default)
		)
		(layer "In1.Cu")
	)
	(gr_line
		(start 385.490466 -3.029712)
		(end 386.125466 -3.029712)
		(stroke
			(width 0.508)
			(type default)
		)
		(layer "In1.Cu")
	)
	(gr_line
		(start 385.490466 -2.978912)
		(end 386.125466 -2.978912)
		(stroke
			(width 0.508)
			(type default)
		)
		(layer "In1.Cu")
	)
	(gr_line
		(start 385.515866 -11.684)
		(end 386.150866 -11.684)
		(stroke
			(width 0.508)
			(type default)
		)
		(layer "In1.Cu")
	)
	(gr_line
		(start 385.515866 -7.483856)
		(end 386.150866 -7.483856)
		(stroke
			(width 0.508)
			(type default)
		)
		(layer "In1.Cu")
	)
	(gr_line
		(start 385.515866 -3.283712)
		(end 386.150866 -3.283712)
		(stroke
			(width 0.508)
			(type default)
		)
		(layer "In1.Cu")
	)
	(gr_line
		(start 385.541266 -13.6398)
		(end 385.541266 -11.3792)
		(stroke
			(width 0.254)
			(type default)
		)
		(layer "In1.Cu")
	)
	(gr_line
		(start 385.541266 -13.4874)
		(end 386.176266 -13.4874)
		(stroke
			(width 0.508)
			(type default)
		)
		(layer "In1.Cu")
	)
	(gr_line
		(start 385.541266 -11.3792)
		(end 386.176266 -11.3792)
		(stroke
			(width 0.254)
			(type default)
		)
		(layer "In1.Cu")
	)
	(gr_line
		(start 385.541266 -9.439656)
		(end 385.541266 -7.179056)
		(stroke
			(width 0.254)
			(type default)
		)
		(layer "In1.Cu")
	)
	(gr_line
		(start 385.541266 -9.287256)
		(end 386.176266 -9.287256)
		(stroke
			(width 0.508)
			(type default)
		)
		(layer "In1.Cu")
	)
	(gr_line
		(start 385.541266 -7.179056)
		(end 386.176266 -7.179056)
		(stroke
			(width 0.254)
			(type default)
		)
		(layer "In1.Cu")
	)
	(gr_line
		(start 385.541266 -5.239512)
		(end 385.541266 -2.978912)
		(stroke
			(width 0.254)
			(type default)
		)
		(layer "In1.Cu")
	)
	(gr_line
		(start 385.541266 -5.087112)
		(end 386.176266 -5.087112)
		(stroke
			(width 0.508)
			(type default)
		)
		(layer "In1.Cu")
	)
	(gr_line
		(start 385.541266 -2.978912)
		(end 386.176266 -2.978912)
		(stroke
			(width 0.254)
			(type default)
		)
		(layer "In1.Cu")
	)
	(gr_line
		(start 385.566666 -13.335)
		(end 386.201666 -13.335)
		(stroke
			(width 0.508)
			(type default)
		)
		(layer "In1.Cu")
	)
	(gr_line
		(start 385.566666 -9.134856)
		(end 386.201666 -9.134856)
		(stroke
			(width 0.508)
			(type default)
		)
		(layer "In1.Cu")
	)
	(gr_line
		(start 385.566666 -4.934712)
		(end 386.201666 -4.934712)
		(stroke
			(width 0.508)
			(type default)
		)
		(layer "In1.Cu")
	)
	(gr_line
		(start 385.592066 -13.6144)
		(end 386.227066 -13.6144)
		(stroke
			(width 0.508)
			(type default)
		)
		(layer "In1.Cu")
	)
	(gr_line
		(start 385.592066 -11.2014)
		(end 386.430266 -11.2014)
		(stroke
			(width 0.2032)
			(type default)
		)
		(layer "In1.Cu")
	)
	(gr_line
		(start 385.592066 -9.414256)
		(end 386.227066 -9.414256)
		(stroke
			(width 0.508)
			(type default)
		)
		(layer "In1.Cu")
	)
	(gr_line
		(start 385.592066 -7.001256)
		(end 386.430266 -7.001256)
		(stroke
			(width 0.2032)
			(type default)
		)
		(layer "In1.Cu")
	)
	(gr_line
		(start 385.592066 -5.214112)
		(end 386.227066 -5.214112)
		(stroke
			(width 0.508)
			(type default)
		)
		(layer "In1.Cu")
	)
	(gr_line
		(start 385.592066 -2.801112)
		(end 386.430266 -2.801112)
		(stroke
			(width 0.2032)
			(type default)
		)
		(layer "In1.Cu")
	)
	(gr_line
		(start 385.617466 -13.6144)
		(end 385.617466 -11.43)
		(stroke
			(width 0.254)
			(type default)
		)
		(layer "In1.Cu")
	)
	(gr_line
		(start 385.617466 -11.43)
		(end 386.100066 -11.43)
		(stroke
			(width 0.254)
			(type default)
		)
		(layer "In1.Cu")
	)
	(gr_line
		(start 385.617466 -11.2522)
		(end 386.354066 -11.2522)
		(stroke
			(width 0.254)
			(type default)
		)
		(layer "In1.Cu")
	)
	(gr_line
		(start 385.617466 -9.414256)
		(end 385.617466 -7.229856)
		(stroke
			(width 0.254)
			(type default)
		)
		(layer "In1.Cu")
	)
	(gr_line
		(start 385.617466 -7.229856)
		(end 386.100066 -7.229856)
		(stroke
			(width 0.254)
			(type default)
		)
		(layer "In1.Cu")
	)
	(gr_line
		(start 385.617466 -7.052056)
		(end 386.354066 -7.052056)
		(stroke
			(width 0.254)
			(type default)
		)
		(layer "In1.Cu")
	)
	(gr_line
		(start 385.617466 -5.214112)
		(end 385.617466 -3.029712)
		(stroke
			(width 0.254)
			(type default)
		)
		(layer "In1.Cu")
	)
	(gr_line
		(start 385.617466 -3.029712)
		(end 386.100066 -3.029712)
		(stroke
			(width 0.254)
			(type default)
		)
		(layer "In1.Cu")
	)
	(gr_line
		(start 385.617466 -2.851912)
		(end 386.354066 -2.851912)
		(stroke
			(width 0.254)
			(type default)
		)
		(layer "In1.Cu")
	)
	(gr_line
		(start 385.636008 -11.36523)
		(end 386.271008 -11.36523)
		(stroke
			(width 0.508)
			(type default)
		)
		(layer "In1.Cu")
	)
	(gr_line
		(start 385.636008 -7.165086)
		(end 386.271008 -7.165086)
		(stroke
			(width 0.508)
			(type default)
		)
		(layer "In1.Cu")
	)
	(gr_line
		(start 385.636008 -2.964942)
		(end 386.271008 -2.964942)
		(stroke
			(width 0.508)
			(type default)
		)
		(layer "In1.Cu")
	)
	(gr_line
		(start 385.642866 -13.6144)
		(end 386.277866 -13.6144)
		(stroke
			(width 0.508)
			(type default)
		)
		(layer "In1.Cu")
	)
	(gr_line
		(start 385.642866 -13.4874)
		(end 385.642866 -11.5062)
		(stroke
			(width 0.762)
			(type default)
		)
		(layer "In1.Cu")
	)
	(gr_line
		(start 385.642866 -11.5062)
		(end 386.277866 -11.5062)
		(stroke
			(width 0.508)
			(type default)
		)
		(layer "In1.Cu")
	)
	(gr_line
		(start 385.642866 -9.414256)
		(end 386.277866 -9.414256)
		(stroke
			(width 0.508)
			(type default)
		)
		(layer "In1.Cu")
	)
	(gr_line
		(start 385.642866 -9.287256)
		(end 385.642866 -7.306056)
		(stroke
			(width 0.762)
			(type default)
		)
		(layer "In1.Cu")
	)
	(gr_line
		(start 385.642866 -7.306056)
		(end 386.277866 -7.306056)
		(stroke
			(width 0.508)
			(type default)
		)
		(layer "In1.Cu")
	)
	(gr_line
		(start 385.642866 -5.214112)
		(end 386.277866 -5.214112)
		(stroke
			(width 0.508)
			(type default)
		)
		(layer "In1.Cu")
	)
	(gr_line
		(start 385.642866 -5.087112)
		(end 385.642866 -3.105912)
		(stroke
			(width 0.762)
			(type default)
		)
		(layer "In1.Cu")
	)
	(gr_line
		(start 385.642866 -3.105912)
		(end 386.277866 -3.105912)
		(stroke
			(width 0.508)
			(type default)
		)
		(layer "In1.Cu")
	)
	(gr_line
		(start 385.693666 -13.5382)
		(end 385.693666 -11.5062)
		(stroke
			(width 0.254)
			(type default)
		)
		(layer "In1.Cu")
	)
	(gr_line
		(start 385.693666 -11.5062)
		(end 386.023866 -11.5062)
		(stroke
			(width 0.254)
			(type default)
		)
		(layer "In1.Cu")
	)
	(gr_line
		(start 385.693666 -9.338056)
		(end 385.693666 -7.306056)
		(stroke
			(width 0.254)
			(type default)
		)
		(layer "In1.Cu")
	)
	(gr_line
		(start 385.693666 -7.306056)
		(end 386.023866 -7.306056)
		(stroke
			(width 0.254)
			(type default)
		)
		(layer "In1.Cu")
	)
	(gr_line
		(start 385.693666 -5.137912)
		(end 385.693666 -3.105912)
		(stroke
			(width 0.254)
			(type default)
		)
		(layer "In1.Cu")
	)
	(gr_line
		(start 385.693666 -3.105912)
		(end 386.023866 -3.105912)
		(stroke
			(width 0.254)
			(type default)
		)
		(layer "In1.Cu")
	)
	(gr_line
		(start 385.795266 -13.462)
		(end 385.795266 -11.6586)
		(stroke
			(width 0.254)
			(type default)
		)
		(layer "In1.Cu")
	)
	(gr_line
		(start 385.795266 -13.462)
		(end 385.795266 -11.4808)
		(stroke
			(width 0.762)
			(type default)
		)
		(layer "In1.Cu")
	)
	(gr_line
		(start 385.795266 -11.6586)
		(end 385.896866 -11.6586)
		(stroke
			(width 0.254)
			(type default)
		)
		(layer "In1.Cu")
	)
	(gr_line
		(start 385.795266 -9.261856)
		(end 385.795266 -7.458456)
		(stroke
			(width 0.254)
			(type default)
		)
		(layer "In1.Cu")
	)
	(gr_line
		(start 385.795266 -9.261856)
		(end 385.795266 -7.280656)
		(stroke
			(width 0.762)
			(type default)
		)
		(layer "In1.Cu")
	)
	(gr_line
		(start 385.795266 -7.458456)
		(end 385.896866 -7.458456)
		(stroke
			(width 0.254)
			(type default)
		)
		(layer "In1.Cu")
	)
	(gr_line
		(start 385.795266 -5.061712)
		(end 385.795266 -3.258312)
		(stroke
			(width 0.254)
			(type default)
		)
		(layer "In1.Cu")
	)
	(gr_line
		(start 385.795266 -5.061712)
		(end 385.795266 -3.080512)
		(stroke
			(width 0.762)
			(type default)
		)
		(layer "In1.Cu")
	)
	(gr_line
		(start 385.795266 -3.258312)
		(end 385.896866 -3.258312)
		(stroke
			(width 0.254)
			(type default)
		)
		(layer "In1.Cu")
	)
	(gr_line
		(start 385.896866 -13.5636)
		(end 385.846066 -13.5636)
		(stroke
			(width 0.254)
			(type default)
		)
		(layer "In1.Cu")
	)
	(gr_line
		(start 385.896866 -11.6586)
		(end 385.896866 -13.5636)
		(stroke
			(width 0.254)
			(type default)
		)
		(layer "In1.Cu")
	)
	(gr_line
		(start 385.896866 -9.363456)
		(end 385.846066 -9.363456)
		(stroke
			(width 0.254)
			(type default)
		)
		(layer "In1.Cu")
	)
	(gr_line
		(start 385.896866 -7.458456)
		(end 385.896866 -9.363456)
		(stroke
			(width 0.254)
			(type default)
		)
		(layer "In1.Cu")
	)
	(gr_line
		(start 385.896866 -5.163312)
		(end 385.846066 -5.163312)
		(stroke
			(width 0.254)
			(type default)
		)
		(layer "In1.Cu")
	)
	(gr_line
		(start 385.896866 -3.258312)
		(end 385.896866 -5.163312)
		(stroke
			(width 0.254)
			(type default)
		)
		(layer "In1.Cu")
	)
	(gr_line
		(start 385.947666 -13.4874)
		(end 385.947666 -11.5062)
		(stroke
			(width 0.762)
			(type default)
		)
		(layer "In1.Cu")
	)
	(gr_line
		(start 385.947666 -9.287256)
		(end 385.947666 -7.306056)
		(stroke
			(width 0.762)
			(type default)
		)
		(layer "In1.Cu")
	)
	(gr_line
		(start 385.947666 -5.087112)
		(end 385.947666 -3.105912)
		(stroke
			(width 0.762)
			(type default)
		)
		(layer "In1.Cu")
	)
	(gr_line
		(start 386.023866 -13.462)
		(end 385.795266 -13.462)
		(stroke
			(width 0.254)
			(type default)
		)
		(layer "In1.Cu")
	)
	(gr_line
		(start 386.023866 -11.5062)
		(end 386.023866 -13.462)
		(stroke
			(width 0.254)
			(type default)
		)
		(layer "In1.Cu")
	)
	(gr_line
		(start 386.023866 -9.261856)
		(end 385.795266 -9.261856)
		(stroke
			(width 0.254)
			(type default)
		)
		(layer "In1.Cu")
	)
	(gr_line
		(start 386.023866 -7.306056)
		(end 386.023866 -9.261856)
		(stroke
			(width 0.254)
			(type default)
		)
		(layer "In1.Cu")
	)
	(gr_line
		(start 386.023866 -5.061712)
		(end 385.795266 -5.061712)
		(stroke
			(width 0.254)
			(type default)
		)
		(layer "In1.Cu")
	)
	(gr_line
		(start 386.023866 -3.105912)
		(end 386.023866 -5.061712)
		(stroke
			(width 0.254)
			(type default)
		)
		(layer "In1.Cu")
	)
	(gr_line
		(start 386.074666 -13.8176)
		(end 386.074666 -13.7668)
		(stroke
			(width 0.1016)
			(type default)
		)
		(layer "In1.Cu")
	)
	(gr_line
		(start 386.074666 -13.8176)
		(end 386.481066 -13.8176)
		(stroke
			(width 0.1016)
			(type default)
		)
		(layer "In1.Cu")
	)
	(gr_line
		(start 386.074666 -13.7668)
		(end 385.312666 -13.7668)
		(stroke
			(width 0.1016)
			(type default)
		)
		(layer "In1.Cu")
	)
	(gr_line
		(start 386.074666 -13.4874)
		(end 386.074666 -11.5062)
		(stroke
			(width 0.762)
			(type default)
		)
		(layer "In1.Cu")
	)
	(gr_line
		(start 386.074666 -9.617456)
		(end 386.074666 -9.566656)
		(stroke
			(width 0.1016)
			(type default)
		)
		(layer "In1.Cu")
	)
	(gr_line
		(start 386.074666 -9.617456)
		(end 386.481066 -9.617456)
		(stroke
			(width 0.1016)
			(type default)
		)
		(layer "In1.Cu")
	)
	(gr_line
		(start 386.074666 -9.566656)
		(end 385.312666 -9.566656)
		(stroke
			(width 0.1016)
			(type default)
		)
		(layer "In1.Cu")
	)
	(gr_line
		(start 386.074666 -9.287256)
		(end 386.074666 -7.306056)
		(stroke
			(width 0.762)
			(type default)
		)
		(layer "In1.Cu")
	)
	(gr_line
		(start 386.074666 -5.417312)
		(end 386.074666 -5.366512)
		(stroke
			(width 0.1016)
			(type default)
		)
		(layer "In1.Cu")
	)
	(gr_line
		(start 386.074666 -5.417312)
		(end 386.481066 -5.417312)
		(stroke
			(width 0.1016)
			(type default)
		)
		(layer "In1.Cu")
	)
	(gr_line
		(start 386.074666 -5.366512)
		(end 385.312666 -5.366512)
		(stroke
			(width 0.1016)
			(type default)
		)
		(layer "In1.Cu")
	)
	(gr_line
		(start 386.074666 -5.087112)
		(end 386.074666 -3.105912)
		(stroke
			(width 0.762)
			(type default)
		)
		(layer "In1.Cu")
	)
	(gr_line
		(start 386.100066 -13.5382)
		(end 385.693666 -13.5382)
		(stroke
			(width 0.254)
			(type default)
		)
		(layer "In1.Cu")
	)
	(gr_line
		(start 386.100066 -11.43)
		(end 386.100066 -13.5382)
		(stroke
			(width 0.254)
			(type default)
		)
		(layer "In1.Cu")
	)
	(gr_line
		(start 386.100066 -9.338056)
		(end 385.693666 -9.338056)
		(stroke
			(width 0.254)
			(type default)
		)
		(layer "In1.Cu")
	)
	(gr_line
		(start 386.100066 -7.229856)
		(end 386.100066 -9.338056)
		(stroke
			(width 0.254)
			(type default)
		)
		(layer "In1.Cu")
	)
	(gr_line
		(start 386.100066 -5.137912)
		(end 385.693666 -5.137912)
		(stroke
			(width 0.254)
			(type default)
		)
		(layer "In1.Cu")
	)
	(gr_line
		(start 386.100066 -3.029712)
		(end 386.100066 -5.137912)
		(stroke
			(width 0.254)
			(type default)
		)
		(layer "In1.Cu")
	)
	(gr_line
		(start 386.150866 -13.4874)
		(end 386.150866 -11.5062)
		(stroke
			(width 0.762)
			(type default)
		)
		(layer "In1.Cu")
	)
	(gr_line
		(start 386.150866 -9.287256)
		(end 386.150866 -7.306056)
		(stroke
			(width 0.762)
			(type default)
		)
		(layer "In1.Cu")
	)
	(gr_line
		(start 386.150866 -5.087112)
		(end 386.150866 -3.105912)
		(stroke
			(width 0.762)
			(type default)
		)
		(layer "In1.Cu")
	)
	(gr_line
		(start 386.176266 -13.6144)
		(end 385.617466 -13.6144)
		(stroke
			(width 0.254)
			(type default)
		)
		(layer "In1.Cu")
	)
	(gr_line
		(start 386.176266 -11.3792)
		(end 386.176266 -13.6144)
		(stroke
			(width 0.254)
			(type default)
		)
		(layer "In1.Cu")
	)
	(gr_line
		(start 386.176266 -9.414256)
		(end 385.617466 -9.414256)
		(stroke
			(width 0.254)
			(type default)
		)
		(layer "In1.Cu")
	)
	(gr_line
		(start 386.176266 -7.179056)
		(end 386.176266 -9.414256)
		(stroke
			(width 0.254)
			(type default)
		)
		(layer "In1.Cu")
	)
	(gr_line
		(start 386.176266 -5.214112)
		(end 385.617466 -5.214112)
		(stroke
			(width 0.254)
			(type default)
		)
		(layer "In1.Cu")
	)
	(gr_line
		(start 386.176266 -2.978912)
		(end 386.176266 -5.214112)
		(stroke
			(width 0.254)
			(type default)
		)
		(layer "In1.Cu")
	)
	(gr_line
		(start 386.252466 -13.6398)
		(end 385.541266 -13.6398)
		(stroke
			(width 0.254)
			(type default)
		)
		(layer "In1.Cu")
	)
	(gr_line
		(start 386.252466 -11.303)
		(end 386.252466 -13.6398)
		(stroke
			(width 0.254)
			(type default)
		)
		(layer "In1.Cu")
	)
	(gr_line
		(start 386.252466 -9.439656)
		(end 385.541266 -9.439656)
		(stroke
			(width 0.254)
			(type default)
		)
		(layer "In1.Cu")
	)
	(gr_line
		(start 386.252466 -7.102856)
		(end 386.252466 -9.439656)
		(stroke
			(width 0.254)
			(type default)
		)
		(layer "In1.Cu")
	)
	(gr_line
		(start 386.252466 -5.239512)
		(end 385.541266 -5.239512)
		(stroke
			(width 0.254)
			(type default)
		)
		(layer "In1.Cu")
	)
	(gr_line
		(start 386.252466 -2.902712)
		(end 386.252466 -5.239512)
		(stroke
			(width 0.254)
			(type default)
		)
		(layer "In1.Cu")
	)
	(gr_line
		(start 386.277866 -13.7668)
		(end 385.287266 -13.7668)
		(stroke
			(width 0.1016)
			(type default)
		)
		(layer "In1.Cu")
	)
	(gr_line
		(start 386.277866 -13.6906)
		(end 385.465066 -13.6906)
		(stroke
			(width 0.254)
			(type default)
		)
		(layer "In1.Cu")
	)
	(gr_line
		(start 386.277866 -11.2776)
		(end 386.277866 -13.6906)
		(stroke
			(width 0.254)
			(type default)
		)
		(layer "In1.Cu")
	)
	(gr_line
		(start 386.277866 -9.566656)
		(end 385.287266 -9.566656)
		(stroke
			(width 0.1016)
			(type default)
		)
		(layer "In1.Cu")
	)
	(gr_line
		(start 386.277866 -9.490456)
		(end 385.465066 -9.490456)
		(stroke
			(width 0.254)
			(type default)
		)
		(layer "In1.Cu")
	)
	(gr_line
		(start 386.277866 -7.077456)
		(end 386.277866 -9.490456)
		(stroke
			(width 0.254)
			(type default)
		)
		(layer "In1.Cu")
	)
	(gr_line
		(start 386.277866 -5.366512)
		(end 385.287266 -5.366512)
		(stroke
			(width 0.1016)
			(type default)
		)
		(layer "In1.Cu")
	)
	(gr_line
		(start 386.277866 -5.290312)
		(end 385.465066 -5.290312)
		(stroke
			(width 0.254)
			(type default)
		)
		(layer "In1.Cu")
	)
	(gr_line
		(start 386.277866 -2.877312)
		(end 386.277866 -5.290312)
		(stroke
			(width 0.254)
			(type default)
		)
		(layer "In1.Cu")
	)
	(gr_line
		(start 386.303266 -13.716)
		(end 385.439666 -13.716)
		(stroke
			(width 0.254)
			(type default)
		)
		(layer "In1.Cu")
	)
	(gr_line
		(start 386.303266 -11.2522)
		(end 386.303266 -13.716)
		(stroke
			(width 0.254)
			(type default)
		)
		(layer "In1.Cu")
	)
	(gr_line
		(start 386.303266 -9.515856)
		(end 385.439666 -9.515856)
		(stroke
			(width 0.254)
			(type default)
		)
		(layer "In1.Cu")
	)
	(gr_line
		(start 386.303266 -7.052056)
		(end 386.303266 -9.515856)
		(stroke
			(width 0.254)
			(type default)
		)
		(layer "In1.Cu")
	)
	(gr_line
		(start 386.303266 -5.315712)
		(end 385.439666 -5.315712)
		(stroke
			(width 0.254)
			(type default)
		)
		(layer "In1.Cu")
	)
	(gr_line
		(start 386.303266 -2.851912)
		(end 386.303266 -5.315712)
		(stroke
			(width 0.254)
			(type default)
		)
		(layer "In1.Cu")
	)
	(gr_line
		(start 386.354066 -13.7414)
		(end 385.414266 -13.7414)
		(stroke
			(width 0.254)
			(type default)
		)
		(layer "In1.Cu")
	)
	(gr_line
		(start 386.354066 -11.2522)
		(end 386.354066 -13.7414)
		(stroke
			(width 0.254)
			(type default)
		)
		(layer "In1.Cu")
	)
	(gr_line
		(start 386.354066 -9.541256)
		(end 385.414266 -9.541256)
		(stroke
			(width 0.254)
			(type default)
		)
		(layer "In1.Cu")
	)
	(gr_line
		(start 386.354066 -7.052056)
		(end 386.354066 -9.541256)
		(stroke
			(width 0.254)
			(type default)
		)
		(layer "In1.Cu")
	)
	(gr_line
		(start 386.354066 -5.341112)
		(end 385.414266 -5.341112)
		(stroke
			(width 0.254)
			(type default)
		)
		(layer "In1.Cu")
	)
	(gr_line
		(start 386.354066 -2.851912)
		(end 386.354066 -5.341112)
		(stroke
			(width 0.254)
			(type default)
		)
		(layer "In1.Cu")
	)
	(gr_line
		(start 386.379466 -13.7414)
		(end 385.414266 -13.7414)
		(stroke
			(width 0.2032)
			(type default)
		)
		(layer "In1.Cu")
	)
	(gr_line
		(start 386.379466 -11.2014)
		(end 386.379466 -13.7414)
		(stroke
			(width 0.2032)
			(type default)
		)
		(layer "In1.Cu")
	)
	(gr_line
		(start 386.379466 -9.541256)
		(end 385.414266 -9.541256)
		(stroke
			(width 0.2032)
			(type default)
		)
		(layer "In1.Cu")
	)
	(gr_line
		(start 386.379466 -7.001256)
		(end 386.379466 -9.541256)
		(stroke
			(width 0.2032)
			(type default)
		)
		(layer "In1.Cu")
	)
	(gr_line
		(start 386.379466 -5.341112)
		(end 385.414266 -5.341112)
		(stroke
			(width 0.2032)
			(type default)
		)
		(layer "In1.Cu")
	)
	(gr_line
		(start 386.379466 -2.801112)
		(end 386.379466 -5.341112)
		(stroke
			(width 0.2032)
			(type default)
		)
		(layer "In1.Cu")
	)
	(gr_line
		(start 386.430266 -13.7668)
		(end 385.363466 -13.7668)
		(stroke
			(width 0.2032)
			(type default)
		)
		(layer "In1.Cu")
	)
	(gr_line
		(start 386.430266 -11.2014)
		(end 386.430266 -13.7668)
		(stroke
			(width 0.2032)
			(type default)
		)
		(layer "In1.Cu")
	)
	(gr_line
		(start 386.430266 -9.566656)
		(end 385.363466 -9.566656)
		(stroke
			(width 0.2032)
			(type default)
		)
		(layer "In1.Cu")
	)
	(gr_line
		(start 386.430266 -7.001256)
		(end 386.430266 -9.566656)
		(stroke
			(width 0.2032)
			(type default)
		)
		(layer "In1.Cu")
	)
	(gr_line
		(start 386.430266 -5.366512)
		(end 385.363466 -5.366512)
		(stroke
			(width 0.2032)
			(type default)
		)
		(layer "In1.Cu")
	)
	(gr_line
		(start 386.430266 -2.801112)
		(end 386.430266 -5.366512)
		(stroke
			(width 0.2032)
			(type default)
		)
		(layer "In1.Cu")
	)
	(gr_line
		(start 386.455666 -13.7668)
		(end 385.338066 -13.7668)
		(stroke
			(width 0.1016)
			(type default)
		)
		(layer "In1.Cu")
	)
	(gr_line
		(start 386.455666 -11.176)
		(end 386.455666 -13.7668)
		(stroke
			(width 0.1016)
			(type default)
		)
		(layer "In1.Cu")
	)
	(gr_line
		(start 386.455666 -9.566656)
		(end 385.338066 -9.566656)
		(stroke
			(width 0.1016)
			(type default)
		)
		(layer "In1.Cu")
	)
	(gr_line
		(start 386.455666 -6.975856)
		(end 386.455666 -9.566656)
		(stroke
			(width 0.1016)
			(type default)
		)
		(layer "In1.Cu")
	)
	(gr_line
		(start 386.455666 -5.366512)
		(end 385.338066 -5.366512)
		(stroke
			(width 0.1016)
			(type default)
		)
		(layer "In1.Cu")
	)
	(gr_line
		(start 386.455666 -2.775712)
		(end 386.455666 -5.366512)
		(stroke
			(width 0.1016)
			(type default)
		)
		(layer "In1.Cu")
	)
	(gr_line
		(start 386.481066 -13.8176)
		(end 386.074666 -13.8176)
		(stroke
			(width 0.1016)
			(type default)
		)
		(layer "In1.Cu")
	)
	(gr_line
		(start 386.481066 -13.8176)
		(end 386.481066 -11.1506)
		(stroke
			(width 0.1016)
			(type default)
		)
		(layer "In1.Cu")
	)
	(gr_line
		(start 386.481066 -11.1506)
		(end 385.287266 -11.1506)
		(stroke
			(width 0.1016)
			(type default)
		)
		(layer "In1.Cu")
	)
	(gr_line
		(start 386.481066 -11.1506)
		(end 386.481066 -13.8176)
		(stroke
			(width 0.1016)
			(type default)
		)
		(layer "In1.Cu")
	)
	(gr_line
		(start 386.481066 -9.617456)
		(end 386.074666 -9.617456)
		(stroke
			(width 0.1016)
			(type default)
		)
		(layer "In1.Cu")
	)
	(gr_line
		(start 386.481066 -9.617456)
		(end 386.481066 -6.950456)
		(stroke
			(width 0.1016)
			(type default)
		)
		(layer "In1.Cu")
	)
	(gr_line
		(start 386.481066 -6.950456)
		(end 385.287266 -6.950456)
		(stroke
			(width 0.1016)
			(type default)
		)
		(layer "In1.Cu")
	)
	(gr_line
		(start 386.481066 -6.950456)
		(end 386.481066 -9.617456)
		(stroke
			(width 0.1016)
			(type default)
		)
		(layer "In1.Cu")
	)
	(gr_line
		(start 386.481066 -5.417312)
		(end 386.074666 -5.417312)
		(stroke
			(width 0.1016)
			(type default)
		)
		(layer "In1.Cu")
	)
	(gr_line
		(start 386.481066 -5.417312)
		(end 386.481066 -2.750312)
		(stroke
			(width 0.1016)
			(type default)
		)
		(layer "In1.Cu")
	)
	(gr_line
		(start 386.481066 -2.750312)
		(end 385.287266 -2.750312)
		(stroke
			(width 0.1016)
			(type default)
		)
		(layer "In1.Cu")
	)
	(gr_line
		(start 386.481066 -2.750312)
		(end 386.481066 -5.417312)
		(stroke
			(width 0.1016)
			(type default)
		)
		(layer "In1.Cu")
	)
	(gr_line
		(start 387.217666 -24.6634)
		(end 387.217666 -23.3934)
		(stroke
			(width 0.7874)
			(type default)
		)
		(layer "In1.Cu")
	)
	(gr_line
		(start 387.287262 -12.563348)
		(end 388.074662 -12.563348)
		(stroke
			(width 0.1016)
			(type default)
		)
		(layer "In1.Cu")
	)
	(gr_line
		(start 387.287262 -12.512548)
		(end 387.287262 -9.896348)
		(stroke
			(width 0.1016)
			(type default)
		)
		(layer "In1.Cu")
	)
	(gr_line
		(start 387.287262 -12.463272)
		(end 388.074662 -12.463272)
		(stroke
			(width 0.1016)
			(type default)
		)
		(layer "In1.Cu")
	)
	(gr_line
		(start 387.287262 -12.412472)
		(end 387.287262 -9.796272)
		(stroke
			(width 0.1016)
			(type default)
		)
		(layer "In1.Cu")
	)
	(gr_line
		(start 387.287262 -9.896348)
		(end 387.287262 -12.563348)
		(stroke
			(width 0.1016)
			(type default)
		)
		(layer "In1.Cu")
	)
	(gr_line
		(start 387.287262 -9.896348)
		(end 388.481062 -9.896348)
		(stroke
			(width 0.1016)
			(type default)
		)
		(layer "In1.Cu")
	)
	(gr_line
		(start 387.287262 -9.796272)
		(end 387.287262 -12.463272)
		(stroke
			(width 0.1016)
			(type default)
		)
		(layer "In1.Cu")
	)
	(gr_line
		(start 387.287262 -9.796272)
		(end 388.481062 -9.796272)
		(stroke
			(width 0.1016)
			(type default)
		)
		(layer "In1.Cu")
	)
	(gr_line
		(start 387.287262 -8.363204)
		(end 388.074662 -8.363204)
		(stroke
			(width 0.1016)
			(type default)
		)
		(layer "In1.Cu")
	)
	(gr_line
		(start 387.287262 -8.312404)
		(end 387.287262 -5.696204)
		(stroke
			(width 0.1016)
			(type default)
		)
		(layer "In1.Cu")
	)
	(gr_line
		(start 387.287262 -8.263128)
		(end 388.074662 -8.263128)
		(stroke
			(width 0.1016)
			(type default)
		)
		(layer "In1.Cu")
	)
	(gr_line
		(start 387.287262 -8.212328)
		(end 387.287262 -5.596128)
		(stroke
			(width 0.1016)
			(type default)
		)
		(layer "In1.Cu")
	)
	(gr_line
		(start 387.287262 -5.696204)
		(end 387.287262 -8.363204)
		(stroke
			(width 0.1016)
			(type default)
		)
		(layer "In1.Cu")
	)
	(gr_line
		(start 387.287262 -5.696204)
		(end 388.481062 -5.696204)
		(stroke
			(width 0.1016)
			(type default)
		)
		(layer "In1.Cu")
	)
	(gr_line
		(start 387.287262 -5.596128)
		(end 387.287262 -8.263128)
		(stroke
			(width 0.1016)
			(type default)
		)
		(layer "In1.Cu")
	)
	(gr_line
		(start 387.287262 -5.596128)
		(end 388.481062 -5.596128)
		(stroke
			(width 0.1016)
			(type default)
		)
		(layer "In1.Cu")
	)
	(gr_line
		(start 387.287262 -4.16306)
		(end 388.074662 -4.16306)
		(stroke
			(width 0.1016)
			(type default)
		)
		(layer "In1.Cu")
	)
	(gr_line
		(start 387.287262 -4.11226)
		(end 387.287262 -1.49606)
		(stroke
			(width 0.1016)
			(type default)
		)
		(layer "In1.Cu")
	)
	(gr_line
		(start 387.287262 -4.062984)
		(end 388.074662 -4.062984)
		(stroke
			(width 0.1016)
			(type default)
		)
		(layer "In1.Cu")
	)
	(gr_line
		(start 387.287262 -4.012184)
		(end 387.287262 -1.395984)
		(stroke
			(width 0.1016)
			(type default)
		)
		(layer "In1.Cu")
	)
	(gr_line
		(start 387.287262 -1.49606)
		(end 387.287262 -4.16306)
		(stroke
			(width 0.1016)
			(type default)
		)
		(layer "In1.Cu")
	)
	(gr_line
		(start 387.287262 -1.49606)
		(end 388.481062 -1.49606)
		(stroke
			(width 0.1016)
			(type default)
		)
		(layer "In1.Cu")
	)
	(gr_line
		(start 387.287262 -1.395984)
		(end 387.287262 -4.062984)
		(stroke
			(width 0.1016)
			(type default)
		)
		(layer "In1.Cu")
	)
	(gr_line
		(start 387.287262 -1.395984)
		(end 388.481062 -1.395984)
		(stroke
			(width 0.1016)
			(type default)
		)
		(layer "In1.Cu")
	)
	(gr_line
		(start 387.312662 -12.512548)
		(end 387.312662 -9.921748)
		(stroke
			(width 0.1016)
			(type default)
		)
		(layer "In1.Cu")
	)
	(gr_line
		(start 387.312662 -12.412472)
		(end 387.312662 -9.821672)
		(stroke
			(width 0.1016)
			(type default)
		)
		(layer "In1.Cu")
	)
	(gr_line
		(start 387.312662 -9.921748)
		(end 388.455662 -9.921748)
		(stroke
			(width 0.1016)
			(type default)
		)
		(layer "In1.Cu")
	)
	(gr_line
		(start 387.312662 -9.821672)
		(end 388.455662 -9.821672)
		(stroke
			(width 0.1016)
			(type default)
		)
		(layer "In1.Cu")
	)
	(gr_line
		(start 387.312662 -8.312404)
		(end 387.312662 -5.721604)
		(stroke
			(width 0.1016)
			(type default)
		)
		(layer "In1.Cu")
	)
	(gr_line
		(start 387.312662 -8.212328)
		(end 387.312662 -5.621528)
		(stroke
			(width 0.1016)
			(type default)
		)
		(layer "In1.Cu")
	)
	(gr_line
		(start 387.312662 -5.721604)
		(end 388.455662 -5.721604)
		(stroke
			(width 0.1016)
			(type default)
		)
		(layer "In1.Cu")
	)
	(gr_line
		(start 387.312662 -5.621528)
		(end 388.455662 -5.621528)
		(stroke
			(width 0.1016)
			(type default)
		)
		(layer "In1.Cu")
	)
	(gr_line
		(start 387.312662 -4.11226)
		(end 387.312662 -1.52146)
		(stroke
			(width 0.1016)
			(type default)
		)
		(layer "In1.Cu")
	)
	(gr_line
		(start 387.312662 -4.012184)
		(end 387.312662 -1.421384)
		(stroke
			(width 0.1016)
			(type default)
		)
		(layer "In1.Cu")
	)
	(gr_line
		(start 387.312662 -1.52146)
		(end 388.455662 -1.52146)
		(stroke
			(width 0.1016)
			(type default)
		)
		(layer "In1.Cu")
	)
	(gr_line
		(start 387.312662 -1.421384)
		(end 388.455662 -1.421384)
		(stroke
			(width 0.1016)
			(type default)
		)
		(layer "In1.Cu")
	)
	(gr_line
		(start 387.338062 -12.512548)
		(end 387.338062 -9.947148)
		(stroke
			(width 0.1016)
			(type default)
		)
		(layer "In1.Cu")
	)
	(gr_line
		(start 387.338062 -12.412472)
		(end 387.338062 -9.847072)
		(stroke
			(width 0.1016)
			(type default)
		)
		(layer "In1.Cu")
	)
	(gr_line
		(start 387.338062 -9.947148)
		(end 387.592062 -9.947148)
		(stroke
			(width 0.1016)
			(type default)
		)
		(layer "In1.Cu")
	)
	(gr_line
		(start 387.338062 -9.847072)
		(end 387.592062 -9.847072)
		(stroke
			(width 0.1016)
			(type default)
		)
		(layer "In1.Cu")
	)
	(gr_line
		(start 387.338062 -8.312404)
		(end 387.338062 -5.747004)
		(stroke
			(width 0.1016)
			(type default)
		)
		(layer "In1.Cu")
	)
	(gr_line
		(start 387.338062 -8.212328)
		(end 387.338062 -5.646928)
		(stroke
			(width 0.1016)
			(type default)
		)
		(layer "In1.Cu")
	)
	(gr_line
		(start 387.338062 -5.747004)
		(end 387.592062 -5.747004)
		(stroke
			(width 0.1016)
			(type default)
		)
		(layer "In1.Cu")
	)
	(gr_line
		(start 387.338062 -5.646928)
		(end 387.592062 -5.646928)
		(stroke
			(width 0.1016)
			(type default)
		)
		(layer "In1.Cu")
	)
	(gr_line
		(start 387.338062 -4.11226)
		(end 387.338062 -1.54686)
		(stroke
			(width 0.1016)
			(type default)
		)
		(layer "In1.Cu")
	)
	(gr_line
		(start 387.338062 -4.012184)
		(end 387.338062 -1.446784)
		(stroke
			(width 0.1016)
			(type default)
		)
		(layer "In1.Cu")
	)
	(gr_line
		(start 387.338062 -1.54686)
		(end 387.592062 -1.54686)
		(stroke
			(width 0.1016)
			(type default)
		)
		(layer "In1.Cu")
	)
	(gr_line
		(start 387.338062 -1.446784)
		(end 387.592062 -1.446784)
		(stroke
			(width 0.1016)
			(type default)
		)
		(layer "In1.Cu")
	)
	(gr_line
		(start 387.363462 -12.512548)
		(end 387.363462 -9.947148)
		(stroke
			(width 0.2032)
			(type default)
		)
		(layer "In1.Cu")
	)
	(gr_line
		(start 387.363462 -12.412472)
		(end 387.363462 -9.847072)
		(stroke
			(width 0.2032)
			(type default)
		)
		(layer "In1.Cu")
	)
	(gr_line
		(start 387.363462 -9.947148)
		(end 388.379462 -9.947148)
		(stroke
			(width 0.2032)
			(type default)
		)
		(layer "In1.Cu")
	)
	(gr_line
		(start 387.363462 -9.847072)
		(end 388.379462 -9.847072)
		(stroke
			(width 0.2032)
			(type default)
		)
		(layer "In1.Cu")
	)
	(gr_line
		(start 387.363462 -8.312404)
		(end 387.363462 -5.747004)
		(stroke
			(width 0.2032)
			(type default)
		)
		(layer "In1.Cu")
	)
	(gr_line
		(start 387.363462 -8.212328)
		(end 387.363462 -5.646928)
		(stroke
			(width 0.2032)
			(type default)
		)
		(layer "In1.Cu")
	)
	(gr_line
		(start 387.363462 -5.747004)
		(end 388.379462 -5.747004)
		(stroke
			(width 0.2032)
			(type default)
		)
		(layer "In1.Cu")
	)
	(gr_line
		(start 387.363462 -5.646928)
		(end 388.379462 -5.646928)
		(stroke
			(width 0.2032)
			(type default)
		)
		(layer "In1.Cu")
	)
	(gr_line
		(start 387.363462 -4.11226)
		(end 387.363462 -1.54686)
		(stroke
			(width 0.2032)
			(type default)
		)
		(layer "In1.Cu")
	)
	(gr_line
		(start 387.363462 -4.012184)
		(end 387.363462 -1.446784)
		(stroke
			(width 0.2032)
			(type default)
		)
		(layer "In1.Cu")
	)
	(gr_line
		(start 387.363462 -1.54686)
		(end 388.379462 -1.54686)
		(stroke
			(width 0.2032)
			(type default)
		)
		(layer "In1.Cu")
	)
	(gr_line
		(start 387.363462 -1.446784)
		(end 388.379462 -1.446784)
		(stroke
			(width 0.2032)
			(type default)
		)
		(layer "In1.Cu")
	)
	(gr_line
		(start 387.414262 -12.487148)
		(end 387.414262 -9.997948)
		(stroke
			(width 0.2032)
			(type default)
		)
		(layer "In1.Cu")
	)
	(gr_line
		(start 387.414262 -12.487148)
		(end 387.414262 -9.997948)
		(stroke
			(width 0.254)
			(type default)
		)
		(layer "In1.Cu")
	)
	(gr_line
		(start 387.414262 -12.387072)
		(end 387.414262 -9.897872)
		(stroke
			(width 0.2032)
			(type default)
		)
		(layer "In1.Cu")
	)
	(gr_line
		(start 387.414262 -12.387072)
		(end 387.414262 -9.897872)
		(stroke
			(width 0.254)
			(type default)
		)
		(layer "In1.Cu")
	)
	(gr_line
		(start 387.414262 -9.997948)
		(end 387.617462 -9.997948)
		(stroke
			(width 0.2032)
			(type default)
		)
		(layer "In1.Cu")
	)
	(gr_line
		(start 387.414262 -9.997948)
		(end 388.303262 -9.997948)
		(stroke
			(width 0.254)
			(type default)
		)
		(layer "In1.Cu")
	)
	(gr_line
		(start 387.414262 -9.897872)
		(end 387.617462 -9.897872)
		(stroke
			(width 0.2032)
			(type default)
		)
		(layer "In1.Cu")
	)
	(gr_line
		(start 387.414262 -9.897872)
		(end 388.303262 -9.897872)
		(stroke
			(width 0.254)
			(type default)
		)
		(layer "In1.Cu")
	)
	(gr_line
		(start 387.414262 -8.287004)
		(end 387.414262 -5.797804)
		(stroke
			(width 0.2032)
			(type default)
		)
		(layer "In1.Cu")
	)
	(gr_line
		(start 387.414262 -8.287004)
		(end 387.414262 -5.797804)
		(stroke
			(width 0.254)
			(type default)
		)
		(layer "In1.Cu")
	)
	(gr_line
		(start 387.414262 -8.186928)
		(end 387.414262 -5.697728)
		(stroke
			(width 0.2032)
			(type default)
		)
		(layer "In1.Cu")
	)
	(gr_line
		(start 387.414262 -8.186928)
		(end 387.414262 -5.697728)
		(stroke
			(width 0.254)
			(type default)
		)
		(layer "In1.Cu")
	)
	(gr_line
		(start 387.414262 -5.797804)
		(end 387.617462 -5.797804)
		(stroke
			(width 0.2032)
			(type default)
		)
		(layer "In1.Cu")
	)
	(gr_line
		(start 387.414262 -5.797804)
		(end 388.303262 -5.797804)
		(stroke
			(width 0.254)
			(type default)
		)
		(layer "In1.Cu")
	)
	(gr_line
		(start 387.414262 -5.697728)
		(end 387.617462 -5.697728)
		(stroke
			(width 0.2032)
			(type default)
		)
		(layer "In1.Cu")
	)
	(gr_line
		(start 387.414262 -5.697728)
		(end 388.303262 -5.697728)
		(stroke
			(width 0.254)
			(type default)
		)
		(layer "In1.Cu")
	)
	(gr_line
		(start 387.414262 -4.08686)
		(end 387.414262 -1.59766)
		(stroke
			(width 0.2032)
			(type default)
		)
		(layer "In1.Cu")
	)
	(gr_line
		(start 387.414262 -4.08686)
		(end 387.414262 -1.59766)
		(stroke
			(width 0.254)
			(type default)
		)
		(layer "In1.Cu")
	)
	(gr_line
		(start 387.414262 -3.986784)
		(end 387.414262 -1.497584)
		(stroke
			(width 0.2032)
			(type default)
		)
		(layer "In1.Cu")
	)
	(gr_line
		(start 387.414262 -3.986784)
		(end 387.414262 -1.497584)
		(stroke
			(width 0.254)
			(type default)
		)
		(layer "In1.Cu")
	)
	(gr_line
		(start 387.414262 -1.59766)
		(end 387.617462 -1.59766)
		(stroke
			(width 0.2032)
			(type default)
		)
		(layer "In1.Cu")
	)
	(gr_line
		(start 387.414262 -1.59766)
		(end 388.303262 -1.59766)
		(stroke
			(width 0.254)
			(type default)
		)
		(layer "In1.Cu")
	)
	(gr_line
		(start 387.414262 -1.497584)
		(end 387.617462 -1.497584)
		(stroke
			(width 0.2032)
			(type default)
		)
		(layer "In1.Cu")
	)
	(gr_line
		(start 387.414262 -1.497584)
		(end 388.303262 -1.497584)
		(stroke
			(width 0.254)
			(type default)
		)
		(layer "In1.Cu")
	)
	(gr_line
		(start 387.439662 -12.461748)
		(end 387.439662 -10.023348)
		(stroke
			(width 0.254)
			(type default)
		)
		(layer "In1.Cu")
	)
	(gr_line
		(start 387.439662 -12.361672)
		(end 387.439662 -9.923272)
		(stroke
			(width 0.254)
			(type default)
		)
		(layer "In1.Cu")
	)
	(gr_line
		(start 387.439662 -10.023348)
		(end 388.277862 -10.023348)
		(stroke
			(width 0.254)
			(type default)
		)
		(layer "In1.Cu")
	)
	(gr_line
		(start 387.439662 -9.923272)
		(end 388.277862 -9.923272)
		(stroke
			(width 0.254)
			(type default)
		)
		(layer "In1.Cu")
	)
	(gr_line
		(start 387.439662 -8.261604)
		(end 387.439662 -5.823204)
		(stroke
			(width 0.254)
			(type default)
		)
		(layer "In1.Cu")
	)
	(gr_line
		(start 387.439662 -8.161528)
		(end 387.439662 -5.723128)
		(stroke
			(width 0.254)
			(type default)
		)
		(layer "In1.Cu")
	)
	(gr_line
		(start 387.439662 -5.823204)
		(end 388.277862 -5.823204)
		(stroke
			(width 0.254)
			(type default)
		)
		(layer "In1.Cu")
	)
	(gr_line
		(start 387.439662 -5.723128)
		(end 388.277862 -5.723128)
		(stroke
			(width 0.254)
			(type default)
		)
		(layer "In1.Cu")
	)
	(gr_line
		(start 387.439662 -4.06146)
		(end 387.439662 -1.62306)
		(stroke
			(width 0.254)
			(type default)
		)
		(layer "In1.Cu")
	)
	(gr_line
		(start 387.439662 -3.961384)
		(end 387.439662 -1.522984)
		(stroke
			(width 0.254)
			(type default)
		)
		(layer "In1.Cu")
	)
	(gr_line
		(start 387.439662 -1.62306)
		(end 388.277862 -1.62306)
		(stroke
			(width 0.254)
			(type default)
		)
		(layer "In1.Cu")
	)
	(gr_line
		(start 387.439662 -1.522984)
		(end 388.277862 -1.522984)
		(stroke
			(width 0.254)
			(type default)
		)
		(layer "In1.Cu")
	)
	(gr_line
		(start 387.465062 -12.436348)
		(end 387.465062 -10.048748)
		(stroke
			(width 0.254)
			(type default)
		)
		(layer "In1.Cu")
	)
	(gr_line
		(start 387.465062 -12.336272)
		(end 387.465062 -9.948672)
		(stroke
			(width 0.254)
			(type default)
		)
		(layer "In1.Cu")
	)
	(gr_line
		(start 387.465062 -10.048748)
		(end 388.252462 -10.048748)
		(stroke
			(width 0.254)
			(type default)
		)
		(layer "In1.Cu")
	)
	(gr_line
		(start 387.465062 -9.948672)
		(end 388.252462 -9.948672)
		(stroke
			(width 0.254)
			(type default)
		)
		(layer "In1.Cu")
	)
	(gr_line
		(start 387.465062 -8.236204)
		(end 387.465062 -5.848604)
		(stroke
			(width 0.254)
			(type default)
		)
		(layer "In1.Cu")
	)
	(gr_line
		(start 387.465062 -8.136128)
		(end 387.465062 -5.748528)
		(stroke
			(width 0.254)
			(type default)
		)
		(layer "In1.Cu")
	)
	(gr_line
		(start 387.465062 -5.848604)
		(end 388.252462 -5.848604)
		(stroke
			(width 0.254)
			(type default)
		)
		(layer "In1.Cu")
	)
	(gr_line
		(start 387.465062 -5.748528)
		(end 388.252462 -5.748528)
		(stroke
			(width 0.254)
			(type default)
		)
		(layer "In1.Cu")
	)
	(gr_line
		(start 387.465062 -4.03606)
		(end 387.465062 -1.64846)
		(stroke
			(width 0.254)
			(type default)
		)
		(layer "In1.Cu")
	)
	(gr_line
		(start 387.465062 -3.935984)
		(end 387.465062 -1.548384)
		(stroke
			(width 0.254)
			(type default)
		)
		(layer "In1.Cu")
	)
	(gr_line
		(start 387.465062 -1.64846)
		(end 388.252462 -1.64846)
		(stroke
			(width 0.254)
			(type default)
		)
		(layer "In1.Cu")
	)
	(gr_line
		(start 387.465062 -1.548384)
		(end 388.252462 -1.548384)
		(stroke
			(width 0.254)
			(type default)
		)
		(layer "In1.Cu")
	)
	(gr_line
		(start 387.490462 -12.360148)
		(end 388.125462 -12.360148)
		(stroke
			(width 0.508)
			(type default)
		)
		(layer "In1.Cu")
	)
	(gr_line
		(start 387.490462 -12.260072)
		(end 388.125462 -12.260072)
		(stroke
			(width 0.508)
			(type default)
		)
		(layer "In1.Cu")
	)
	(gr_line
		(start 387.490462 -10.175748)
		(end 388.125462 -10.175748)
		(stroke
			(width 0.508)
			(type default)
		)
		(layer "In1.Cu")
	)
	(gr_line
		(start 387.490462 -10.124948)
		(end 388.125462 -10.124948)
		(stroke
			(width 0.508)
			(type default)
		)
		(layer "In1.Cu")
	)
	(gr_line
		(start 387.490462 -10.075672)
		(end 388.125462 -10.075672)
		(stroke
			(width 0.508)
			(type default)
		)
		(layer "In1.Cu")
	)
	(gr_line
		(start 387.490462 -10.024872)
		(end 388.125462 -10.024872)
		(stroke
			(width 0.508)
			(type default)
		)
		(layer "In1.Cu")
	)
	(gr_line
		(start 387.490462 -8.160004)
		(end 388.125462 -8.160004)
		(stroke
			(width 0.508)
			(type default)
		)
		(layer "In1.Cu")
	)
	(gr_line
		(start 387.490462 -8.059928)
		(end 388.125462 -8.059928)
		(stroke
			(width 0.508)
			(type default)
		)
		(layer "In1.Cu")
	)
	(gr_line
		(start 387.490462 -5.975604)
		(end 388.125462 -5.975604)
		(stroke
			(width 0.508)
			(type default)
		)
		(layer "In1.Cu")
	)
	(gr_line
		(start 387.490462 -5.924804)
		(end 388.125462 -5.924804)
		(stroke
			(width 0.508)
			(type default)
		)
		(layer "In1.Cu")
	)
	(gr_line
		(start 387.490462 -5.875528)
		(end 388.125462 -5.875528)
		(stroke
			(width 0.508)
			(type default)
		)
		(layer "In1.Cu")
	)
	(gr_line
		(start 387.490462 -5.824728)
		(end 388.125462 -5.824728)
		(stroke
			(width 0.508)
			(type default)
		)
		(layer "In1.Cu")
	)
	(gr_line
		(start 387.490462 -3.95986)
		(end 388.125462 -3.95986)
		(stroke
			(width 0.508)
			(type default)
		)
		(layer "In1.Cu")
	)
	(gr_line
		(start 387.490462 -3.859784)
		(end 388.125462 -3.859784)
		(stroke
			(width 0.508)
			(type default)
		)
		(layer "In1.Cu")
	)
	(gr_line
		(start 387.490462 -1.77546)
		(end 388.125462 -1.77546)
		(stroke
			(width 0.508)
			(type default)
		)
		(layer "In1.Cu")
	)
	(gr_line
		(start 387.490462 -1.72466)
		(end 388.125462 -1.72466)
		(stroke
			(width 0.508)
			(type default)
		)
		(layer "In1.Cu")
	)
	(gr_line
		(start 387.490462 -1.675384)
		(end 388.125462 -1.675384)
		(stroke
			(width 0.508)
			(type default)
		)
		(layer "In1.Cu")
	)
	(gr_line
		(start 387.490462 -1.624584)
		(end 388.125462 -1.624584)
		(stroke
			(width 0.508)
			(type default)
		)
		(layer "In1.Cu")
	)
	(gr_line
		(start 387.515862 -10.429748)
		(end 388.150862 -10.429748)
		(stroke
			(width 0.508)
			(type default)
		)
		(layer "In1.Cu")
	)
	(gr_line
		(start 387.515862 -10.329672)
		(end 388.150862 -10.329672)
		(stroke
			(width 0.508)
			(type default)
		)
		(layer "In1.Cu")
	)
	(gr_line
		(start 387.515862 -6.229604)
		(end 388.150862 -6.229604)
		(stroke
			(width 0.508)
			(type default)
		)
		(layer "In1.Cu")
	)
	(gr_line
		(start 387.515862 -6.129528)
		(end 388.150862 -6.129528)
		(stroke
			(width 0.508)
			(type default)
		)
		(layer "In1.Cu")
	)
	(gr_line
		(start 387.515862 -2.02946)
		(end 388.150862 -2.02946)
		(stroke
			(width 0.508)
			(type default)
		)
		(layer "In1.Cu")
	)
	(gr_line
		(start 387.515862 -1.929384)
		(end 388.150862 -1.929384)
		(stroke
			(width 0.508)
			(type default)
		)
		(layer "In1.Cu")
	)
	(gr_line
		(start 387.541262 -12.385548)
		(end 387.541262 -10.124948)
		(stroke
			(width 0.254)
			(type default)
		)
		(layer "In1.Cu")
	)
	(gr_line
		(start 387.541262 -12.285472)
		(end 387.541262 -10.024872)
		(stroke
			(width 0.254)
			(type default)
		)
		(layer "In1.Cu")
	)
	(gr_line
		(start 387.541262 -12.233148)
		(end 388.176262 -12.233148)
		(stroke
			(width 0.508)
			(type default)
		)
		(layer "In1.Cu")
	)
	(gr_line
		(start 387.541262 -12.133072)
		(end 388.176262 -12.133072)
		(stroke
			(width 0.508)
			(type default)
		)
		(layer "In1.Cu")
	)
	(gr_line
		(start 387.541262 -10.124948)
		(end 388.176262 -10.124948)
		(stroke
			(width 0.254)
			(type default)
		)
		(layer "In1.Cu")
	)
	(gr_line
		(start 387.541262 -10.024872)
		(end 388.176262 -10.024872)
		(stroke
			(width 0.254)
			(type default)
		)
		(layer "In1.Cu")
	)
	(gr_line
		(start 387.541262 -8.185404)
		(end 387.541262 -5.924804)
		(stroke
			(width 0.254)
			(type default)
		)
		(layer "In1.Cu")
	)
	(gr_line
		(start 387.541262 -8.085328)
		(end 387.541262 -5.824728)
		(stroke
			(width 0.254)
			(type default)
		)
		(layer "In1.Cu")
	)
	(gr_line
		(start 387.541262 -8.033004)
		(end 388.176262 -8.033004)
		(stroke
			(width 0.508)
			(type default)
		)
		(layer "In1.Cu")
	)
	(gr_line
		(start 387.541262 -7.932928)
		(end 388.176262 -7.932928)
		(stroke
			(width 0.508)
			(type default)
		)
		(layer "In1.Cu")
	)
	(gr_line
		(start 387.541262 -5.924804)
		(end 388.176262 -5.924804)
		(stroke
			(width 0.254)
			(type default)
		)
		(layer "In1.Cu")
	)
	(gr_line
		(start 387.541262 -5.824728)
		(end 388.176262 -5.824728)
		(stroke
			(width 0.254)
			(type default)
		)
		(layer "In1.Cu")
	)
	(gr_line
		(start 387.541262 -3.98526)
		(end 387.541262 -1.72466)
		(stroke
			(width 0.254)
			(type default)
		)
		(layer "In1.Cu")
	)
	(gr_line
		(start 387.541262 -3.885184)
		(end 387.541262 -1.624584)
		(stroke
			(width 0.254)
			(type default)
		)
		(layer "In1.Cu")
	)
	(gr_line
		(start 387.541262 -3.83286)
		(end 388.176262 -3.83286)
		(stroke
			(width 0.508)
			(type default)
		)
		(layer "In1.Cu")
	)
	(gr_line
		(start 387.541262 -3.732784)
		(end 388.176262 -3.732784)
		(stroke
			(width 0.508)
			(type default)
		)
		(layer "In1.Cu")
	)
	(gr_line
		(start 387.541262 -1.72466)
		(end 388.176262 -1.72466)
		(stroke
			(width 0.254)
			(type default)
		)
		(layer "In1.Cu")
	)
	(gr_line
		(start 387.541262 -1.624584)
		(end 388.176262 -1.624584)
		(stroke
			(width 0.254)
			(type default)
		)
		(layer "In1.Cu")
	)
	(gr_line
		(start 387.566662 -12.080748)
		(end 388.201662 -12.080748)
		(stroke
			(width 0.508)
			(type default)
		)
		(layer "In1.Cu")
	)
	(gr_line
		(start 387.566662 -11.980672)
		(end 388.201662 -11.980672)
		(stroke
			(width 0.508)
			(type default)
		)
		(layer "In1.Cu")
	)
	(gr_line
		(start 387.566662 -7.880604)
		(end 388.201662 -7.880604)
		(stroke
			(width 0.508)
			(type default)
		)
		(layer "In1.Cu")
	)
	(gr_line
		(start 387.566662 -7.780528)
		(end 388.201662 -7.780528)
		(stroke
			(width 0.508)
			(type default)
		)
		(layer "In1.Cu")
	)
	(gr_line
		(start 387.566662 -3.68046)
		(end 388.201662 -3.68046)
		(stroke
			(width 0.508)
			(type default)
		)
		(layer "In1.Cu")
	)
	(gr_line
		(start 387.566662 -3.580384)
		(end 388.201662 -3.580384)
		(stroke
			(width 0.508)
			(type default)
		)
		(layer "In1.Cu")
	)
	(gr_line
		(start 387.592062 -12.360148)
		(end 388.227062 -12.360148)
		(stroke
			(width 0.508)
			(type default)
		)
		(layer "In1.Cu")
	)
	(gr_line
		(start 387.592062 -12.260072)
		(end 388.227062 -12.260072)
		(stroke
			(width 0.508)
			(type default)
		)
		(layer "In1.Cu")
	)
	(gr_line
		(start 387.592062 -9.947148)
		(end 388.430262 -9.947148)
		(stroke
			(width 0.2032)
			(type default)
		)
		(layer "In1.Cu")
	)
	(gr_line
		(start 387.592062 -9.847072)
		(end 388.430262 -9.847072)
		(stroke
			(width 0.2032)
			(type default)
		)
		(layer "In1.Cu")
	)
	(gr_line
		(start 387.592062 -8.160004)
		(end 388.227062 -8.160004)
		(stroke
			(width 0.508)
			(type default)
		)
		(layer "In1.Cu")
	)
	(gr_line
		(start 387.592062 -8.059928)
		(end 388.227062 -8.059928)
		(stroke
			(width 0.508)
			(type default)
		)
		(layer "In1.Cu")
	)
	(gr_line
		(start 387.592062 -5.747004)
		(end 388.430262 -5.747004)
		(stroke
			(width 0.2032)
			(type default)
		)
		(layer "In1.Cu")
	)
	(gr_line
		(start 387.592062 -5.646928)
		(end 388.430262 -5.646928)
		(stroke
			(width 0.2032)
			(type default)
		)
		(layer "In1.Cu")
	)
	(gr_line
		(start 387.592062 -3.95986)
		(end 388.227062 -3.95986)
		(stroke
			(width 0.508)
			(type default)
		)
		(layer "In1.Cu")
	)
	(gr_line
		(start 387.592062 -3.859784)
		(end 388.227062 -3.859784)
		(stroke
			(width 0.508)
			(type default)
		)
		(layer "In1.Cu")
	)
	(gr_line
		(start 387.592062 -1.54686)
		(end 388.430262 -1.54686)
		(stroke
			(width 0.2032)
			(type default)
		)
		(layer "In1.Cu")
	)
	(gr_line
		(start 387.592062 -1.446784)
		(end 388.430262 -1.446784)
		(stroke
			(width 0.2032)
			(type default)
		)
		(layer "In1.Cu")
	)
	(gr_line
		(start 387.617462 -12.360148)
		(end 387.617462 -10.175748)
		(stroke
			(width 0.254)
			(type default)
		)
		(layer "In1.Cu")
	)
	(gr_line
		(start 387.617462 -12.260072)
		(end 387.617462 -10.075672)
		(stroke
			(width 0.254)
			(type default)
		)
		(layer "In1.Cu")
	)
	(gr_line
		(start 387.617462 -10.175748)
		(end 388.100062 -10.175748)
		(stroke
			(width 0.254)
			(type default)
		)
		(layer "In1.Cu")
	)
	(gr_line
		(start 387.617462 -10.075672)
		(end 388.100062 -10.075672)
		(stroke
			(width 0.254)
			(type default)
		)
		(layer "In1.Cu")
	)
	(gr_line
		(start 387.617462 -9.997948)
		(end 388.354062 -9.997948)
		(stroke
			(width 0.254)
			(type default)
		)
		(layer "In1.Cu")
	)
	(gr_line
		(start 387.617462 -9.897872)
		(end 388.354062 -9.897872)
		(stroke
			(width 0.254)
			(type default)
		)
		(layer "In1.Cu")
	)
	(gr_line
		(start 387.617462 -8.160004)
		(end 387.617462 -5.975604)
		(stroke
			(width 0.254)
			(type default)
		)
		(layer "In1.Cu")
	)
	(gr_line
		(start 387.617462 -8.059928)
		(end 387.617462 -5.875528)
		(stroke
			(width 0.254)
			(type default)
		)
		(layer "In1.Cu")
	)
	(gr_line
		(start 387.617462 -5.975604)
		(end 388.100062 -5.975604)
		(stroke
			(width 0.254)
			(type default)
		)
		(layer "In1.Cu")
	)
	(gr_line
		(start 387.617462 -5.875528)
		(end 388.100062 -5.875528)
		(stroke
			(width 0.254)
			(type default)
		)
		(layer "In1.Cu")
	)
	(gr_line
		(start 387.617462 -5.797804)
		(end 388.354062 -5.797804)
		(stroke
			(width 0.254)
			(type default)
		)
		(layer "In1.Cu")
	)
	(gr_line
		(start 387.617462 -5.697728)
		(end 388.354062 -5.697728)
		(stroke
			(width 0.254)
			(type default)
		)
		(layer "In1.Cu")
	)
	(gr_line
		(start 387.617462 -3.95986)
		(end 387.617462 -1.77546)
		(stroke
			(width 0.254)
			(type default)
		)
		(layer "In1.Cu")
	)
	(gr_line
		(start 387.617462 -3.859784)
		(end 387.617462 -1.675384)
		(stroke
			(width 0.254)
			(type default)
		)
		(layer "In1.Cu")
	)
	(gr_line
		(start 387.617462 -1.77546)
		(end 388.100062 -1.77546)
		(stroke
			(width 0.254)
			(type default)
		)
		(layer "In1.Cu")
	)
	(gr_line
		(start 387.617462 -1.675384)
		(end 388.100062 -1.675384)
		(stroke
			(width 0.254)
			(type default)
		)
		(layer "In1.Cu")
	)
	(gr_line
		(start 387.617462 -1.59766)
		(end 388.354062 -1.59766)
		(stroke
			(width 0.254)
			(type default)
		)
		(layer "In1.Cu")
	)
	(gr_line
		(start 387.617462 -1.497584)
		(end 388.354062 -1.497584)
		(stroke
			(width 0.254)
			(type default)
		)
		(layer "In1.Cu")
	)
	(gr_line
		(start 387.636004 -10.110978)
		(end 388.271004 -10.110978)
		(stroke
			(width 0.508)
			(type default)
		)
		(layer "In1.Cu")
	)
	(gr_line
		(start 387.636004 -10.010902)
		(end 388.271004 -10.010902)
		(stroke
			(width 0.508)
			(type default)
		)
		(layer "In1.Cu")
	)
	(gr_line
		(start 387.636004 -5.910834)
		(end 388.271004 -5.910834)
		(stroke
			(width 0.508)
			(type default)
		)
		(layer "In1.Cu")
	)
	(gr_line
		(start 387.636004 -5.810758)
		(end 388.271004 -5.810758)
		(stroke
			(width 0.508)
			(type default)
		)
		(layer "In1.Cu")
	)
	(gr_line
		(start 387.636004 -1.71069)
		(end 388.271004 -1.71069)
		(stroke
			(width 0.508)
			(type default)
		)
		(layer "In1.Cu")
	)
	(gr_line
		(start 387.636004 -1.610614)
		(end 388.271004 -1.610614)
		(stroke
			(width 0.508)
			(type default)
		)
		(layer "In1.Cu")
	)
	(gr_line
		(start 387.642862 -12.360148)
		(end 388.277862 -12.360148)
		(stroke
			(width 0.508)
			(type default)
		)
		(layer "In1.Cu")
	)
	(gr_line
		(start 387.642862 -12.260072)
		(end 388.277862 -12.260072)
		(stroke
			(width 0.508)
			(type default)
		)
		(layer "In1.Cu")
	)
	(gr_line
		(start 387.642862 -12.233148)
		(end 387.642862 -10.251948)
		(stroke
			(width 0.762)
			(type default)
		)
		(layer "In1.Cu")
	)
	(gr_line
		(start 387.642862 -12.133072)
		(end 387.642862 -10.151872)
		(stroke
			(width 0.762)
			(type default)
		)
		(layer "In1.Cu")
	)
	(gr_line
		(start 387.642862 -10.251948)
		(end 388.277862 -10.251948)
		(stroke
			(width 0.508)
			(type default)
		)
		(layer "In1.Cu")
	)
	(gr_line
		(start 387.642862 -10.151872)
		(end 388.277862 -10.151872)
		(stroke
			(width 0.508)
			(type default)
		)
		(layer "In1.Cu")
	)
	(gr_line
		(start 387.642862 -8.160004)
		(end 388.277862 -8.160004)
		(stroke
			(width 0.508)
			(type default)
		)
		(layer "In1.Cu")
	)
	(gr_line
		(start 387.642862 -8.059928)
		(end 388.277862 -8.059928)
		(stroke
			(width 0.508)
			(type default)
		)
		(layer "In1.Cu")
	)
	(gr_line
		(start 387.642862 -8.033004)
		(end 387.642862 -6.051804)
		(stroke
			(width 0.762)
			(type default)
		)
		(layer "In1.Cu")
	)
	(gr_line
		(start 387.642862 -7.932928)
		(end 387.642862 -5.951728)
		(stroke
			(width 0.762)
			(type default)
		)
		(layer "In1.Cu")
	)
	(gr_line
		(start 387.642862 -6.051804)
		(end 388.277862 -6.051804)
		(stroke
			(width 0.508)
			(type default)
		)
		(layer "In1.Cu")
	)
	(gr_line
		(start 387.642862 -5.951728)
		(end 388.277862 -5.951728)
		(stroke
			(width 0.508)
			(type default)
		)
		(layer "In1.Cu")
	)
	(gr_line
		(start 387.642862 -3.95986)
		(end 388.277862 -3.95986)
		(stroke
			(width 0.508)
			(type default)
		)
		(layer "In1.Cu")
	)
	(gr_line
		(start 387.642862 -3.859784)
		(end 388.277862 -3.859784)
		(stroke
			(width 0.508)
			(type default)
		)
		(layer "In1.Cu")
	)
	(gr_line
		(start 387.642862 -3.83286)
		(end 387.642862 -1.85166)
		(stroke
			(width 0.762)
			(type default)
		)
		(layer "In1.Cu")
	)
	(gr_line
		(start 387.642862 -3.732784)
		(end 387.642862 -1.751584)
		(stroke
			(width 0.762)
			(type default)
		)
		(layer "In1.Cu")
	)
	(gr_line
		(start 387.642862 -1.85166)
		(end 388.277862 -1.85166)
		(stroke
			(width 0.508)
			(type default)
		)
		(layer "In1.Cu")
	)
	(gr_line
		(start 387.642862 -1.751584)
		(end 388.277862 -1.751584)
		(stroke
			(width 0.508)
			(type default)
		)
		(layer "In1.Cu")
	)
	(gr_line
		(start 387.693662 -12.283948)
		(end 387.693662 -10.251948)
		(stroke
			(width 0.254)
			(type default)
		)
		(layer "In1.Cu")
	)
	(gr_line
		(start 387.693662 -12.183872)
		(end 387.693662 -10.151872)
		(stroke
			(width 0.254)
			(type default)
		)
		(layer "In1.Cu")
	)
	(gr_line
		(start 387.693662 -10.251948)
		(end 388.023862 -10.251948)
		(stroke
			(width 0.254)
			(type default)
		)
		(layer "In1.Cu")
	)
	(gr_line
		(start 387.693662 -10.151872)
		(end 388.023862 -10.151872)
		(stroke
			(width 0.254)
			(type default)
		)
		(layer "In1.Cu")
	)
	(gr_line
		(start 387.693662 -8.083804)
		(end 387.693662 -6.051804)
		(stroke
			(width 0.254)
			(type default)
		)
		(layer "In1.Cu")
	)
	(gr_line
		(start 387.693662 -7.983728)
		(end 387.693662 -5.951728)
		(stroke
			(width 0.254)
			(type default)
		)
		(layer "In1.Cu")
	)
	(gr_line
		(start 387.693662 -6.051804)
		(end 388.023862 -6.051804)
		(stroke
			(width 0.254)
			(type default)
		)
		(layer "In1.Cu")
	)
	(gr_line
		(start 387.693662 -5.951728)
		(end 388.023862 -5.951728)
		(stroke
			(width 0.254)
			(type default)
		)
		(layer "In1.Cu")
	)
	(gr_line
		(start 387.693662 -3.88366)
		(end 387.693662 -1.85166)
		(stroke
			(width 0.254)
			(type default)
		)
		(layer "In1.Cu")
	)
	(gr_line
		(start 387.693662 -3.783584)
		(end 387.693662 -1.751584)
		(stroke
			(width 0.254)
			(type default)
		)
		(layer "In1.Cu")
	)
	(gr_line
		(start 387.693662 -1.85166)
		(end 388.023862 -1.85166)
		(stroke
			(width 0.254)
			(type default)
		)
		(layer "In1.Cu")
	)
	(gr_line
		(start 387.693662 -1.751584)
		(end 388.023862 -1.751584)
		(stroke
			(width 0.254)
			(type default)
		)
		(layer "In1.Cu")
	)
	(gr_line
		(start 387.795262 -12.207748)
		(end 387.795262 -10.404348)
		(stroke
			(width 0.254)
			(type default)
		)
		(layer "In1.Cu")
	)
	(gr_line
		(start 387.795262 -12.207748)
		(end 387.795262 -10.226548)
		(stroke
			(width 0.762)
			(type default)
		)
		(layer "In1.Cu")
	)
	(gr_line
		(start 387.795262 -12.107672)
		(end 387.795262 -10.304272)
		(stroke
			(width 0.254)
			(type default)
		)
		(layer "In1.Cu")
	)
	(gr_line
		(start 387.795262 -12.107672)
		(end 387.795262 -10.126472)
		(stroke
			(width 0.762)
			(type default)
		)
		(layer "In1.Cu")
	)
	(gr_line
		(start 387.795262 -10.404348)
		(end 387.896862 -10.404348)
		(stroke
			(width 0.254)
			(type default)
		)
		(layer "In1.Cu")
	)
	(gr_line
		(start 387.795262 -10.304272)
		(end 387.896862 -10.304272)
		(stroke
			(width 0.254)
			(type default)
		)
		(layer "In1.Cu")
	)
	(gr_line
		(start 387.795262 -8.007604)
		(end 387.795262 -6.204204)
		(stroke
			(width 0.254)
			(type default)
		)
		(layer "In1.Cu")
	)
	(gr_line
		(start 387.795262 -8.007604)
		(end 387.795262 -6.026404)
		(stroke
			(width 0.762)
			(type default)
		)
		(layer "In1.Cu")
	)
	(gr_line
		(start 387.795262 -7.907528)
		(end 387.795262 -6.104128)
		(stroke
			(width 0.254)
			(type default)
		)
		(layer "In1.Cu")
	)
	(gr_line
		(start 387.795262 -7.907528)
		(end 387.795262 -5.926328)
		(stroke
			(width 0.762)
			(type default)
		)
		(layer "In1.Cu")
	)
	(gr_line
		(start 387.795262 -6.204204)
		(end 387.896862 -6.204204)
		(stroke
			(width 0.254)
			(type default)
		)
		(layer "In1.Cu")
	)
	(gr_line
		(start 387.795262 -6.104128)
		(end 387.896862 -6.104128)
		(stroke
			(width 0.254)
			(type default)
		)
		(layer "In1.Cu")
	)
	(gr_line
		(start 387.795262 -3.80746)
		(end 387.795262 -2.00406)
		(stroke
			(width 0.254)
			(type default)
		)
		(layer "In1.Cu")
	)
	(gr_line
		(start 387.795262 -3.80746)
		(end 387.795262 -1.82626)
		(stroke
			(width 0.762)
			(type default)
		)
		(layer "In1.Cu")
	)
	(gr_line
		(start 387.795262 -3.707384)
		(end 387.795262 -1.903984)
		(stroke
			(width 0.254)
			(type default)
		)
		(layer "In1.Cu")
	)
	(gr_line
		(start 387.795262 -3.707384)
		(end 387.795262 -1.726184)
		(stroke
			(width 0.762)
			(type default)
		)
		(layer "In1.Cu")
	)
	(gr_line
		(start 387.795262 -2.00406)
		(end 387.896862 -2.00406)
		(stroke
			(width 0.254)
			(type default)
		)
		(layer "In1.Cu")
	)
	(gr_line
		(start 387.795262 -1.903984)
		(end 387.896862 -1.903984)
		(stroke
			(width 0.254)
			(type default)
		)
		(layer "In1.Cu")
	)
	(gr_line
		(start 387.896862 -12.309348)
		(end 387.846062 -12.309348)
		(stroke
			(width 0.254)
			(type default)
		)
		(layer "In1.Cu")
	)
	(gr_line
		(start 387.896862 -12.209272)
		(end 387.846062 -12.209272)
		(stroke
			(width 0.254)
			(type default)
		)
		(layer "In1.Cu")
	)
	(gr_line
		(start 387.896862 -10.404348)
		(end 387.896862 -12.309348)
		(stroke
			(width 0.254)
			(type default)
		)
		(layer "In1.Cu")
	)
	(gr_line
		(start 387.896862 -10.304272)
		(end 387.896862 -12.209272)
		(stroke
			(width 0.254)
			(type default)
		)
		(layer "In1.Cu")
	)
	(gr_line
		(start 387.896862 -8.109204)
		(end 387.846062 -8.109204)
		(stroke
			(width 0.254)
			(type default)
		)
		(layer "In1.Cu")
	)
	(gr_line
		(start 387.896862 -8.009128)
		(end 387.846062 -8.009128)
		(stroke
			(width 0.254)
			(type default)
		)
		(layer "In1.Cu")
	)
	(gr_line
		(start 387.896862 -6.204204)
		(end 387.896862 -8.109204)
		(stroke
			(width 0.254)
			(type default)
		)
		(layer "In1.Cu")
	)
	(gr_line
		(start 387.896862 -6.104128)
		(end 387.896862 -8.009128)
		(stroke
			(width 0.254)
			(type default)
		)
		(layer "In1.Cu")
	)
	(gr_line
		(start 387.896862 -3.90906)
		(end 387.846062 -3.90906)
		(stroke
			(width 0.254)
			(type default)
		)
		(layer "In1.Cu")
	)
	(gr_line
		(start 387.896862 -3.808984)
		(end 387.846062 -3.808984)
		(stroke
			(width 0.254)
			(type default)
		)
		(layer "In1.Cu")
	)
	(gr_line
		(start 387.896862 -2.00406)
		(end 387.896862 -3.90906)
		(stroke
			(width 0.254)
			(type default)
		)
		(layer "In1.Cu")
	)
	(gr_line
		(start 387.896862 -1.903984)
		(end 387.896862 -3.808984)
		(stroke
			(width 0.254)
			(type default)
		)
		(layer "In1.Cu")
	)
	(gr_line
		(start 387.947662 -12.233148)
		(end 387.947662 -10.251948)
		(stroke
			(width 0.762)
			(type default)
		)
		(layer "In1.Cu")
	)
	(gr_line
		(start 387.947662 -12.133072)
		(end 387.947662 -10.151872)
		(stroke
			(width 0.762)
			(type default)
		)
		(layer "In1.Cu")
	)
	(gr_line
		(start 387.947662 -8.033004)
		(end 387.947662 -6.051804)
		(stroke
			(width 0.762)
			(type default)
		)
		(layer "In1.Cu")
	)
	(gr_line
		(start 387.947662 -7.932928)
		(end 387.947662 -5.951728)
		(stroke
			(width 0.762)
			(type default)
		)
		(layer "In1.Cu")
	)
	(gr_line
		(start 387.947662 -3.83286)
		(end 387.947662 -1.85166)
		(stroke
			(width 0.762)
			(type default)
		)
		(layer "In1.Cu")
	)
	(gr_line
		(start 387.947662 -3.732784)
		(end 387.947662 -1.751584)
		(stroke
			(width 0.762)
			(type default)
		)
		(layer "In1.Cu")
	)
	(gr_line
		(start 388.023862 -12.207748)
		(end 387.795262 -12.207748)
		(stroke
			(width 0.254)
			(type default)
		)
		(layer "In1.Cu")
	)
	(gr_line
		(start 388.023862 -12.107672)
		(end 387.795262 -12.107672)
		(stroke
			(width 0.254)
			(type default)
		)
		(layer "In1.Cu")
	)
	(gr_line
		(start 388.023862 -10.251948)
		(end 388.023862 -12.207748)
		(stroke
			(width 0.254)
			(type default)
		)
		(layer "In1.Cu")
	)
	(gr_line
		(start 388.023862 -10.151872)
		(end 388.023862 -12.107672)
		(stroke
			(width 0.254)
			(type default)
		)
		(layer "In1.Cu")
	)
	(gr_line
		(start 388.023862 -8.007604)
		(end 387.795262 -8.007604)
		(stroke
			(width 0.254)
			(type default)
		)
		(layer "In1.Cu")
	)
	(gr_line
		(start 388.023862 -7.907528)
		(end 387.795262 -7.907528)
		(stroke
			(width 0.254)
			(type default)
		)
		(layer "In1.Cu")
	)
	(gr_line
		(start 388.023862 -6.051804)
		(end 388.023862 -8.007604)
		(stroke
			(width 0.254)
			(type default)
		)
		(layer "In1.Cu")
	)
	(gr_line
		(start 388.023862 -5.951728)
		(end 388.023862 -7.907528)
		(stroke
			(width 0.254)
			(type default)
		)
		(layer "In1.Cu")
	)
	(gr_line
		(start 388.023862 -3.80746)
		(end 387.795262 -3.80746)
		(stroke
			(width 0.254)
			(type default)
		)
		(layer "In1.Cu")
	)
	(gr_line
		(start 388.023862 -3.707384)
		(end 387.795262 -3.707384)
		(stroke
			(width 0.254)
			(type default)
		)
		(layer "In1.Cu")
	)
	(gr_line
		(start 388.023862 -1.85166)
		(end 388.023862 -3.80746)
		(stroke
			(width 0.254)
			(type default)
		)
		(layer "In1.Cu")
	)
	(gr_line
		(start 388.023862 -1.751584)
		(end 388.023862 -3.707384)
		(stroke
			(width 0.254)
			(type default)
		)
		(layer "In1.Cu")
	)
	(gr_line
		(start 388.074662 -12.563348)
		(end 388.074662 -12.512548)
		(stroke
			(width 0.1016)
			(type default)
		)
		(layer "In1.Cu")
	)
	(gr_line
		(start 388.074662 -12.563348)
		(end 388.481062 -12.563348)
		(stroke
			(width 0.1016)
			(type default)
		)
		(layer "In1.Cu")
	)
	(gr_line
		(start 388.074662 -12.512548)
		(end 387.312662 -12.512548)
		(stroke
			(width 0.1016)
			(type default)
		)
		(layer "In1.Cu")
	)
	(gr_line
		(start 388.074662 -12.463272)
		(end 388.074662 -12.412472)
		(stroke
			(width 0.1016)
			(type default)
		)
		(layer "In1.Cu")
	)
	(gr_line
		(start 388.074662 -12.463272)
		(end 388.481062 -12.463272)
		(stroke
			(width 0.1016)
			(type default)
		)
		(layer "In1.Cu")
	)
	(gr_line
		(start 388.074662 -12.412472)
		(end 387.312662 -12.412472)
		(stroke
			(width 0.1016)
			(type default)
		)
		(layer "In1.Cu")
	)
	(gr_line
		(start 388.074662 -12.233148)
		(end 388.074662 -10.251948)
		(stroke
			(width 0.762)
			(type default)
		)
		(layer "In1.Cu")
	)
	(gr_line
		(start 388.074662 -12.133072)
		(end 388.074662 -10.151872)
		(stroke
			(width 0.762)
			(type default)
		)
		(layer "In1.Cu")
	)
	(gr_line
		(start 388.074662 -8.363204)
		(end 388.074662 -8.312404)
		(stroke
			(width 0.1016)
			(type default)
		)
		(layer "In1.Cu")
	)
	(gr_line
		(start 388.074662 -8.363204)
		(end 388.481062 -8.363204)
		(stroke
			(width 0.1016)
			(type default)
		)
		(layer "In1.Cu")
	)
	(gr_line
		(start 388.074662 -8.312404)
		(end 387.312662 -8.312404)
		(stroke
			(width 0.1016)
			(type default)
		)
		(layer "In1.Cu")
	)
	(gr_line
		(start 388.074662 -8.263128)
		(end 388.074662 -8.212328)
		(stroke
			(width 0.1016)
			(type default)
		)
		(layer "In1.Cu")
	)
	(gr_line
		(start 388.074662 -8.263128)
		(end 388.481062 -8.263128)
		(stroke
			(width 0.1016)
			(type default)
		)
		(layer "In1.Cu")
	)
	(gr_line
		(start 388.074662 -8.212328)
		(end 387.312662 -8.212328)
		(stroke
			(width 0.1016)
			(type default)
		)
		(layer "In1.Cu")
	)
	(gr_line
		(start 388.074662 -8.033004)
		(end 388.074662 -6.051804)
		(stroke
			(width 0.762)
			(type default)
		)
		(layer "In1.Cu")
	)
	(gr_line
		(start 388.074662 -7.932928)
		(end 388.074662 -5.951728)
		(stroke
			(width 0.762)
			(type default)
		)
		(layer "In1.Cu")
	)
	(gr_line
		(start 388.074662 -4.16306)
		(end 388.074662 -4.11226)
		(stroke
			(width 0.1016)
			(type default)
		)
		(layer "In1.Cu")
	)
	(gr_line
		(start 388.074662 -4.16306)
		(end 388.481062 -4.16306)
		(stroke
			(width 0.1016)
			(type default)
		)
		(layer "In1.Cu")
	)
	(gr_line
		(start 388.074662 -4.11226)
		(end 387.312662 -4.11226)
		(stroke
			(width 0.1016)
			(type default)
		)
		(layer "In1.Cu")
	)
	(gr_line
		(start 388.074662 -4.062984)
		(end 388.074662 -4.012184)
		(stroke
			(width 0.1016)
			(type default)
		)
		(layer "In1.Cu")
	)
	(gr_line
		(start 388.074662 -4.062984)
		(end 388.481062 -4.062984)
		(stroke
			(width 0.1016)
			(type default)
		)
		(layer "In1.Cu")
	)
	(gr_line
		(start 388.074662 -4.012184)
		(end 387.312662 -4.012184)
		(stroke
			(width 0.1016)
			(type default)
		)
		(layer "In1.Cu")
	)
	(gr_line
		(start 388.074662 -3.83286)
		(end 388.074662 -1.85166)
		(stroke
			(width 0.762)
			(type default)
		)
		(layer "In1.Cu")
	)
	(gr_line
		(start 388.074662 -3.732784)
		(end 388.074662 -1.751584)
		(stroke
			(width 0.762)
			(type default)
		)
		(layer "In1.Cu")
	)
	(gr_line
		(start 388.100062 -12.283948)
		(end 387.693662 -12.283948)
		(stroke
			(width 0.254)
			(type default)
		)
		(layer "In1.Cu")
	)
	(gr_line
		(start 388.100062 -12.183872)
		(end 387.693662 -12.183872)
		(stroke
			(width 0.254)
			(type default)
		)
		(layer "In1.Cu")
	)
	(gr_line
		(start 388.100062 -10.175748)
		(end 388.100062 -12.283948)
		(stroke
			(width 0.254)
			(type default)
		)
		(layer "In1.Cu")
	)
	(gr_line
		(start 388.100062 -10.075672)
		(end 388.100062 -12.183872)
		(stroke
			(width 0.254)
			(type default)
		)
		(layer "In1.Cu")
	)
	(gr_line
		(start 388.100062 -8.083804)
		(end 387.693662 -8.083804)
		(stroke
			(width 0.254)
			(type default)
		)
		(layer "In1.Cu")
	)
	(gr_line
		(start 388.100062 -7.983728)
		(end 387.693662 -7.983728)
		(stroke
			(width 0.254)
			(type default)
		)
		(layer "In1.Cu")
	)
	(gr_line
		(start 388.100062 -5.975604)
		(end 388.100062 -8.083804)
		(stroke
			(width 0.254)
			(type default)
		)
		(layer "In1.Cu")
	)
	(gr_line
		(start 388.100062 -5.875528)
		(end 388.100062 -7.983728)
		(stroke
			(width 0.254)
			(type default)
		)
		(layer "In1.Cu")
	)
	(gr_line
		(start 388.100062 -3.88366)
		(end 387.693662 -3.88366)
		(stroke
			(width 0.254)
			(type default)
		)
		(layer "In1.Cu")
	)
	(gr_line
		(start 388.100062 -3.783584)
		(end 387.693662 -3.783584)
		(stroke
			(width 0.254)
			(type default)
		)
		(layer "In1.Cu")
	)
	(gr_line
		(start 388.100062 -1.77546)
		(end 388.100062 -3.88366)
		(stroke
			(width 0.254)
			(type default)
		)
		(layer "In1.Cu")
	)
	(gr_line
		(start 388.100062 -1.675384)
		(end 388.100062 -3.783584)
		(stroke
			(width 0.254)
			(type default)
		)
		(layer "In1.Cu")
	)
	(gr_line
		(start 388.150862 -12.233148)
		(end 388.150862 -10.251948)
		(stroke
			(width 0.762)
			(type default)
		)
		(layer "In1.Cu")
	)
	(gr_line
		(start 388.150862 -12.133072)
		(end 388.150862 -10.151872)
		(stroke
			(width 0.762)
			(type default)
		)
		(layer "In1.Cu")
	)
	(gr_line
		(start 388.150862 -8.033004)
		(end 388.150862 -6.051804)
		(stroke
			(width 0.762)
			(type default)
		)
		(layer "In1.Cu")
	)
	(gr_line
		(start 388.150862 -7.932928)
		(end 388.150862 -5.951728)
		(stroke
			(width 0.762)
			(type default)
		)
		(layer "In1.Cu")
	)
	(gr_line
		(start 388.150862 -3.83286)
		(end 388.150862 -1.85166)
		(stroke
			(width 0.762)
			(type default)
		)
		(layer "In1.Cu")
	)
	(gr_line
		(start 388.150862 -3.732784)
		(end 388.150862 -1.751584)
		(stroke
			(width 0.762)
			(type default)
		)
		(layer "In1.Cu")
	)
	(gr_line
		(start 388.176262 -12.360148)
		(end 387.617462 -12.360148)
		(stroke
			(width 0.254)
			(type default)
		)
		(layer "In1.Cu")
	)
	(gr_line
		(start 388.176262 -12.260072)
		(end 387.617462 -12.260072)
		(stroke
			(width 0.254)
			(type default)
		)
		(layer "In1.Cu")
	)
	(gr_line
		(start 388.176262 -10.124948)
		(end 388.176262 -12.360148)
		(stroke
			(width 0.254)
			(type default)
		)
		(layer "In1.Cu")
	)
	(gr_line
		(start 388.176262 -10.024872)
		(end 388.176262 -12.260072)
		(stroke
			(width 0.254)
			(type default)
		)
		(layer "In1.Cu")
	)
	(gr_line
		(start 388.176262 -8.160004)
		(end 387.617462 -8.160004)
		(stroke
			(width 0.254)
			(type default)
		)
		(layer "In1.Cu")
	)
	(gr_line
		(start 388.176262 -8.059928)
		(end 387.617462 -8.059928)
		(stroke
			(width 0.254)
			(type default)
		)
		(layer "In1.Cu")
	)
	(gr_line
		(start 388.176262 -5.924804)
		(end 388.176262 -8.160004)
		(stroke
			(width 0.254)
			(type default)
		)
		(layer "In1.Cu")
	)
	(gr_line
		(start 388.176262 -5.824728)
		(end 388.176262 -8.059928)
		(stroke
			(width 0.254)
			(type default)
		)
		(layer "In1.Cu")
	)
	(gr_line
		(start 388.176262 -3.95986)
		(end 387.617462 -3.95986)
		(stroke
			(width 0.254)
			(type default)
		)
		(layer "In1.Cu")
	)
	(gr_line
		(start 388.176262 -3.859784)
		(end 387.617462 -3.859784)
		(stroke
			(width 0.254)
			(type default)
		)
		(layer "In1.Cu")
	)
	(gr_line
		(start 388.176262 -1.72466)
		(end 388.176262 -3.95986)
		(stroke
			(width 0.254)
			(type default)
		)
		(layer "In1.Cu")
	)
	(gr_line
		(start 388.176262 -1.624584)
		(end 388.176262 -3.859784)
		(stroke
			(width 0.254)
			(type default)
		)
		(layer "In1.Cu")
	)
	(gr_line
		(start 388.252462 -12.385548)
		(end 387.541262 -12.385548)
		(stroke
			(width 0.254)
			(type default)
		)
		(layer "In1.Cu")
	)
	(gr_line
		(start 388.252462 -12.285472)
		(end 387.541262 -12.285472)
		(stroke
			(width 0.254)
			(type default)
		)
		(layer "In1.Cu")
	)
	(gr_line
		(start 388.252462 -10.048748)
		(end 388.252462 -12.385548)
		(stroke
			(width 0.254)
			(type default)
		)
		(layer "In1.Cu")
	)
	(gr_line
		(start 388.252462 -9.948672)
		(end 388.252462 -12.285472)
		(stroke
			(width 0.254)
			(type default)
		)
		(layer "In1.Cu")
	)
	(gr_line
		(start 388.252462 -8.185404)
		(end 387.541262 -8.185404)
		(stroke
			(width 0.254)
			(type default)
		)
		(layer "In1.Cu")
	)
	(gr_line
		(start 388.252462 -8.085328)
		(end 387.541262 -8.085328)
		(stroke
			(width 0.254)
			(type default)
		)
		(layer "In1.Cu")
	)
	(gr_line
		(start 388.252462 -5.848604)
		(end 388.252462 -8.185404)
		(stroke
			(width 0.254)
			(type default)
		)
		(layer "In1.Cu")
	)
	(gr_line
		(start 388.252462 -5.748528)
		(end 388.252462 -8.085328)
		(stroke
			(width 0.254)
			(type default)
		)
		(layer "In1.Cu")
	)
	(gr_line
		(start 388.252462 -3.98526)
		(end 387.541262 -3.98526)
		(stroke
			(width 0.254)
			(type default)
		)
		(layer "In1.Cu")
	)
	(gr_line
		(start 388.252462 -3.885184)
		(end 387.541262 -3.885184)
		(stroke
			(width 0.254)
			(type default)
		)
		(layer "In1.Cu")
	)
	(gr_line
		(start 388.252462 -1.64846)
		(end 388.252462 -3.98526)
		(stroke
			(width 0.254)
			(type default)
		)
		(layer "In1.Cu")
	)
	(gr_line
		(start 388.252462 -1.548384)
		(end 388.252462 -3.885184)
		(stroke
			(width 0.254)
			(type default)
		)
		(layer "In1.Cu")
	)
	(gr_line
		(start 388.277862 -12.512548)
		(end 387.287262 -12.512548)
		(stroke
			(width 0.1016)
			(type default)
		)
		(layer "In1.Cu")
	)
	(gr_line
		(start 388.277862 -12.436348)
		(end 387.465062 -12.436348)
		(stroke
			(width 0.254)
			(type default)
		)
		(layer "In1.Cu")
	)
	(gr_line
		(start 388.277862 -12.412472)
		(end 387.287262 -12.412472)
		(stroke
			(width 0.1016)
			(type default)
		)
		(layer "In1.Cu")
	)
	(gr_line
		(start 388.277862 -12.336272)
		(end 387.465062 -12.336272)
		(stroke
			(width 0.254)
			(type default)
		)
		(layer "In1.Cu")
	)
	(gr_line
		(start 388.277862 -10.023348)
		(end 388.277862 -12.436348)
		(stroke
			(width 0.254)
			(type default)
		)
		(layer "In1.Cu")
	)
	(gr_line
		(start 388.277862 -9.923272)
		(end 388.277862 -12.336272)
		(stroke
			(width 0.254)
			(type default)
		)
		(layer "In1.Cu")
	)
	(gr_line
		(start 388.277862 -8.312404)
		(end 387.287262 -8.312404)
		(stroke
			(width 0.1016)
			(type default)
		)
		(layer "In1.Cu")
	)
	(gr_line
		(start 388.277862 -8.236204)
		(end 387.465062 -8.236204)
		(stroke
			(width 0.254)
			(type default)
		)
		(layer "In1.Cu")
	)
	(gr_line
		(start 388.277862 -8.212328)
		(end 387.287262 -8.212328)
		(stroke
			(width 0.1016)
			(type default)
		)
		(layer "In1.Cu")
	)
	(gr_line
		(start 388.277862 -8.136128)
		(end 387.465062 -8.136128)
		(stroke
			(width 0.254)
			(type default)
		)
		(layer "In1.Cu")
	)
	(gr_line
		(start 388.277862 -5.823204)
		(end 388.277862 -8.236204)
		(stroke
			(width 0.254)
			(type default)
		)
		(layer "In1.Cu")
	)
	(gr_line
		(start 388.277862 -5.723128)
		(end 388.277862 -8.136128)
		(stroke
			(width 0.254)
			(type default)
		)
		(layer "In1.Cu")
	)
	(gr_line
		(start 388.277862 -4.11226)
		(end 387.287262 -4.11226)
		(stroke
			(width 0.1016)
			(type default)
		)
		(layer "In1.Cu")
	)
	(gr_line
		(start 388.277862 -4.03606)
		(end 387.465062 -4.03606)
		(stroke
			(width 0.254)
			(type default)
		)
		(layer "In1.Cu")
	)
	(gr_line
		(start 388.277862 -4.012184)
		(end 387.287262 -4.012184)
		(stroke
			(width 0.1016)
			(type default)
		)
		(layer "In1.Cu")
	)
	(gr_line
		(start 388.277862 -3.935984)
		(end 387.465062 -3.935984)
		(stroke
			(width 0.254)
			(type default)
		)
		(layer "In1.Cu")
	)
	(gr_line
		(start 388.277862 -1.62306)
		(end 388.277862 -4.03606)
		(stroke
			(width 0.254)
			(type default)
		)
		(layer "In1.Cu")
	)
	(gr_line
		(start 388.277862 -1.522984)
		(end 388.277862 -3.935984)
		(stroke
			(width 0.254)
			(type default)
		)
		(layer "In1.Cu")
	)
	(gr_line
		(start 388.303262 -12.461748)
		(end 387.439662 -12.461748)
		(stroke
			(width 0.254)
			(type default)
		)
		(layer "In1.Cu")
	)
	(gr_line
		(start 388.303262 -12.361672)
		(end 387.439662 -12.361672)
		(stroke
			(width 0.254)
			(type default)
		)
		(layer "In1.Cu")
	)
	(gr_line
		(start 388.303262 -9.997948)
		(end 388.303262 -12.461748)
		(stroke
			(width 0.254)
			(type default)
		)
		(layer "In1.Cu")
	)
	(gr_line
		(start 388.303262 -9.897872)
		(end 388.303262 -12.361672)
		(stroke
			(width 0.254)
			(type default)
		)
		(layer "In1.Cu")
	)
	(gr_line
		(start 388.303262 -8.261604)
		(end 387.439662 -8.261604)
		(stroke
			(width 0.254)
			(type default)
		)
		(layer "In1.Cu")
	)
	(gr_line
		(start 388.303262 -8.161528)
		(end 387.439662 -8.161528)
		(stroke
			(width 0.254)
			(type default)
		)
		(layer "In1.Cu")
	)
	(gr_line
		(start 388.303262 -5.797804)
		(end 388.303262 -8.261604)
		(stroke
			(width 0.254)
			(type default)
		)
		(layer "In1.Cu")
	)
	(gr_line
		(start 388.303262 -5.697728)
		(end 388.303262 -8.161528)
		(stroke
			(width 0.254)
			(type default)
		)
		(layer "In1.Cu")
	)
	(gr_line
		(start 388.303262 -4.06146)
		(end 387.439662 -4.06146)
		(stroke
			(width 0.254)
			(type default)
		)
		(layer "In1.Cu")
	)
	(gr_line
		(start 388.303262 -3.961384)
		(end 387.439662 -3.961384)
		(stroke
			(width 0.254)
			(type default)
		)
		(layer "In1.Cu")
	)
	(gr_line
		(start 388.303262 -1.59766)
		(end 388.303262 -4.06146)
		(stroke
			(width 0.254)
			(type default)
		)
		(layer "In1.Cu")
	)
	(gr_line
		(start 388.303262 -1.497584)
		(end 388.303262 -3.961384)
		(stroke
			(width 0.254)
			(type default)
		)
		(layer "In1.Cu")
	)
	(gr_line
		(start 388.354062 -12.487148)
		(end 387.414262 -12.487148)
		(stroke
			(width 0.254)
			(type default)
		)
		(layer "In1.Cu")
	)
	(gr_line
		(start 388.354062 -12.387072)
		(end 387.414262 -12.387072)
		(stroke
			(width 0.254)
			(type default)
		)
		(layer "In1.Cu")
	)
	(gr_line
		(start 388.354062 -9.997948)
		(end 388.354062 -12.487148)
		(stroke
			(width 0.254)
			(type default)
		)
		(layer "In1.Cu")
	)
	(gr_line
		(start 388.354062 -9.897872)
		(end 388.354062 -12.387072)
		(stroke
			(width 0.254)
			(type default)
		)
		(layer "In1.Cu")
	)
	(gr_line
		(start 388.354062 -8.287004)
		(end 387.414262 -8.287004)
		(stroke
			(width 0.254)
			(type default)
		)
		(layer "In1.Cu")
	)
	(gr_line
		(start 388.354062 -8.186928)
		(end 387.414262 -8.186928)
		(stroke
			(width 0.254)
			(type default)
		)
		(layer "In1.Cu")
	)
	(gr_line
		(start 388.354062 -5.797804)
		(end 388.354062 -8.287004)
		(stroke
			(width 0.254)
			(type default)
		)
		(layer "In1.Cu")
	)
	(gr_line
		(start 388.354062 -5.697728)
		(end 388.354062 -8.186928)
		(stroke
			(width 0.254)
			(type default)
		)
		(layer "In1.Cu")
	)
	(gr_line
		(start 388.354062 -4.08686)
		(end 387.414262 -4.08686)
		(stroke
			(width 0.254)
			(type default)
		)
		(layer "In1.Cu")
	)
	(gr_line
		(start 388.354062 -3.986784)
		(end 387.414262 -3.986784)
		(stroke
			(width 0.254)
			(type default)
		)
		(layer "In1.Cu")
	)
	(gr_line
		(start 388.354062 -1.59766)
		(end 388.354062 -4.08686)
		(stroke
			(width 0.254)
			(type default)
		)
		(layer "In1.Cu")
	)
	(gr_line
		(start 388.354062 -1.497584)
		(end 388.354062 -3.986784)
		(stroke
			(width 0.254)
			(type default)
		)
		(layer "In1.Cu")
	)
	(gr_line
		(start 388.379462 -12.487148)
		(end 387.414262 -12.487148)
		(stroke
			(width 0.2032)
			(type default)
		)
		(layer "In1.Cu")
	)
	(gr_line
		(start 388.379462 -12.387072)
		(end 387.414262 -12.387072)
		(stroke
			(width 0.2032)
			(type default)
		)
		(layer "In1.Cu")
	)
	(gr_line
		(start 388.379462 -9.947148)
		(end 388.379462 -12.487148)
		(stroke
			(width 0.2032)
			(type default)
		)
		(layer "In1.Cu")
	)
	(gr_line
		(start 388.379462 -9.847072)
		(end 388.379462 -12.387072)
		(stroke
			(width 0.2032)
			(type default)
		)
		(layer "In1.Cu")
	)
	(gr_line
		(start 388.379462 -8.287004)
		(end 387.414262 -8.287004)
		(stroke
			(width 0.2032)
			(type default)
		)
		(layer "In1.Cu")
	)
	(gr_line
		(start 388.379462 -8.186928)
		(end 387.414262 -8.186928)
		(stroke
			(width 0.2032)
			(type default)
		)
		(layer "In1.Cu")
	)
	(gr_line
		(start 388.379462 -5.747004)
		(end 388.379462 -8.287004)
		(stroke
			(width 0.2032)
			(type default)
		)
		(layer "In1.Cu")
	)
	(gr_line
		(start 388.379462 -5.646928)
		(end 388.379462 -8.186928)
		(stroke
			(width 0.2032)
			(type default)
		)
		(layer "In1.Cu")
	)
	(gr_line
		(start 388.379462 -4.08686)
		(end 387.414262 -4.08686)
		(stroke
			(width 0.2032)
			(type default)
		)
		(layer "In1.Cu")
	)
	(gr_line
		(start 388.379462 -3.986784)
		(end 387.414262 -3.986784)
		(stroke
			(width 0.2032)
			(type default)
		)
		(layer "In1.Cu")
	)
	(gr_line
		(start 388.379462 -1.54686)
		(end 388.379462 -4.08686)
		(stroke
			(width 0.2032)
			(type default)
		)
		(layer "In1.Cu")
	)
	(gr_line
		(start 388.379462 -1.446784)
		(end 388.379462 -3.986784)
		(stroke
			(width 0.2032)
			(type default)
		)
		(layer "In1.Cu")
	)
	(gr_line
		(start 388.430262 -12.512548)
		(end 387.363462 -12.512548)
		(stroke
			(width 0.2032)
			(type default)
		)
		(layer "In1.Cu")
	)
	(gr_line
		(start 388.430262 -12.412472)
		(end 387.363462 -12.412472)
		(stroke
			(width 0.2032)
			(type default)
		)
		(layer "In1.Cu")
	)
	(gr_line
		(start 388.430262 -9.947148)
		(end 388.430262 -12.512548)
		(stroke
			(width 0.2032)
			(type default)
		)
		(layer "In1.Cu")
	)
	(gr_line
		(start 388.430262 -9.847072)
		(end 388.430262 -12.412472)
		(stroke
			(width 0.2032)
			(type default)
		)
		(layer "In1.Cu")
	)
	(gr_line
		(start 388.430262 -8.312404)
		(end 387.363462 -8.312404)
		(stroke
			(width 0.2032)
			(type default)
		)
		(layer "In1.Cu")
	)
	(gr_line
		(start 388.430262 -8.212328)
		(end 387.363462 -8.212328)
		(stroke
			(width 0.2032)
			(type default)
		)
		(layer "In1.Cu")
	)
	(gr_line
		(start 388.430262 -5.747004)
		(end 388.430262 -8.312404)
		(stroke
			(width 0.2032)
			(type default)
		)
		(layer "In1.Cu")
	)
	(gr_line
		(start 388.430262 -5.646928)
		(end 388.430262 -8.212328)
		(stroke
			(width 0.2032)
			(type default)
		)
		(layer "In1.Cu")
	)
	(gr_line
		(start 388.430262 -4.11226)
		(end 387.363462 -4.11226)
		(stroke
			(width 0.2032)
			(type default)
		)
		(layer "In1.Cu")
	)
	(gr_line
		(start 388.430262 -4.012184)
		(end 387.363462 -4.012184)
		(stroke
			(width 0.2032)
			(type default)
		)
		(layer "In1.Cu")
	)
	(gr_line
		(start 388.430262 -1.54686)
		(end 388.430262 -4.11226)
		(stroke
			(width 0.2032)
			(type default)
		)
		(layer "In1.Cu")
	)
	(gr_line
		(start 388.430262 -1.446784)
		(end 388.430262 -4.012184)
		(stroke
			(width 0.2032)
			(type default)
		)
		(layer "In1.Cu")
	)
	(gr_line
		(start 388.455662 -12.512548)
		(end 387.338062 -12.512548)
		(stroke
			(width 0.1016)
			(type default)
		)
		(layer "In1.Cu")
	)
	(gr_line
		(start 388.455662 -12.412472)
		(end 387.338062 -12.412472)
		(stroke
			(width 0.1016)
			(type default)
		)
		(layer "In1.Cu")
	)
	(gr_line
		(start 388.455662 -9.921748)
		(end 388.455662 -12.512548)
		(stroke
			(width 0.1016)
			(type default)
		)
		(layer "In1.Cu")
	)
	(gr_line
		(start 388.455662 -9.821672)
		(end 388.455662 -12.412472)
		(stroke
			(width 0.1016)
			(type default)
		)
		(layer "In1.Cu")
	)
	(gr_line
		(start 388.455662 -8.312404)
		(end 387.338062 -8.312404)
		(stroke
			(width 0.1016)
			(type default)
		)
		(layer "In1.Cu")
	)
	(gr_line
		(start 388.455662 -8.212328)
		(end 387.338062 -8.212328)
		(stroke
			(width 0.1016)
			(type default)
		)
		(layer "In1.Cu")
	)
	(gr_line
		(start 388.455662 -5.721604)
		(end 388.455662 -8.312404)
		(stroke
			(width 0.1016)
			(type default)
		)
		(layer "In1.Cu")
	)
	(gr_line
		(start 388.455662 -5.621528)
		(end 388.455662 -8.212328)
		(stroke
			(width 0.1016)
			(type default)
		)
		(layer "In1.Cu")
	)
	(gr_line
		(start 388.455662 -4.11226)
		(end 387.338062 -4.11226)
		(stroke
			(width 0.1016)
			(type default)
		)
		(layer "In1.Cu")
	)
	(gr_line
		(start 388.455662 -4.012184)
		(end 387.338062 -4.012184)
		(stroke
			(width 0.1016)
			(type default)
		)
		(layer "In1.Cu")
	)
	(gr_line
		(start 388.455662 -1.52146)
		(end 388.455662 -4.11226)
		(stroke
			(width 0.1016)
			(type default)
		)
		(layer "In1.Cu")
	)
	(gr_line
		(start 388.455662 -1.421384)
		(end 388.455662 -4.012184)
		(stroke
			(width 0.1016)
			(type default)
		)
		(layer "In1.Cu")
	)
	(gr_line
		(start 388.464806 -18.5166)
		(end 389.734806 -18.5166)
		(stroke
			(width 0.7874)
			(type default)
		)
		(layer "In1.Cu")
	)
	(gr_line
		(start 388.481062 -12.563348)
		(end 388.074662 -12.563348)
		(stroke
			(width 0.1016)
			(type default)
		)
		(layer "In1.Cu")
	)
	(gr_line
		(start 388.481062 -12.563348)
		(end 388.481062 -9.896348)
		(stroke
			(width 0.1016)
			(type default)
		)
		(layer "In1.Cu")
	)
	(gr_line
		(start 388.481062 -12.463272)
		(end 388.074662 -12.463272)
		(stroke
			(width 0.1016)
			(type default)
		)
		(layer "In1.Cu")
	)
	(gr_line
		(start 388.481062 -12.463272)
		(end 388.481062 -9.796272)
		(stroke
			(width 0.1016)
			(type default)
		)
		(layer "In1.Cu")
	)
	(gr_line
		(start 388.481062 -9.896348)
		(end 387.287262 -9.896348)
		(stroke
			(width 0.1016)
			(type default)
		)
		(layer "In1.Cu")
	)
	(gr_line
		(start 388.481062 -9.896348)
		(end 388.481062 -12.563348)
		(stroke
			(width 0.1016)
			(type default)
		)
		(layer "In1.Cu")
	)
	(gr_line
		(start 388.481062 -9.796272)
		(end 387.287262 -9.796272)
		(stroke
			(width 0.1016)
			(type default)
		)
		(layer "In1.Cu")
	)
	(gr_line
		(start 388.481062 -9.796272)
		(end 388.481062 -12.463272)
		(stroke
			(width 0.1016)
			(type default)
		)
		(layer "In1.Cu")
	)
	(gr_line
		(start 388.481062 -8.363204)
		(end 388.074662 -8.363204)
		(stroke
			(width 0.1016)
			(type default)
		)
		(layer "In1.Cu")
	)
	(gr_line
		(start 388.481062 -8.363204)
		(end 388.481062 -5.696204)
		(stroke
			(width 0.1016)
			(type default)
		)
		(layer "In1.Cu")
	)
	(gr_line
		(start 388.481062 -8.263128)
		(end 388.074662 -8.263128)
		(stroke
			(width 0.1016)
			(type default)
		)
		(layer "In1.Cu")
	)
	(gr_line
		(start 388.481062 -8.263128)
		(end 388.481062 -5.596128)
		(stroke
			(width 0.1016)
			(type default)
		)
		(layer "In1.Cu")
	)
	(gr_line
		(start 388.481062 -5.696204)
		(end 387.287262 -5.696204)
		(stroke
			(width 0.1016)
			(type default)
		)
		(layer "In1.Cu")
	)
	(gr_line
		(start 388.481062 -5.696204)
		(end 388.481062 -8.363204)
		(stroke
			(width 0.1016)
			(type default)
		)
		(layer "In1.Cu")
	)
	(gr_line
		(start 388.481062 -5.596128)
		(end 387.287262 -5.596128)
		(stroke
			(width 0.1016)
			(type default)
		)
		(layer "In1.Cu")
	)
	(gr_line
		(start 388.481062 -5.596128)
		(end 388.481062 -8.263128)
		(stroke
			(width 0.1016)
			(type default)
		)
		(layer "In1.Cu")
	)
	(gr_line
		(start 388.481062 -4.16306)
		(end 388.074662 -4.16306)
		(stroke
			(width 0.1016)
			(type default)
		)
		(layer "In1.Cu")
	)
	(gr_line
		(start 388.481062 -4.16306)
		(end 388.481062 -1.49606)
		(stroke
			(width 0.1016)
			(type default)
		)
		(layer "In1.Cu")
	)
	(gr_line
		(start 388.481062 -4.062984)
		(end 388.074662 -4.062984)
		(stroke
			(width 0.1016)
			(type default)
		)
		(layer "In1.Cu")
	)
	(gr_line
		(start 388.481062 -4.062984)
		(end 388.481062 -1.395984)
		(stroke
			(width 0.1016)
			(type default)
		)
		(layer "In1.Cu")
	)
	(gr_line
		(start 388.481062 -1.49606)
		(end 387.287262 -1.49606)
		(stroke
			(width 0.1016)
			(type default)
		)
		(layer "In1.Cu")
	)
	(gr_line
		(start 388.481062 -1.49606)
		(end 388.481062 -4.16306)
		(stroke
			(width 0.1016)
			(type default)
		)
		(layer "In1.Cu")
	)
	(gr_line
		(start 388.481062 -1.395984)
		(end 387.287262 -1.395984)
		(stroke
			(width 0.1016)
			(type default)
		)
		(layer "In1.Cu")
	)
	(gr_line
		(start 388.481062 -1.395984)
		(end 388.481062 -4.062984)
		(stroke
			(width 0.1016)
			(type default)
		)
		(layer "In1.Cu")
	)
	(gr_line
		(start 389.097012 -29.337)
		(end 389.935212 -29.337)
		(stroke
			(width 0.1016)
			(type default)
		)
		(layer "In1.Cu")
	)
	(gr_line
		(start 389.097012 -27.4828)
		(end 389.097012 -29.337)
		(stroke
			(width 0.1016)
			(type default)
		)
		(layer "In1.Cu")
	)
	(gr_line
		(start 389.147812 -29.2354)
		(end 389.147812 -27.559)
		(stroke
			(width 0.2032)
			(type default)
		)
		(layer "In1.Cu")
	)
	(gr_line
		(start 389.147812 -27.559)
		(end 390.214612 -27.559)
		(stroke
			(width 0.2032)
			(type default)
		)
		(layer "In1.Cu")
	)
	(gr_line
		(start 389.173212 -29.2608)
		(end 390.163812 -29.2608)
		(stroke
			(width 0.2032)
			(type default)
		)
		(layer "In1.Cu")
	)
	(gr_line
		(start 389.173212 -29.2354)
		(end 389.173212 -29.2608)
		(stroke
			(width 0.2032)
			(type default)
		)
		(layer "In1.Cu")
	)
	(gr_line
		(start 389.224012 -29.1846)
		(end 390.163812 -29.1846)
		(stroke
			(width 0.2032)
			(type default)
		)
		(layer "In1.Cu")
	)
	(gr_line
		(start 389.224012 -27.6098)
		(end 389.224012 -29.1846)
		(stroke
			(width 0.2032)
			(type default)
		)
		(layer "In1.Cu")
	)
	(gr_line
		(start 389.287258 -13.8176)
		(end 390.074658 -13.8176)
		(stroke
			(width 0.1016)
			(type default)
		)
		(layer "In1.Cu")
	)
	(gr_line
		(start 389.287258 -13.7668)
		(end 389.287258 -11.1506)
		(stroke
			(width 0.1016)
			(type default)
		)
		(layer "In1.Cu")
	)
	(gr_line
		(start 389.287258 -11.1506)
		(end 389.287258 -13.8176)
		(stroke
			(width 0.1016)
			(type default)
		)
		(layer "In1.Cu")
	)
	(gr_line
		(start 389.287258 -11.1506)
		(end 390.481058 -11.1506)
		(stroke
			(width 0.1016)
			(type default)
		)
		(layer "In1.Cu")
	)
	(gr_line
		(start 389.287258 -9.617456)
		(end 390.074658 -9.617456)
		(stroke
			(width 0.1016)
			(type default)
		)
		(layer "In1.Cu")
	)
	(gr_line
		(start 389.287258 -9.566656)
		(end 389.287258 -6.950456)
		(stroke
			(width 0.1016)
			(type default)
		)
		(layer "In1.Cu")
	)
	(gr_line
		(start 389.287258 -6.950456)
		(end 389.287258 -9.617456)
		(stroke
			(width 0.1016)
			(type default)
		)
		(layer "In1.Cu")
	)
	(gr_line
		(start 389.287258 -6.950456)
		(end 390.481058 -6.950456)
		(stroke
			(width 0.1016)
			(type default)
		)
		(layer "In1.Cu")
	)
	(gr_line
		(start 389.300212 -29.1084)
		(end 389.300212 -27.7622)
		(stroke
			(width 0.508)
			(type default)
		)
		(layer "In1.Cu")
	)
	(gr_line
		(start 389.312658 -13.7668)
		(end 389.312658 -11.176)
		(stroke
			(width 0.1016)
			(type default)
		)
		(layer "In1.Cu")
	)
	(gr_line
		(start 389.312658 -11.176)
		(end 390.455658 -11.176)
		(stroke
			(width 0.1016)
			(type default)
		)
		(layer "In1.Cu")
	)
	(gr_line
		(start 389.312658 -9.566656)
		(end 389.312658 -6.975856)
		(stroke
			(width 0.1016)
			(type default)
		)
		(layer "In1.Cu")
	)
	(gr_line
		(start 389.312658 -6.975856)
		(end 390.455658 -6.975856)
		(stroke
			(width 0.1016)
			(type default)
		)
		(layer "In1.Cu")
	)
	(gr_line
		(start 389.325612 -29.1084)
		(end 389.986012 -29.1084)
		(stroke
			(width 0.508)
			(type default)
		)
		(layer "In1.Cu")
	)
	(gr_line
		(start 389.325612 -29.083)
		(end 389.325612 -27.7368)
		(stroke
			(width 0.508)
			(type default)
		)
		(layer "In1.Cu")
	)
	(gr_line
		(start 389.325612 -27.7114)
		(end 389.960612 -27.7114)
		(stroke
			(width 0.508)
			(type default)
		)
		(layer "In1.Cu")
	)
	(gr_line
		(start 389.338058 -13.7668)
		(end 389.338058 -11.2014)
		(stroke
			(width 0.1016)
			(type default)
		)
		(layer "In1.Cu")
	)
	(gr_line
		(start 389.338058 -11.2014)
		(end 389.592058 -11.2014)
		(stroke
			(width 0.1016)
			(type default)
		)
		(layer "In1.Cu")
	)
	(gr_line
		(start 389.338058 -9.566656)
		(end 389.338058 -7.001256)
		(stroke
			(width 0.1016)
			(type default)
		)
		(layer "In1.Cu")
	)
	(gr_line
		(start 389.338058 -7.001256)
		(end 389.592058 -7.001256)
		(stroke
			(width 0.1016)
			(type default)
		)
		(layer "In1.Cu")
	)
	(gr_line
		(start 389.351012 -29.083)
		(end 389.351012 -27.7368)
		(stroke
			(width 0.508)
			(type default)
		)
		(layer "In1.Cu")
	)
	(gr_line
		(start 389.363458 -13.7668)
		(end 389.363458 -11.2014)
		(stroke
			(width 0.2032)
			(type default)
		)
		(layer "In1.Cu")
	)
	(gr_line
		(start 389.363458 -11.2014)
		(end 390.379458 -11.2014)
		(stroke
			(width 0.2032)
			(type default)
		)
		(layer "In1.Cu")
	)
	(gr_line
		(start 389.363458 -9.566656)
		(end 389.363458 -7.001256)
		(stroke
			(width 0.2032)
			(type default)
		)
		(layer "In1.Cu")
	)
	(gr_line
		(start 389.363458 -7.001256)
		(end 390.379458 -7.001256)
		(stroke
			(width 0.2032)
			(type default)
		)
		(layer "In1.Cu")
	)
	(gr_line
		(start 389.376412 -29.083)
		(end 389.376412 -27.7368)
		(stroke
			(width 0.508)
			(type default)
		)
		(layer "In1.Cu")
	)
	(gr_line
		(start 389.414258 -13.7414)
		(end 389.414258 -11.2522)
		(stroke
			(width 0.2032)
			(type default)
		)
		(layer "In1.Cu")
	)
	(gr_line
		(start 389.414258 -13.7414)
		(end 389.414258 -11.2522)
		(stroke
			(width 0.254)
			(type default)
		)
		(layer "In1.Cu")
	)
	(gr_line
		(start 389.414258 -11.2522)
		(end 389.617458 -11.2522)
		(stroke
			(width 0.2032)
			(type default)
		)
		(layer "In1.Cu")
	)
	(gr_line
		(start 389.414258 -11.2522)
		(end 390.303258 -11.2522)
		(stroke
			(width 0.254)
			(type default)
		)
		(layer "In1.Cu")
	)
	(gr_line
		(start 389.414258 -9.541256)
		(end 389.414258 -7.052056)
		(stroke
			(width 0.2032)
			(type default)
		)
		(layer "In1.Cu")
	)
	(gr_line
		(start 389.414258 -9.541256)
		(end 389.414258 -7.052056)
		(stroke
			(width 0.254)
			(type default)
		)
		(layer "In1.Cu")
	)
	(gr_line
		(start 389.414258 -7.052056)
		(end 389.617458 -7.052056)
		(stroke
			(width 0.2032)
			(type default)
		)
		(layer "In1.Cu")
	)
	(gr_line
		(start 389.414258 -7.052056)
		(end 390.303258 -7.052056)
		(stroke
			(width 0.254)
			(type default)
		)
		(layer "In1.Cu")
	)
	(gr_line
		(start 389.427212 -29.1084)
		(end 389.427212 -27.7622)
		(stroke
			(width 0.508)
			(type default)
		)
		(layer "In1.Cu")
	)
	(gr_line
		(start 389.427212 -29.083)
		(end 389.427212 -27.7368)
		(stroke
			(width 0.508)
			(type default)
		)
		(layer "In1.Cu")
	)
	(gr_line
		(start 389.439658 -13.716)
		(end 389.439658 -11.2776)
		(stroke
			(width 0.254)
			(type default)
		)
		(layer "In1.Cu")
	)
	(gr_line
		(start 389.439658 -11.2776)
		(end 390.277858 -11.2776)
		(stroke
			(width 0.254)
			(type default)
		)
		(layer "In1.Cu")
	)
	(gr_line
		(start 389.439658 -9.515856)
		(end 389.439658 -7.077456)
		(stroke
			(width 0.254)
			(type default)
		)
		(layer "In1.Cu")
	)
	(gr_line
		(start 389.439658 -7.077456)
		(end 390.277858 -7.077456)
		(stroke
			(width 0.254)
			(type default)
		)
		(layer "In1.Cu")
	)
	(gr_line
		(start 389.465058 -13.6906)
		(end 389.465058 -11.303)
		(stroke
			(width 0.254)
			(type default)
		)
		(layer "In1.Cu")
	)
	(gr_line
		(start 389.465058 -11.303)
		(end 390.252458 -11.303)
		(stroke
			(width 0.254)
			(type default)
		)
		(layer "In1.Cu")
	)
	(gr_line
		(start 389.465058 -9.490456)
		(end 389.465058 -7.102856)
		(stroke
			(width 0.254)
			(type default)
		)
		(layer "In1.Cu")
	)
	(gr_line
		(start 389.465058 -7.102856)
		(end 390.252458 -7.102856)
		(stroke
			(width 0.254)
			(type default)
		)
		(layer "In1.Cu")
	)
	(gr_line
		(start 389.478012 -29.083)
		(end 389.478012 -27.7368)
		(stroke
			(width 0.508)
			(type default)
		)
		(layer "In1.Cu")
	)
	(gr_line
		(start 389.490458 -13.6144)
		(end 390.125458 -13.6144)
		(stroke
			(width 0.508)
			(type default)
		)
		(layer "In1.Cu")
	)
	(gr_line
		(start 389.490458 -11.43)
		(end 390.125458 -11.43)
		(stroke
			(width 0.508)
			(type default)
		)
		(layer "In1.Cu")
	)
	(gr_line
		(start 389.490458 -11.3792)
		(end 390.125458 -11.3792)
		(stroke
			(width 0.508)
			(type default)
		)
		(layer "In1.Cu")
	)
	(gr_line
		(start 389.490458 -9.414256)
		(end 390.125458 -9.414256)
		(stroke
			(width 0.508)
			(type default)
		)
		(layer "In1.Cu")
	)
	(gr_line
		(start 389.490458 -7.229856)
		(end 390.125458 -7.229856)
		(stroke
			(width 0.508)
			(type default)
		)
		(layer "In1.Cu")
	)
	(gr_line
		(start 389.490458 -7.179056)
		(end 390.125458 -7.179056)
		(stroke
			(width 0.508)
			(type default)
		)
		(layer "In1.Cu")
	)
	(gr_line
		(start 389.497062 -26.826972)
		(end 390.335262 -26.826972)
		(stroke
			(width 0.1016)
			(type default)
		)
		(layer "In1.Cu")
	)
	(gr_line
		(start 389.497062 -24.972772)
		(end 389.497062 -26.826972)
		(stroke
			(width 0.1016)
			(type default)
		)
		(layer "In1.Cu")
	)
	(gr_line
		(start 389.503412 -29.0576)
		(end 389.503412 -27.7114)
		(stroke
			(width 0.508)
			(type default)
		)
		(layer "In1.Cu")
	)
	(gr_line
		(start 389.515858 -11.684)
		(end 390.150858 -11.684)
		(stroke
			(width 0.508)
			(type default)
		)
		(layer "In1.Cu")
	)
	(gr_line
		(start 389.515858 -7.483856)
		(end 390.150858 -7.483856)
		(stroke
			(width 0.508)
			(type default)
		)
		(layer "In1.Cu")
	)
	(gr_line
		(start 389.528812 -29.083)
		(end 389.528812 -27.7368)
		(stroke
			(width 0.508)
			(type default)
		)
		(layer "In1.Cu")
	)
	(gr_line
		(start 389.541258 -13.6398)
		(end 389.541258 -11.3792)
		(stroke
			(width 0.254)
			(type default)
		)
		(layer "In1.Cu")
	)
	(gr_line
		(start 389.541258 -13.4874)
		(end 390.176258 -13.4874)
		(stroke
			(width 0.508)
			(type default)
		)
		(layer "In1.Cu")
	)
	(gr_line
		(start 389.541258 -11.3792)
		(end 390.176258 -11.3792)
		(stroke
			(width 0.254)
			(type default)
		)
		(layer "In1.Cu")
	)
	(gr_line
		(start 389.541258 -9.439656)
		(end 389.541258 -7.179056)
		(stroke
			(width 0.254)
			(type default)
		)
		(layer "In1.Cu")
	)
	(gr_line
		(start 389.541258 -9.287256)
		(end 390.176258 -9.287256)
		(stroke
			(width 0.508)
			(type default)
		)
		(layer "In1.Cu")
	)
	(gr_line
		(start 389.541258 -7.179056)
		(end 390.176258 -7.179056)
		(stroke
			(width 0.254)
			(type default)
		)
		(layer "In1.Cu")
	)
	(gr_line
		(start 389.547862 -26.725372)
		(end 389.547862 -25.048972)
		(stroke
			(width 0.2032)
			(type default)
		)
		(layer "In1.Cu")
	)
	(gr_line
		(start 389.547862 -25.048972)
		(end 390.614662 -25.048972)
		(stroke
			(width 0.2032)
			(type default)
		)
		(layer "In1.Cu")
	)
	(gr_line
		(start 389.554212 -29.083)
		(end 389.554212 -27.7368)
		(stroke
			(width 0.508)
			(type default)
		)
		(layer "In1.Cu")
	)
	(gr_line
		(start 389.566658 -13.335)
		(end 390.201658 -13.335)
		(stroke
			(width 0.508)
			(type default)
		)
		(layer "In1.Cu")
	)
	(gr_line
		(start 389.566658 -9.134856)
		(end 390.201658 -9.134856)
		(stroke
			(width 0.508)
			(type default)
		)
		(layer "In1.Cu")
	)
	(gr_line
		(start 389.573262 -26.750772)
		(end 390.563862 -26.750772)
		(stroke
			(width 0.2032)
			(type default)
		)
		(layer "In1.Cu")
	)
	(gr_line
		(start 389.573262 -26.725372)
		(end 389.573262 -26.750772)
		(stroke
			(width 0.2032)
			(type default)
		)
		(layer "In1.Cu")
	)
	(gr_line
		(start 389.579612 -29.083)
		(end 389.579612 -27.7368)
		(stroke
			(width 0.508)
			(type default)
		)
		(layer "In1.Cu")
	)
	(gr_line
		(start 389.592058 -13.6144)
		(end 390.227058 -13.6144)
		(stroke
			(width 0.508)
			(type default)
		)
		(layer "In1.Cu")
	)
	(gr_line
		(start 389.592058 -11.2014)
		(end 390.430258 -11.2014)
		(stroke
			(width 0.2032)
			(type default)
		)
		(layer "In1.Cu")
	)
	(gr_line
		(start 389.592058 -9.414256)
		(end 390.227058 -9.414256)
		(stroke
			(width 0.508)
			(type default)
		)
		(layer "In1.Cu")
	)
	(gr_line
		(start 389.592058 -7.001256)
		(end 390.430258 -7.001256)
		(stroke
			(width 0.2032)
			(type default)
		)
		(layer "In1.Cu")
	)
	(gr_line
		(start 389.617458 -13.6144)
		(end 389.617458 -11.43)
		(stroke
			(width 0.254)
			(type default)
		)
		(layer "In1.Cu")
	)
	(gr_line
		(start 389.617458 -11.43)
		(end 390.100058 -11.43)
		(stroke
			(width 0.254)
			(type default)
		)
		(layer "In1.Cu")
	)
	(gr_line
		(start 389.617458 -11.2522)
		(end 390.354058 -11.2522)
		(stroke
			(width 0.254)
			(type default)
		)
		(layer "In1.Cu")
	)
	(gr_line
		(start 389.617458 -9.414256)
		(end 389.617458 -7.229856)
		(stroke
			(width 0.254)
			(type default)
		)
		(layer "In1.Cu")
	)
	(gr_line
		(start 389.617458 -7.229856)
		(end 390.100058 -7.229856)
		(stroke
			(width 0.254)
			(type default)
		)
		(layer "In1.Cu")
	)
	(gr_line
		(start 389.617458 -7.052056)
		(end 390.354058 -7.052056)
		(stroke
			(width 0.254)
			(type default)
		)
		(layer "In1.Cu")
	)
	(gr_line
		(start 389.624062 -26.674572)
		(end 390.563862 -26.674572)
		(stroke
			(width 0.2032)
			(type default)
		)
		(layer "In1.Cu")
	)
	(gr_line
		(start 389.624062 -25.099772)
		(end 389.624062 -26.674572)
		(stroke
			(width 0.2032)
			(type default)
		)
		(layer "In1.Cu")
	)
	(gr_line
		(start 389.630412 -29.083)
		(end 389.630412 -27.7368)
		(stroke
			(width 0.508)
			(type default)
		)
		(layer "In1.Cu")
	)
	(gr_line
		(start 389.636 -11.36523)
		(end 390.271 -11.36523)
		(stroke
			(width 0.508)
			(type default)
		)
		(layer "In1.Cu")
	)
	(gr_line
		(start 389.636 -7.165086)
		(end 390.271 -7.165086)
		(stroke
			(width 0.508)
			(type default)
		)
		(layer "In1.Cu")
	)
	(gr_line
		(start 389.642858 -13.6144)
		(end 390.277858 -13.6144)
		(stroke
			(width 0.508)
			(type default)
		)
		(layer "In1.Cu")
	)
	(gr_line
		(start 389.642858 -13.4874)
		(end 389.642858 -11.5062)
		(stroke
			(width 0.762)
			(type default)
		)
		(layer "In1.Cu")
	)
	(gr_line
		(start 389.642858 -11.5062)
		(end 390.277858 -11.5062)
		(stroke
			(width 0.508)
			(type default)
		)
		(layer "In1.Cu")
	)
	(gr_line
		(start 389.642858 -9.414256)
		(end 390.277858 -9.414256)
		(stroke
			(width 0.508)
			(type default)
		)
		(layer "In1.Cu")
	)
	(gr_line
		(start 389.642858 -9.287256)
		(end 389.642858 -7.306056)
		(stroke
			(width 0.762)
			(type default)
		)
		(layer "In1.Cu")
	)
	(gr_line
		(start 389.642858 -7.306056)
		(end 390.277858 -7.306056)
		(stroke
			(width 0.508)
			(type default)
		)
		(layer "In1.Cu")
	)
	(gr_line
		(start 389.655812 -29.083)
		(end 389.655812 -27.7368)
		(stroke
			(width 0.508)
			(type default)
		)
		(layer "In1.Cu")
	)
	(gr_line
		(start 389.681212 -29.083)
		(end 389.681212 -27.7368)
		(stroke
			(width 0.508)
			(type default)
		)
		(layer "In1.Cu")
	)
	(gr_line
		(start 389.693658 -13.5382)
		(end 389.693658 -11.5062)
		(stroke
			(width 0.254)
			(type default)
		)
		(layer "In1.Cu")
	)
	(gr_line
		(start 389.693658 -11.5062)
		(end 390.023858 -11.5062)
		(stroke
			(width 0.254)
			(type default)
		)
		(layer "In1.Cu")
	)
	(gr_line
		(start 389.693658 -9.338056)
		(end 389.693658 -7.306056)
		(stroke
			(width 0.254)
			(type default)
		)
		(layer "In1.Cu")
	)
	(gr_line
		(start 389.693658 -7.306056)
		(end 390.023858 -7.306056)
		(stroke
			(width 0.254)
			(type default)
		)
		(layer "In1.Cu")
	)
	(gr_line
		(start 389.700262 -26.598372)
		(end 389.700262 -25.252172)
		(stroke
			(width 0.508)
			(type default)
		)
		(layer "In1.Cu")
	)
	(gr_line
		(start 389.706612 -29.083)
		(end 389.706612 -27.7368)
		(stroke
			(width 0.508)
			(type default)
		)
		(layer "In1.Cu")
	)
	(gr_line
		(start 389.725662 -26.598372)
		(end 390.386062 -26.598372)
		(stroke
			(width 0.508)
			(type default)
		)
		(layer "In1.Cu")
	)
	(gr_line
		(start 389.725662 -26.572972)
		(end 389.725662 -25.226772)
		(stroke
			(width 0.508)
			(type default)
		)
		(layer "In1.Cu")
	)
	(gr_line
		(start 389.725662 -25.201372)
		(end 390.360662 -25.201372)
		(stroke
			(width 0.508)
			(type default)
		)
		(layer "In1.Cu")
	)
	(gr_line
		(start 389.732012 -29.1084)
		(end 389.732012 -27.7622)
		(stroke
			(width 0.508)
			(type default)
		)
		(layer "In1.Cu")
	)
	(gr_line
		(start 389.751062 -26.572972)
		(end 389.751062 -25.226772)
		(stroke
			(width 0.508)
			(type default)
		)
		(layer "In1.Cu")
	)
	(gr_line
		(start 389.757412 -29.1084)
		(end 389.757412 -27.7622)
		(stroke
			(width 0.508)
			(type default)
		)
		(layer "In1.Cu")
	)
	(gr_line
		(start 389.757412 -29.083)
		(end 389.757412 -27.7368)
		(stroke
			(width 0.508)
			(type default)
		)
		(layer "In1.Cu")
	)
	(gr_line
		(start 389.776462 -26.572972)
		(end 389.776462 -25.226772)
		(stroke
			(width 0.508)
			(type default)
		)
		(layer "In1.Cu")
	)
	(gr_line
		(start 389.782812 -29.083)
		(end 389.782812 -27.7368)
		(stroke
			(width 0.508)
			(type default)
		)
		(layer "In1.Cu")
	)
	(gr_line
		(start 389.795258 -13.462)
		(end 389.795258 -11.6586)
		(stroke
			(width 0.254)
			(type default)
		)
		(layer "In1.Cu")
	)
	(gr_line
		(start 389.795258 -13.462)
		(end 389.795258 -11.4808)
		(stroke
			(width 0.762)
			(type default)
		)
		(layer "In1.Cu")
	)
	(gr_line
		(start 389.795258 -11.6586)
		(end 389.896858 -11.6586)
		(stroke
			(width 0.254)
			(type default)
		)
		(layer "In1.Cu")
	)
	(gr_line
		(start 389.795258 -9.261856)
		(end 389.795258 -7.458456)
		(stroke
			(width 0.254)
			(type default)
		)
		(layer "In1.Cu")
	)
	(gr_line
		(start 389.795258 -9.261856)
		(end 389.795258 -7.280656)
		(stroke
			(width 0.762)
			(type default)
		)
		(layer "In1.Cu")
	)
	(gr_line
		(start 389.795258 -7.458456)
		(end 389.896858 -7.458456)
		(stroke
			(width 0.254)
			(type default)
		)
		(layer "In1.Cu")
	)
	(gr_line
		(start 389.808212 -29.083)
		(end 389.808212 -27.7368)
		(stroke
			(width 0.508)
			(type default)
		)
		(layer "In1.Cu")
	)
	(gr_line
		(start 389.827262 -26.598372)
		(end 389.827262 -25.252172)
		(stroke
			(width 0.508)
			(type default)
		)
		(layer "In1.Cu")
	)
	(gr_line
		(start 389.827262 -26.572972)
		(end 389.827262 -25.226772)
		(stroke
			(width 0.508)
			(type default)
		)
		(layer "In1.Cu")
	)
	(gr_line
		(start 389.833612 -29.083)
		(end 389.833612 -27.7368)
		(stroke
			(width 0.508)
			(type default)
		)
		(layer "In1.Cu")
	)
	(gr_line
		(start 389.859012 -29.1084)
		(end 389.859012 -27.7622)
		(stroke
			(width 0.508)
			(type default)
		)
		(layer "In1.Cu")
	)
	(gr_line
		(start 389.859012 -29.083)
		(end 389.859012 -27.7368)
		(stroke
			(width 0.508)
			(type default)
		)
		(layer "In1.Cu")
	)
	(gr_line
		(start 389.878062 -26.572972)
		(end 389.878062 -25.226772)
		(stroke
			(width 0.508)
			(type default)
		)
		(layer "In1.Cu")
	)
	(gr_line
		(start 389.884412 -29.1084)
		(end 389.884412 -27.7622)
		(stroke
			(width 0.508)
			(type default)
		)
		(layer "In1.Cu")
	)
	(gr_line
		(start 389.884412 -29.083)
		(end 389.884412 -27.7368)
		(stroke
			(width 0.508)
			(type default)
		)
		(layer "In1.Cu")
	)
	(gr_line
		(start 389.896858 -13.5636)
		(end 389.846058 -13.5636)
		(stroke
			(width 0.254)
			(type default)
		)
		(layer "In1.Cu")
	)
	(gr_line
		(start 389.896858 -11.6586)
		(end 389.896858 -13.5636)
		(stroke
			(width 0.254)
			(type default)
		)
		(layer "In1.Cu")
	)
	(gr_line
		(start 389.896858 -9.363456)
		(end 389.846058 -9.363456)
		(stroke
			(width 0.254)
			(type default)
		)
		(layer "In1.Cu")
	)
	(gr_line
		(start 389.896858 -7.458456)
		(end 389.896858 -9.363456)
		(stroke
			(width 0.254)
			(type default)
		)
		(layer "In1.Cu")
	)
	(gr_line
		(start 389.903462 -26.547572)
		(end 389.903462 -25.201372)
		(stroke
			(width 0.508)
			(type default)
		)
		(layer "In1.Cu")
	)
	(gr_line
		(start 389.909812 -29.1084)
		(end 389.909812 -27.7622)
		(stroke
			(width 0.508)
			(type default)
		)
		(layer "In1.Cu")
	)
	(gr_line
		(start 389.928862 -26.572972)
		(end 389.928862 -25.226772)
		(stroke
			(width 0.508)
			(type default)
		)
		(layer "In1.Cu")
	)
	(gr_line
		(start 389.935212 -29.337)
		(end 390.265412 -29.337)
		(stroke
			(width 0.1016)
			(type default)
		)
		(layer "In1.Cu")
	)
	(gr_line
		(start 389.935212 -29.083)
		(end 389.935212 -27.7368)
		(stroke
			(width 0.508)
			(type default)
		)
		(layer "In1.Cu")
	)
	(gr_line
		(start 389.947658 -13.4874)
		(end 389.947658 -11.5062)
		(stroke
			(width 0.762)
			(type default)
		)
		(layer "In1.Cu")
	)
	(gr_line
		(start 389.947658 -9.287256)
		(end 389.947658 -7.306056)
		(stroke
			(width 0.762)
			(type default)
		)
		(layer "In1.Cu")
	)
	(gr_line
		(start 389.954262 -26.572972)
		(end 389.954262 -25.226772)
		(stroke
			(width 0.508)
			(type default)
		)
		(layer "In1.Cu")
	)
	(gr_line
		(start 389.960612 -29.1084)
		(end 389.960612 -27.7622)
		(stroke
			(width 0.508)
			(type default)
		)
		(layer "In1.Cu")
	)
	(gr_line
		(start 389.960612 -29.083)
		(end 389.960612 -27.7368)
		(stroke
			(width 0.508)
			(type default)
		)
		(layer "In1.Cu")
	)
	(gr_line
		(start 389.979662 -26.572972)
		(end 389.979662 -25.226772)
		(stroke
			(width 0.508)
			(type default)
		)
		(layer "In1.Cu")
	)
	(gr_line
		(start 389.986012 -29.1084)
		(end 389.986012 -27.7622)
		(stroke
			(width 0.508)
			(type default)
		)
		(layer "In1.Cu")
	)
	(gr_line
		(start 390.023858 -13.462)
		(end 389.795258 -13.462)
		(stroke
			(width 0.254)
			(type default)
		)
		(layer "In1.Cu")
	)
	(gr_line
		(start 390.023858 -11.5062)
		(end 390.023858 -13.462)
		(stroke
			(width 0.254)
			(type default)
		)
		(layer "In1.Cu")
	)
	(gr_line
		(start 390.023858 -9.261856)
		(end 389.795258 -9.261856)
		(stroke
			(width 0.254)
			(type default)
		)
		(layer "In1.Cu")
	)
	(gr_line
		(start 390.023858 -7.306056)
		(end 390.023858 -9.261856)
		(stroke
			(width 0.254)
			(type default)
		)
		(layer "In1.Cu")
	)
	(gr_line
		(start 390.030462 -26.572972)
		(end 390.030462 -25.226772)
		(stroke
			(width 0.508)
			(type default)
		)
		(layer "In1.Cu")
	)
	(gr_line
		(start 390.055862 -26.572972)
		(end 390.055862 -25.226772)
		(stroke
			(width 0.508)
			(type default)
		)
		(layer "In1.Cu")
	)
	(gr_line
		(start 390.062212 -29.1084)
		(end 390.062212 -27.7622)
		(stroke
			(width 0.508)
			(type default)
		)
		(layer "In1.Cu")
	)
	(gr_line
		(start 390.074658 -13.8176)
		(end 390.074658 -13.7668)
		(stroke
			(width 0.1016)
			(type default)
		)
		(layer "In1.Cu")
	)
	(gr_line
		(start 390.074658 -13.8176)
		(end 390.481058 -13.8176)
		(stroke
			(width 0.1016)
			(type default)
		)
		(layer "In1.Cu")
	)
	(gr_line
		(start 390.074658 -13.7668)
		(end 389.312658 -13.7668)
		(stroke
			(width 0.1016)
			(type default)
		)
		(layer "In1.Cu")
	)
	(gr_line
		(start 390.074658 -13.4874)
		(end 390.074658 -11.5062)
		(stroke
			(width 0.762)
			(type default)
		)
		(layer "In1.Cu")
	)
	(gr_line
		(start 390.074658 -9.617456)
		(end 390.074658 -9.566656)
		(stroke
			(width 0.1016)
			(type default)
		)
		(layer "In1.Cu")
	)
	(gr_line
		(start 390.074658 -9.617456)
		(end 390.481058 -9.617456)
		(stroke
			(width 0.1016)
			(type default)
		)
		(layer "In1.Cu")
	)
	(gr_line
		(start 390.074658 -9.566656)
		(end 389.312658 -9.566656)
		(stroke
			(width 0.1016)
			(type default)
		)
		(layer "In1.Cu")
	)
	(gr_line
		(start 390.074658 -9.287256)
		(end 390.074658 -7.306056)
		(stroke
			(width 0.762)
			(type default)
		)
		(layer "In1.Cu")
	)
	(gr_line
		(start 390.081262 -26.572972)
		(end 390.081262 -25.226772)
		(stroke
			(width 0.508)
			(type default)
		)
		(layer "In1.Cu")
	)
	(gr_line
		(start 390.100058 -13.5382)
		(end 389.693658 -13.5382)
		(stroke
			(width 0.254)
			(type default)
		)
		(layer "In1.Cu")
	)
	(gr_line
		(start 390.100058 -11.43)
		(end 390.100058 -13.5382)
		(stroke
			(width 0.254)
			(type default)
		)
		(layer "In1.Cu")
	)
	(gr_line
		(start 390.100058 -9.338056)
		(end 389.693658 -9.338056)
		(stroke
			(width 0.254)
			(type default)
		)
		(layer "In1.Cu")
	)
	(gr_line
		(start 390.100058 -7.229856)
		(end 390.100058 -9.338056)
		(stroke
			(width 0.254)
			(type default)
		)
		(layer "In1.Cu")
	)
	(gr_line
		(start 390.106662 -26.572972)
		(end 390.106662 -25.226772)
		(stroke
			(width 0.508)
			(type default)
		)
		(layer "In1.Cu")
	)
	(gr_line
		(start 390.132062 -26.598372)
		(end 390.132062 -25.252172)
		(stroke
			(width 0.508)
			(type default)
		)
		(layer "In1.Cu")
	)
	(gr_line
		(start 390.150858 -13.4874)
		(end 390.150858 -11.5062)
		(stroke
			(width 0.762)
			(type default)
		)
		(layer "In1.Cu")
	)
	(gr_line
		(start 390.150858 -9.287256)
		(end 390.150858 -7.306056)
		(stroke
			(width 0.762)
			(type default)
		)
		(layer "In1.Cu")
	)
	(gr_line
		(start 390.157462 -26.598372)
		(end 390.157462 -25.252172)
		(stroke
			(width 0.508)
			(type default)
		)
		(layer "In1.Cu")
	)
	(gr_line
		(start 390.157462 -26.572972)
		(end 390.157462 -25.226772)
		(stroke
			(width 0.508)
			(type default)
		)
		(layer "In1.Cu")
	)
	(gr_line
		(start 390.163812 -29.2608)
		(end 390.163812 -27.6098)
		(stroke
			(width 0.2032)
			(type default)
		)
		(layer "In1.Cu")
	)
	(gr_line
		(start 390.163812 -29.2354)
		(end 389.147812 -29.2354)
		(stroke
			(width 0.2032)
			(type default)
		)
		(layer "In1.Cu")
	)
	(gr_line
		(start 390.163812 -29.1846)
		(end 390.163812 -29.2354)
		(stroke
			(width 0.2032)
			(type default)
		)
		(layer "In1.Cu")
	)
	(gr_line
		(start 390.163812 -27.6098)
		(end 389.224012 -27.6098)
		(stroke
			(width 0.2032)
			(type default)
		)
		(layer "In1.Cu")
	)
	(gr_line
		(start 390.176258 -13.6144)
		(end 389.617458 -13.6144)
		(stroke
			(width 0.254)
			(type default)
		)
		(layer "In1.Cu")
	)
	(gr_line
		(start 390.176258 -11.3792)
		(end 390.176258 -13.6144)
		(stroke
			(width 0.254)
			(type default)
		)
		(layer "In1.Cu")
	)
	(gr_line
		(start 390.176258 -9.414256)
		(end 389.617458 -9.414256)
		(stroke
			(width 0.254)
			(type default)
		)
		(layer "In1.Cu")
	)
	(gr_line
		(start 390.176258 -7.179056)
		(end 390.176258 -9.414256)
		(stroke
			(width 0.254)
			(type default)
		)
		(layer "In1.Cu")
	)
	(gr_line
		(start 390.182862 -26.572972)
		(end 390.182862 -25.226772)
		(stroke
			(width 0.508)
			(type default)
		)
		(layer "In1.Cu")
	)
	(gr_line
		(start 390.208262 -26.572972)
		(end 390.208262 -25.226772)
		(stroke
			(width 0.508)
			(type default)
		)
		(layer "In1.Cu")
	)
	(gr_line
		(start 390.214612 -29.2354)
		(end 389.173212 -29.2354)
		(stroke
			(width 0.2032)
			(type default)
		)
		(layer "In1.Cu")
	)
	(gr_line
		(start 390.214612 -27.559)
		(end 390.214612 -29.2354)
		(stroke
			(width 0.2032)
			(type default)
		)
		(layer "In1.Cu")
	)
	(gr_line
		(start 390.233662 -26.572972)
		(end 390.233662 -25.226772)
		(stroke
			(width 0.508)
			(type default)
		)
		(layer "In1.Cu")
	)
	(gr_line
		(start 390.252458 -13.6398)
		(end 389.541258 -13.6398)
		(stroke
			(width 0.254)
			(type default)
		)
		(layer "In1.Cu")
	)
	(gr_line
		(start 390.252458 -11.303)
		(end 390.252458 -13.6398)
		(stroke
			(width 0.254)
			(type default)
		)
		(layer "In1.Cu")
	)
	(gr_line
		(start 390.252458 -9.439656)
		(end 389.541258 -9.439656)
		(stroke
			(width 0.254)
			(type default)
		)
		(layer "In1.Cu")
	)
	(gr_line
		(start 390.252458 -7.102856)
		(end 390.252458 -9.439656)
		(stroke
			(width 0.254)
			(type default)
		)
		(layer "In1.Cu")
	)
	(gr_line
		(start 390.259062 -26.598372)
		(end 390.259062 -25.252172)
		(stroke
			(width 0.508)
			(type default)
		)
		(layer "In1.Cu")
	)
	(gr_line
		(start 390.259062 -26.572972)
		(end 390.259062 -25.226772)
		(stroke
			(width 0.508)
			(type default)
		)
		(layer "In1.Cu")
	)
	(gr_line
		(start 390.265412 -29.337)
		(end 390.265412 -27.4828)
		(stroke
			(width 0.1016)
			(type default)
		)
		(layer "In1.Cu")
	)
	(gr_line
		(start 390.265412 -27.4828)
		(end 389.097012 -27.4828)
		(stroke
			(width 0.1016)
			(type default)
		)
		(layer "In1.Cu")
	)
	(gr_line
		(start 390.277858 -13.7668)
		(end 389.287258 -13.7668)
		(stroke
			(width 0.1016)
			(type default)
		)
		(layer "In1.Cu")
	)
	(gr_line
		(start 390.277858 -13.6906)
		(end 389.465058 -13.6906)
		(stroke
			(width 0.254)
			(type default)
		)
		(layer "In1.Cu")
	)
	(gr_line
		(start 390.277858 -11.2776)
		(end 390.277858 -13.6906)
		(stroke
			(width 0.254)
			(type default)
		)
		(layer "In1.Cu")
	)
	(gr_line
		(start 390.277858 -9.566656)
		(end 389.287258 -9.566656)
		(stroke
			(width 0.1016)
			(type default)
		)
		(layer "In1.Cu")
	)
	(gr_line
		(start 390.277858 -9.490456)
		(end 389.465058 -9.490456)
		(stroke
			(width 0.254)
			(type default)
		)
		(layer "In1.Cu")
	)
	(gr_line
		(start 390.277858 -7.077456)
		(end 390.277858 -9.490456)
		(stroke
			(width 0.254)
			(type default)
		)
		(layer "In1.Cu")
	)
	(gr_line
		(start 390.284462 -26.598372)
		(end 390.284462 -25.252172)
		(stroke
			(width 0.508)
			(type default)
		)
		(layer "In1.Cu")
	)
	(gr_line
		(start 390.284462 -26.572972)
		(end 390.284462 -25.226772)
		(stroke
			(width 0.508)
			(type default)
		)
		(layer "In1.Cu")
	)
	(gr_line
		(start 390.303258 -13.716)
		(end 389.439658 -13.716)
		(stroke
			(width 0.254)
			(type default)
		)
		(layer "In1.Cu")
	)
	(gr_line
		(start 390.303258 -11.2522)
		(end 390.303258 -13.716)
		(stroke
			(width 0.254)
			(type default)
		)
		(layer "In1.Cu")
	)
	(gr_line
		(start 390.303258 -9.515856)
		(end 389.439658 -9.515856)
		(stroke
			(width 0.254)
			(type default)
		)
		(layer "In1.Cu")
	)
	(gr_line
		(start 390.303258 -7.052056)
		(end 390.303258 -9.515856)
		(stroke
			(width 0.254)
			(type default)
		)
		(layer "In1.Cu")
	)
	(gr_line
		(start 390.309862 -26.598372)
		(end 390.309862 -25.252172)
		(stroke
			(width 0.508)
			(type default)
		)
		(layer "In1.Cu")
	)
	(gr_line
		(start 390.319768 -30.734)
		(end 389.049768 -30.734)
		(stroke
			(width 0.7874)
			(type default)
		)
		(layer "In1.Cu")
	)
	(gr_line
		(start 390.335262 -26.826972)
		(end 390.665462 -26.826972)
		(stroke
			(width 0.1016)
			(type default)
		)
		(layer "In1.Cu")
	)
	(gr_line
		(start 390.335262 -26.572972)
		(end 390.335262 -25.226772)
		(stroke
			(width 0.508)
			(type default)
		)
		(layer "In1.Cu")
	)
	(gr_line
		(start 390.354058 -13.7414)
		(end 389.414258 -13.7414)
		(stroke
			(width 0.254)
			(type default)
		)
		(layer "In1.Cu")
	)
	(gr_line
		(start 390.354058 -11.2522)
		(end 390.354058 -13.7414)
		(stroke
			(width 0.254)
			(type default)
		)
		(layer "In1.Cu")
	)
	(gr_line
		(start 390.354058 -9.541256)
		(end 389.414258 -9.541256)
		(stroke
			(width 0.254)
			(type default)
		)
		(layer "In1.Cu")
	)
	(gr_line
		(start 390.354058 -7.052056)
		(end 390.354058 -9.541256)
		(stroke
			(width 0.254)
			(type default)
		)
		(layer "In1.Cu")
	)
	(gr_line
		(start 390.360662 -26.598372)
		(end 390.360662 -25.252172)
		(stroke
			(width 0.508)
			(type default)
		)
		(layer "In1.Cu")
	)
	(gr_line
		(start 390.360662 -26.572972)
		(end 390.360662 -25.226772)
		(stroke
			(width 0.508)
			(type default)
		)
		(layer "In1.Cu")
	)
	(gr_line
		(start 390.379458 -13.7414)
		(end 389.414258 -13.7414)
		(stroke
			(width 0.2032)
			(type default)
		)
		(layer "In1.Cu")
	)
	(gr_line
		(start 390.379458 -11.2014)
		(end 390.379458 -13.7414)
		(stroke
			(width 0.2032)
			(type default)
		)
		(layer "In1.Cu")
	)
	(gr_line
		(start 390.379458 -9.541256)
		(end 389.414258 -9.541256)
		(stroke
			(width 0.2032)
			(type default)
		)
		(layer "In1.Cu")
	)
	(gr_line
		(start 390.379458 -7.001256)
		(end 390.379458 -9.541256)
		(stroke
			(width 0.2032)
			(type default)
		)
		(layer "In1.Cu")
	)
	(gr_line
		(start 390.386062 -26.598372)
		(end 390.386062 -25.252172)
		(stroke
			(width 0.508)
			(type default)
		)
		(layer "In1.Cu")
	)
	(gr_line
		(start 390.430258 -13.7668)
		(end 389.363458 -13.7668)
		(stroke
			(width 0.2032)
			(type default)
		)
		(layer "In1.Cu")
	)
	(gr_line
		(start 390.430258 -11.2014)
		(end 390.430258 -13.7668)
		(stroke
			(width 0.2032)
			(type default)
		)
		(layer "In1.Cu")
	)
	(gr_line
		(start 390.430258 -9.566656)
		(end 389.363458 -9.566656)
		(stroke
			(width 0.2032)
			(type default)
		)
		(layer "In1.Cu")
	)
	(gr_line
		(start 390.430258 -7.001256)
		(end 390.430258 -9.566656)
		(stroke
			(width 0.2032)
			(type default)
		)
		(layer "In1.Cu")
	)
	(gr_line
		(start 390.455658 -13.7668)
		(end 389.338058 -13.7668)
		(stroke
			(width 0.1016)
			(type default)
		)
		(layer "In1.Cu")
	)
	(gr_line
		(start 390.455658 -11.176)
		(end 390.455658 -13.7668)
		(stroke
			(width 0.1016)
			(type default)
		)
		(layer "In1.Cu")
	)
	(gr_line
		(start 390.455658 -9.566656)
		(end 389.338058 -9.566656)
		(stroke
			(width 0.1016)
			(type default)
		)
		(layer "In1.Cu")
	)
	(gr_line
		(start 390.455658 -6.975856)
		(end 390.455658 -9.566656)
		(stroke
			(width 0.1016)
			(type default)
		)
		(layer "In1.Cu")
	)
	(gr_line
		(start 390.462262 -26.598372)
		(end 390.462262 -25.252172)
		(stroke
			(width 0.508)
			(type default)
		)
		(layer "In1.Cu")
	)
	(gr_line
		(start 390.481058 -13.8176)
		(end 390.074658 -13.8176)
		(stroke
			(width 0.1016)
			(type default)
		)
		(layer "In1.Cu")
	)
	(gr_line
		(start 390.481058 -13.8176)
		(end 390.481058 -11.1506)
		(stroke
			(width 0.1016)
			(type default)
		)
		(layer "In1.Cu")
	)
	(gr_line
		(start 390.481058 -11.1506)
		(end 389.287258 -11.1506)
		(stroke
			(width 0.1016)
			(type default)
		)
		(layer "In1.Cu")
	)
	(gr_line
		(start 390.481058 -11.1506)
		(end 390.481058 -13.8176)
		(stroke
			(width 0.1016)
			(type default)
		)
		(layer "In1.Cu")
	)
	(gr_line
		(start 390.481058 -9.617456)
		(end 390.074658 -9.617456)
		(stroke
			(width 0.1016)
			(type default)
		)
		(layer "In1.Cu")
	)
	(gr_line
		(start 390.481058 -9.617456)
		(end 390.481058 -6.950456)
		(stroke
			(width 0.1016)
			(type default)
		)
		(layer "In1.Cu")
	)
	(gr_line
		(start 390.481058 -6.950456)
		(end 389.287258 -6.950456)
		(stroke
			(width 0.1016)
			(type default)
		)
		(layer "In1.Cu")
	)
	(gr_line
		(start 390.481058 -6.950456)
		(end 390.481058 -9.617456)
		(stroke
			(width 0.1016)
			(type default)
		)
		(layer "In1.Cu")
	)
	(gr_line
		(start 390.563862 -26.750772)
		(end 390.563862 -25.099772)
		(stroke
			(width 0.2032)
			(type default)
		)
		(layer "In1.Cu")
	)
	(gr_line
		(start 390.563862 -26.725372)
		(end 389.547862 -26.725372)
		(stroke
			(width 0.2032)
			(type default)
		)
		(layer "In1.Cu")
	)
	(gr_line
		(start 390.563862 -26.674572)
		(end 390.563862 -26.725372)
		(stroke
			(width 0.2032)
			(type default)
		)
		(layer "In1.Cu")
	)
	(gr_line
		(start 390.563862 -25.099772)
		(end 389.624062 -25.099772)
		(stroke
			(width 0.2032)
			(type default)
		)
		(layer "In1.Cu")
	)
	(gr_line
		(start 390.614662 -26.725372)
		(end 389.573262 -26.725372)
		(stroke
			(width 0.2032)
			(type default)
		)
		(layer "In1.Cu")
	)
	(gr_line
		(start 390.614662 -25.048972)
		(end 390.614662 -26.725372)
		(stroke
			(width 0.2032)
			(type default)
		)
		(layer "In1.Cu")
	)
	(gr_line
		(start 390.665462 -26.826972)
		(end 390.665462 -24.972772)
		(stroke
			(width 0.1016)
			(type default)
		)
		(layer "In1.Cu")
	)
	(gr_line
		(start 390.665462 -24.972772)
		(end 389.497062 -24.972772)
		(stroke
			(width 0.1016)
			(type default)
		)
		(layer "In1.Cu")
	)
	(gr_line
		(start 391.287254 -12.563348)
		(end 392.074654 -12.563348)
		(stroke
			(width 0.1016)
			(type default)
		)
		(layer "In1.Cu")
	)
	(gr_line
		(start 391.287254 -12.512548)
		(end 391.287254 -9.896348)
		(stroke
			(width 0.1016)
			(type default)
		)
		(layer "In1.Cu")
	)
	(gr_line
		(start 391.287254 -12.463272)
		(end 392.074654 -12.463272)
		(stroke
			(width 0.1016)
			(type default)
		)
		(layer "In1.Cu")
	)
	(gr_line
		(start 391.287254 -12.412472)
		(end 391.287254 -9.796272)
		(stroke
			(width 0.1016)
			(type default)
		)
		(layer "In1.Cu")
	)
	(gr_line
		(start 391.287254 -9.896348)
		(end 391.287254 -12.563348)
		(stroke
			(width 0.1016)
			(type default)
		)
		(layer "In1.Cu")
	)
	(gr_line
		(start 391.287254 -9.896348)
		(end 392.481054 -9.896348)
		(stroke
			(width 0.1016)
			(type default)
		)
		(layer "In1.Cu")
	)
	(gr_line
		(start 391.287254 -9.796272)
		(end 391.287254 -12.463272)
		(stroke
			(width 0.1016)
			(type default)
		)
		(layer "In1.Cu")
	)
	(gr_line
		(start 391.287254 -9.796272)
		(end 392.481054 -9.796272)
		(stroke
			(width 0.1016)
			(type default)
		)
		(layer "In1.Cu")
	)
	(gr_line
		(start 391.287254 -8.363204)
		(end 392.074654 -8.363204)
		(stroke
			(width 0.1016)
			(type default)
		)
		(layer "In1.Cu")
	)
	(gr_line
		(start 391.287254 -8.312404)
		(end 391.287254 -5.696204)
		(stroke
			(width 0.1016)
			(type default)
		)
		(layer "In1.Cu")
	)
	(gr_line
		(start 391.287254 -8.263128)
		(end 392.074654 -8.263128)
		(stroke
			(width 0.1016)
			(type default)
		)
		(layer "In1.Cu")
	)
	(gr_line
		(start 391.287254 -8.212328)
		(end 391.287254 -5.596128)
		(stroke
			(width 0.1016)
			(type default)
		)
		(layer "In1.Cu")
	)
	(gr_line
		(start 391.287254 -5.696204)
		(end 391.287254 -8.363204)
		(stroke
			(width 0.1016)
			(type default)
		)
		(layer "In1.Cu")
	)
	(gr_line
		(start 391.287254 -5.696204)
		(end 392.481054 -5.696204)
		(stroke
			(width 0.1016)
			(type default)
		)
		(layer "In1.Cu")
	)
	(gr_line
		(start 391.287254 -5.596128)
		(end 391.287254 -8.263128)
		(stroke
			(width 0.1016)
			(type default)
		)
		(layer "In1.Cu")
	)
	(gr_line
		(start 391.287254 -5.596128)
		(end 392.481054 -5.596128)
		(stroke
			(width 0.1016)
			(type default)
		)
		(layer "In1.Cu")
	)
	(gr_line
		(start 391.312654 -12.512548)
		(end 391.312654 -9.921748)
		(stroke
			(width 0.1016)
			(type default)
		)
		(layer "In1.Cu")
	)
	(gr_line
		(start 391.312654 -12.412472)
		(end 391.312654 -9.821672)
		(stroke
			(width 0.1016)
			(type default)
		)
		(layer "In1.Cu")
	)
	(gr_line
		(start 391.312654 -9.921748)
		(end 392.455654 -9.921748)
		(stroke
			(width 0.1016)
			(type default)
		)
		(layer "In1.Cu")
	)
	(gr_line
		(start 391.312654 -9.821672)
		(end 392.455654 -9.821672)
		(stroke
			(width 0.1016)
			(type default)
		)
		(layer "In1.Cu")
	)
	(gr_line
		(start 391.312654 -8.312404)
		(end 391.312654 -5.721604)
		(stroke
			(width 0.1016)
			(type default)
		)
		(layer "In1.Cu")
	)
	(gr_line
		(start 391.312654 -8.212328)
		(end 391.312654 -5.621528)
		(stroke
			(width 0.1016)
			(type default)
		)
		(layer "In1.Cu")
	)
	(gr_line
		(start 391.312654 -5.721604)
		(end 392.455654 -5.721604)
		(stroke
			(width 0.1016)
			(type default)
		)
		(layer "In1.Cu")
	)
	(gr_line
		(start 391.312654 -5.621528)
		(end 392.455654 -5.621528)
		(stroke
			(width 0.1016)
			(type default)
		)
		(layer "In1.Cu")
	)
	(gr_line
		(start 391.338054 -12.512548)
		(end 391.338054 -9.947148)
		(stroke
			(width 0.1016)
			(type default)
		)
		(layer "In1.Cu")
	)
	(gr_line
		(start 391.338054 -12.412472)
		(end 391.338054 -9.847072)
		(stroke
			(width 0.1016)
			(type default)
		)
		(layer "In1.Cu")
	)
	(gr_line
		(start 391.338054 -9.947148)
		(end 391.592054 -9.947148)
		(stroke
			(width 0.1016)
			(type default)
		)
		(layer "In1.Cu")
	)
	(gr_line
		(start 391.338054 -9.847072)
		(end 391.592054 -9.847072)
		(stroke
			(width 0.1016)
			(type default)
		)
		(layer "In1.Cu")
	)
	(gr_line
		(start 391.338054 -8.312404)
		(end 391.338054 -5.747004)
		(stroke
			(width 0.1016)
			(type default)
		)
		(layer "In1.Cu")
	)
	(gr_line
		(start 391.338054 -8.212328)
		(end 391.338054 -5.646928)
		(stroke
			(width 0.1016)
			(type default)
		)
		(layer "In1.Cu")
	)
	(gr_line
		(start 391.338054 -5.747004)
		(end 391.592054 -5.747004)
		(stroke
			(width 0.1016)
			(type default)
		)
		(layer "In1.Cu")
	)
	(gr_line
		(start 391.338054 -5.646928)
		(end 391.592054 -5.646928)
		(stroke
			(width 0.1016)
			(type default)
		)
		(layer "In1.Cu")
	)
	(gr_line
		(start 391.363454 -12.512548)
		(end 391.363454 -9.947148)
		(stroke
			(width 0.2032)
			(type default)
		)
		(layer "In1.Cu")
	)
	(gr_line
		(start 391.363454 -12.412472)
		(end 391.363454 -9.847072)
		(stroke
			(width 0.2032)
			(type default)
		)
		(layer "In1.Cu")
	)
	(gr_line
		(start 391.363454 -9.947148)
		(end 392.379454 -9.947148)
		(stroke
			(width 0.2032)
			(type default)
		)
		(layer "In1.Cu")
	)
	(gr_line
		(start 391.363454 -9.847072)
		(end 392.379454 -9.847072)
		(stroke
			(width 0.2032)
			(type default)
		)
		(layer "In1.Cu")
	)
	(gr_line
		(start 391.363454 -8.312404)
		(end 391.363454 -5.747004)
		(stroke
			(width 0.2032)
			(type default)
		)
		(layer "In1.Cu")
	)
	(gr_line
		(start 391.363454 -8.212328)
		(end 391.363454 -5.646928)
		(stroke
			(width 0.2032)
			(type default)
		)
		(layer "In1.Cu")
	)
	(gr_line
		(start 391.363454 -5.747004)
		(end 392.379454 -5.747004)
		(stroke
			(width 0.2032)
			(type default)
		)
		(layer "In1.Cu")
	)
	(gr_line
		(start 391.363454 -5.646928)
		(end 392.379454 -5.646928)
		(stroke
			(width 0.2032)
			(type default)
		)
		(layer "In1.Cu")
	)
	(gr_line
		(start 391.414254 -12.487148)
		(end 391.414254 -9.997948)
		(stroke
			(width 0.2032)
			(type default)
		)
		(layer "In1.Cu")
	)
	(gr_line
		(start 391.414254 -12.487148)
		(end 391.414254 -9.997948)
		(stroke
			(width 0.254)
			(type default)
		)
		(layer "In1.Cu")
	)
	(gr_line
		(start 391.414254 -12.387072)
		(end 391.414254 -9.897872)
		(stroke
			(width 0.2032)
			(type default)
		)
		(layer "In1.Cu")
	)
	(gr_line
		(start 391.414254 -12.387072)
		(end 391.414254 -9.897872)
		(stroke
			(width 0.254)
			(type default)
		)
		(layer "In1.Cu")
	)
	(gr_line
		(start 391.414254 -9.997948)
		(end 391.617454 -9.997948)
		(stroke
			(width 0.2032)
			(type default)
		)
		(layer "In1.Cu")
	)
	(gr_line
		(start 391.414254 -9.997948)
		(end 392.303254 -9.997948)
		(stroke
			(width 0.254)
			(type default)
		)
		(layer "In1.Cu")
	)
	(gr_line
		(start 391.414254 -9.897872)
		(end 391.617454 -9.897872)
		(stroke
			(width 0.2032)
			(type default)
		)
		(layer "In1.Cu")
	)
	(gr_line
		(start 391.414254 -9.897872)
		(end 392.303254 -9.897872)
		(stroke
			(width 0.254)
			(type default)
		)
		(layer "In1.Cu")
	)
	(gr_line
		(start 391.414254 -8.287004)
		(end 391.414254 -5.797804)
		(stroke
			(width 0.2032)
			(type default)
		)
		(layer "In1.Cu")
	)
	(gr_line
		(start 391.414254 -8.287004)
		(end 391.414254 -5.797804)
		(stroke
			(width 0.254)
			(type default)
		)
		(layer "In1.Cu")
	)
	(gr_line
		(start 391.414254 -8.186928)
		(end 391.414254 -5.697728)
		(stroke
			(width 0.2032)
			(type default)
		)
		(layer "In1.Cu")
	)
	(gr_line
		(start 391.414254 -8.186928)
		(end 391.414254 -5.697728)
		(stroke
			(width 0.254)
			(type default)
		)
		(layer "In1.Cu")
	)
	(gr_line
		(start 391.414254 -5.797804)
		(end 391.617454 -5.797804)
		(stroke
			(width 0.2032)
			(type default)
		)
		(layer "In1.Cu")
	)
	(gr_line
		(start 391.414254 -5.797804)
		(end 392.303254 -5.797804)
		(stroke
			(width 0.254)
			(type default)
		)
		(layer "In1.Cu")
	)
	(gr_line
		(start 391.414254 -5.697728)
		(end 391.617454 -5.697728)
		(stroke
			(width 0.2032)
			(type default)
		)
		(layer "In1.Cu")
	)
	(gr_line
		(start 391.414254 -5.697728)
		(end 392.303254 -5.697728)
		(stroke
			(width 0.254)
			(type default)
		)
		(layer "In1.Cu")
	)
	(gr_line
		(start 391.439654 -12.461748)
		(end 391.439654 -10.023348)
		(stroke
			(width 0.254)
			(type default)
		)
		(layer "In1.Cu")
	)
	(gr_line
		(start 391.439654 -12.361672)
		(end 391.439654 -9.923272)
		(stroke
			(width 0.254)
			(type default)
		)
		(layer "In1.Cu")
	)
	(gr_line
		(start 391.439654 -10.023348)
		(end 392.277854 -10.023348)
		(stroke
			(width 0.254)
			(type default)
		)
		(layer "In1.Cu")
	)
	(gr_line
		(start 391.439654 -9.923272)
		(end 392.277854 -9.923272)
		(stroke
			(width 0.254)
			(type default)
		)
		(layer "In1.Cu")
	)
	(gr_line
		(start 391.439654 -8.261604)
		(end 391.439654 -5.823204)
		(stroke
			(width 0.254)
			(type default)
		)
		(layer "In1.Cu")
	)
	(gr_line
		(start 391.439654 -8.161528)
		(end 391.439654 -5.723128)
		(stroke
			(width 0.254)
			(type default)
		)
		(layer "In1.Cu")
	)
	(gr_line
		(start 391.439654 -5.823204)
		(end 392.277854 -5.823204)
		(stroke
			(width 0.254)
			(type default)
		)
		(layer "In1.Cu")
	)
	(gr_line
		(start 391.439654 -5.723128)
		(end 392.277854 -5.723128)
		(stroke
			(width 0.254)
			(type default)
		)
		(layer "In1.Cu")
	)
	(gr_line
		(start 391.465054 -12.436348)
		(end 391.465054 -10.048748)
		(stroke
			(width 0.254)
			(type default)
		)
		(layer "In1.Cu")
	)
	(gr_line
		(start 391.465054 -12.336272)
		(end 391.465054 -9.948672)
		(stroke
			(width 0.254)
			(type default)
		)
		(layer "In1.Cu")
	)
	(gr_line
		(start 391.465054 -10.048748)
		(end 392.252454 -10.048748)
		(stroke
			(width 0.254)
			(type default)
		)
		(layer "In1.Cu")
	)
	(gr_line
		(start 391.465054 -9.948672)
		(end 392.252454 -9.948672)
		(stroke
			(width 0.254)
			(type default)
		)
		(layer "In1.Cu")
	)
	(gr_line
		(start 391.465054 -8.236204)
		(end 391.465054 -5.848604)
		(stroke
			(width 0.254)
			(type default)
		)
		(layer "In1.Cu")
	)
	(gr_line
		(start 391.465054 -8.136128)
		(end 391.465054 -5.748528)
		(stroke
			(width 0.254)
			(type default)
		)
		(layer "In1.Cu")
	)
	(gr_line
		(start 391.465054 -5.848604)
		(end 392.252454 -5.848604)
		(stroke
			(width 0.254)
			(type default)
		)
		(layer "In1.Cu")
	)
	(gr_line
		(start 391.465054 -5.748528)
		(end 392.252454 -5.748528)
		(stroke
			(width 0.254)
			(type default)
		)
		(layer "In1.Cu")
	)
	(gr_line
		(start 391.490454 -12.360148)
		(end 392.125454 -12.360148)
		(stroke
			(width 0.508)
			(type default)
		)
		(layer "In1.Cu")
	)
	(gr_line
		(start 391.490454 -12.260072)
		(end 392.125454 -12.260072)
		(stroke
			(width 0.508)
			(type default)
		)
		(layer "In1.Cu")
	)
	(gr_line
		(start 391.490454 -10.175748)
		(end 392.125454 -10.175748)
		(stroke
			(width 0.508)
			(type default)
		)
		(layer "In1.Cu")
	)
	(gr_line
		(start 391.490454 -10.124948)
		(end 392.125454 -10.124948)
		(stroke
			(width 0.508)
			(type default)
		)
		(layer "In1.Cu")
	)
	(gr_line
		(start 391.490454 -10.075672)
		(end 392.125454 -10.075672)
		(stroke
			(width 0.508)
			(type default)
		)
		(layer "In1.Cu")
	)
	(gr_line
		(start 391.490454 -10.024872)
		(end 392.125454 -10.024872)
		(stroke
			(width 0.508)
			(type default)
		)
		(layer "In1.Cu")
	)
	(gr_line
		(start 391.490454 -8.160004)
		(end 392.125454 -8.160004)
		(stroke
			(width 0.508)
			(type default)
		)
		(layer "In1.Cu")
	)
	(gr_line
		(start 391.490454 -8.059928)
		(end 392.125454 -8.059928)
		(stroke
			(width 0.508)
			(type default)
		)
		(layer "In1.Cu")
	)
	(gr_line
		(start 391.490454 -5.975604)
		(end 392.125454 -5.975604)
		(stroke
			(width 0.508)
			(type default)
		)
		(layer "In1.Cu")
	)
	(gr_line
		(start 391.490454 -5.924804)
		(end 392.125454 -5.924804)
		(stroke
			(width 0.508)
			(type default)
		)
		(layer "In1.Cu")
	)
	(gr_line
		(start 391.490454 -5.875528)
		(end 392.125454 -5.875528)
		(stroke
			(width 0.508)
			(type default)
		)
		(layer "In1.Cu")
	)
	(gr_line
		(start 391.490454 -5.824728)
		(end 392.125454 -5.824728)
		(stroke
			(width 0.508)
			(type default)
		)
		(layer "In1.Cu")
	)
	(gr_line
		(start 391.497058 -29.337)
		(end 392.335258 -29.337)
		(stroke
			(width 0.1016)
			(type default)
		)
		(layer "In1.Cu")
	)
	(gr_line
		(start 391.497058 -27.4828)
		(end 391.497058 -29.337)
		(stroke
			(width 0.1016)
			(type default)
		)
		(layer "In1.Cu")
	)
	(gr_line
		(start 391.515854 -10.429748)
		(end 392.150854 -10.429748)
		(stroke
			(width 0.508)
			(type default)
		)
		(layer "In1.Cu")
	)
	(gr_line
		(start 391.515854 -10.329672)
		(end 392.150854 -10.329672)
		(stroke
			(width 0.508)
			(type default)
		)
		(layer "In1.Cu")
	)
	(gr_line
		(start 391.515854 -6.229604)
		(end 392.150854 -6.229604)
		(stroke
			(width 0.508)
			(type default)
		)
		(layer "In1.Cu")
	)
	(gr_line
		(start 391.515854 -6.129528)
		(end 392.150854 -6.129528)
		(stroke
			(width 0.508)
			(type default)
		)
		(layer "In1.Cu")
	)
	(gr_line
		(start 391.541254 -12.385548)
		(end 391.541254 -10.124948)
		(stroke
			(width 0.254)
			(type default)
		)
		(layer "In1.Cu")
	)
	(gr_line
		(start 391.541254 -12.285472)
		(end 391.541254 -10.024872)
		(stroke
			(width 0.254)
			(type default)
		)
		(layer "In1.Cu")
	)
	(gr_line
		(start 391.541254 -12.233148)
		(end 392.176254 -12.233148)
		(stroke
			(width 0.508)
			(type default)
		)
		(layer "In1.Cu")
	)
	(gr_line
		(start 391.541254 -12.133072)
		(end 392.176254 -12.133072)
		(stroke
			(width 0.508)
			(type default)
		)
		(layer "In1.Cu")
	)
	(gr_line
		(start 391.541254 -10.124948)
		(end 392.176254 -10.124948)
		(stroke
			(width 0.254)
			(type default)
		)
		(layer "In1.Cu")
	)
	(gr_line
		(start 391.541254 -10.024872)
		(end 392.176254 -10.024872)
		(stroke
			(width 0.254)
			(type default)
		)
		(layer "In1.Cu")
	)
	(gr_line
		(start 391.541254 -8.185404)
		(end 391.541254 -5.924804)
		(stroke
			(width 0.254)
			(type default)
		)
		(layer "In1.Cu")
	)
	(gr_line
		(start 391.541254 -8.085328)
		(end 391.541254 -5.824728)
		(stroke
			(width 0.254)
			(type default)
		)
		(layer "In1.Cu")
	)
	(gr_line
		(start 391.541254 -8.033004)
		(end 392.176254 -8.033004)
		(stroke
			(width 0.508)
			(type default)
		)
		(layer "In1.Cu")
	)
	(gr_line
		(start 391.541254 -7.932928)
		(end 392.176254 -7.932928)
		(stroke
			(width 0.508)
			(type default)
		)
		(layer "In1.Cu")
	)
	(gr_line
		(start 391.541254 -5.924804)
		(end 392.176254 -5.924804)
		(stroke
			(width 0.254)
			(type default)
		)
		(layer "In1.Cu")
	)
	(gr_line
		(start 391.541254 -5.824728)
		(end 392.176254 -5.824728)
		(stroke
			(width 0.254)
			(type default)
		)
		(layer "In1.Cu")
	)
	(gr_line
		(start 391.547858 -29.2354)
		(end 391.547858 -27.559)
		(stroke
			(width 0.2032)
			(type default)
		)
		(layer "In1.Cu")
	)
	(gr_line
		(start 391.547858 -27.559)
		(end 392.614658 -27.559)
		(stroke
			(width 0.2032)
			(type default)
		)
		(layer "In1.Cu")
	)
	(gr_line
		(start 391.566654 -12.080748)
		(end 392.201654 -12.080748)
		(stroke
			(width 0.508)
			(type default)
		)
		(layer "In1.Cu")
	)
	(gr_line
		(start 391.566654 -11.980672)
		(end 392.201654 -11.980672)
		(stroke
			(width 0.508)
			(type default)
		)
		(layer "In1.Cu")
	)
	(gr_line
		(start 391.566654 -7.880604)
		(end 392.201654 -7.880604)
		(stroke
			(width 0.508)
			(type default)
		)
		(layer "In1.Cu")
	)
	(gr_line
		(start 391.566654 -7.780528)
		(end 392.201654 -7.780528)
		(stroke
			(width 0.508)
			(type default)
		)
		(layer "In1.Cu")
	)
	(gr_line
		(start 391.573258 -29.2608)
		(end 392.563858 -29.2608)
		(stroke
			(width 0.2032)
			(type default)
		)
		(layer "In1.Cu")
	)
	(gr_line
		(start 391.573258 -29.2354)
		(end 391.573258 -29.2608)
		(stroke
			(width 0.2032)
			(type default)
		)
		(layer "In1.Cu")
	)
	(gr_line
		(start 391.592054 -12.360148)
		(end 392.227054 -12.360148)
		(stroke
			(width 0.508)
			(type default)
		)
		(layer "In1.Cu")
	)
	(gr_line
		(start 391.592054 -12.260072)
		(end 392.227054 -12.260072)
		(stroke
			(width 0.508)
			(type default)
		)
		(layer "In1.Cu")
	)
	(gr_line
		(start 391.592054 -9.947148)
		(end 392.430254 -9.947148)
		(stroke
			(width 0.2032)
			(type default)
		)
		(layer "In1.Cu")
	)
	(gr_line
		(start 391.592054 -9.847072)
		(end 392.430254 -9.847072)
		(stroke
			(width 0.2032)
			(type default)
		)
		(layer "In1.Cu")
	)
	(gr_line
		(start 391.592054 -8.160004)
		(end 392.227054 -8.160004)
		(stroke
			(width 0.508)
			(type default)
		)
		(layer "In1.Cu")
	)
	(gr_line
		(start 391.592054 -8.059928)
		(end 392.227054 -8.059928)
		(stroke
			(width 0.508)
			(type default)
		)
		(layer "In1.Cu")
	)
	(gr_line
		(start 391.592054 -5.747004)
		(end 392.430254 -5.747004)
		(stroke
			(width 0.2032)
			(type default)
		)
		(layer "In1.Cu")
	)
	(gr_line
		(start 391.592054 -5.646928)
		(end 392.430254 -5.646928)
		(stroke
			(width 0.2032)
			(type default)
		)
		(layer "In1.Cu")
	)
	(gr_line
		(start 391.617454 -12.360148)
		(end 391.617454 -10.175748)
		(stroke
			(width 0.254)
			(type default)
		)
		(layer "In1.Cu")
	)
	(gr_line
		(start 391.617454 -12.260072)
		(end 391.617454 -10.075672)
		(stroke
			(width 0.254)
			(type default)
		)
		(layer "In1.Cu")
	)
	(gr_line
		(start 391.617454 -10.175748)
		(end 392.100054 -10.175748)
		(stroke
			(width 0.254)
			(type default)
		)
		(layer "In1.Cu")
	)
	(gr_line
		(start 391.617454 -10.075672)
		(end 392.100054 -10.075672)
		(stroke
			(width 0.254)
			(type default)
		)
		(layer "In1.Cu")
	)
	(gr_line
		(start 391.617454 -9.997948)
		(end 392.354054 -9.997948)
		(stroke
			(width 0.254)
			(type default)
		)
		(layer "In1.Cu")
	)
	(gr_line
		(start 391.617454 -9.897872)
		(end 392.354054 -9.897872)
		(stroke
			(width 0.254)
			(type default)
		)
		(layer "In1.Cu")
	)
	(gr_line
		(start 391.617454 -8.160004)
		(end 391.617454 -5.975604)
		(stroke
			(width 0.254)
			(type default)
		)
		(layer "In1.Cu")
	)
	(gr_line
		(start 391.617454 -8.059928)
		(end 391.617454 -5.875528)
		(stroke
			(width 0.254)
			(type default)
		)
		(layer "In1.Cu")
	)
	(gr_line
		(start 391.617454 -5.975604)
		(end 392.100054 -5.975604)
		(stroke
			(width 0.254)
			(type default)
		)
		(layer "In1.Cu")
	)
	(gr_line
		(start 391.617454 -5.875528)
		(end 392.100054 -5.875528)
		(stroke
			(width 0.254)
			(type default)
		)
		(layer "In1.Cu")
	)
	(gr_line
		(start 391.617454 -5.797804)
		(end 392.354054 -5.797804)
		(stroke
			(width 0.254)
			(type default)
		)
		(layer "In1.Cu")
	)
	(gr_line
		(start 391.617454 -5.697728)
		(end 392.354054 -5.697728)
		(stroke
			(width 0.254)
			(type default)
		)
		(layer "In1.Cu")
	)
	(gr_line
		(start 391.624058 -29.1846)
		(end 392.563858 -29.1846)
		(stroke
			(width 0.2032)
			(type default)
		)
		(layer "In1.Cu")
	)
	(gr_line
		(start 391.624058 -27.6098)
		(end 391.624058 -29.1846)
		(stroke
			(width 0.2032)
			(type default)
		)
		(layer "In1.Cu")
	)
	(gr_line
		(start 391.635996 -10.110978)
		(end 392.270996 -10.110978)
		(stroke
			(width 0.508)
			(type default)
		)
		(layer "In1.Cu")
	)
	(gr_line
		(start 391.635996 -10.010902)
		(end 392.270996 -10.010902)
		(stroke
			(width 0.508)
			(type default)
		)
		(layer "In1.Cu")
	)
	(gr_line
		(start 391.635996 -5.910834)
		(end 392.270996 -5.910834)
		(stroke
			(width 0.508)
			(type default)
		)
		(layer "In1.Cu")
	)
	(gr_line
		(start 391.635996 -5.810758)
		(end 392.270996 -5.810758)
		(stroke
			(width 0.508)
			(type default)
		)
		(layer "In1.Cu")
	)
	(gr_line
		(start 391.642854 -12.360148)
		(end 392.277854 -12.360148)
		(stroke
			(width 0.508)
			(type default)
		)
		(layer "In1.Cu")
	)
	(gr_line
		(start 391.642854 -12.260072)
		(end 392.277854 -12.260072)
		(stroke
			(width 0.508)
			(type default)
		)
		(layer "In1.Cu")
	)
	(gr_line
		(start 391.642854 -12.233148)
		(end 391.642854 -10.251948)
		(stroke
			(width 0.762)
			(type default)
		)
		(layer "In1.Cu")
	)
	(gr_line
		(start 391.642854 -12.133072)
		(end 391.642854 -10.151872)
		(stroke
			(width 0.762)
			(type default)
		)
		(layer "In1.Cu")
	)
	(gr_line
		(start 391.642854 -10.251948)
		(end 392.277854 -10.251948)
		(stroke
			(width 0.508)
			(type default)
		)
		(layer "In1.Cu")
	)
	(gr_line
		(start 391.642854 -10.151872)
		(end 392.277854 -10.151872)
		(stroke
			(width 0.508)
			(type default)
		)
		(layer "In1.Cu")
	)
	(gr_line
		(start 391.642854 -8.160004)
		(end 392.277854 -8.160004)
		(stroke
			(width 0.508)
			(type default)
		)
		(layer "In1.Cu")
	)
	(gr_line
		(start 391.642854 -8.059928)
		(end 392.277854 -8.059928)
		(stroke
			(width 0.508)
			(type default)
		)
		(layer "In1.Cu")
	)
	(gr_line
		(start 391.642854 -8.033004)
		(end 391.642854 -6.051804)
		(stroke
			(width 0.762)
			(type default)
		)
		(layer "In1.Cu")
	)
	(gr_line
		(start 391.642854 -7.932928)
		(end 391.642854 -5.951728)
		(stroke
			(width 0.762)
			(type default)
		)
		(layer "In1.Cu")
	)
	(gr_line
		(start 391.642854 -6.051804)
		(end 392.277854 -6.051804)
		(stroke
			(width 0.508)
			(type default)
		)
		(layer "In1.Cu")
	)
	(gr_line
		(start 391.642854 -5.951728)
		(end 392.277854 -5.951728)
		(stroke
			(width 0.508)
			(type default)
		)
		(layer "In1.Cu")
	)
	(gr_line
		(start 391.693654 -12.283948)
		(end 391.693654 -10.251948)
		(stroke
			(width 0.254)
			(type default)
		)
		(layer "In1.Cu")
	)
	(gr_line
		(start 391.693654 -12.183872)
		(end 391.693654 -10.151872)
		(stroke
			(width 0.254)
			(type default)
		)
		(layer "In1.Cu")
	)
	(gr_line
		(start 391.693654 -10.251948)
		(end 392.023854 -10.251948)
		(stroke
			(width 0.254)
			(type default)
		)
		(layer "In1.Cu")
	)
	(gr_line
		(start 391.693654 -10.151872)
		(end 392.023854 -10.151872)
		(stroke
			(width 0.254)
			(type default)
		)
		(layer "In1.Cu")
	)
	(gr_line
		(start 391.693654 -8.083804)
		(end 391.693654 -6.051804)
		(stroke
			(width 0.254)
			(type default)
		)
		(layer "In1.Cu")
	)
	(gr_line
		(start 391.693654 -7.983728)
		(end 391.693654 -5.951728)
		(stroke
			(width 0.254)
			(type default)
		)
		(layer "In1.Cu")
	)
	(gr_line
		(start 391.693654 -6.051804)
		(end 392.023854 -6.051804)
		(stroke
			(width 0.254)
			(type default)
		)
		(layer "In1.Cu")
	)
	(gr_line
		(start 391.693654 -5.951728)
		(end 392.023854 -5.951728)
		(stroke
			(width 0.254)
			(type default)
		)
		(layer "In1.Cu")
	)
	(gr_line
		(start 391.700258 -29.1084)
		(end 391.700258 -27.7622)
		(stroke
			(width 0.508)
			(type default)
		)
		(layer "In1.Cu")
	)
	(gr_line
		(start 391.725658 -29.1084)
		(end 392.386058 -29.1084)
		(stroke
			(width 0.508)
			(type default)
		)
		(layer "In1.Cu")
	)
	(gr_line
		(start 391.725658 -29.083)
		(end 391.725658 -27.7368)
		(stroke
			(width 0.508)
			(type default)
		)
		(layer "In1.Cu")
	)
	(gr_line
		(start 391.725658 -27.7114)
		(end 392.360658 -27.7114)
		(stroke
			(width 0.508)
			(type default)
		)
		(layer "In1.Cu")
	)
	(gr_line
		(start 391.751058 -29.083)
		(end 391.751058 -27.7368)
		(stroke
			(width 0.508)
			(type default)
		)
		(layer "In1.Cu")
	)
	(gr_line
		(start 391.776458 -29.083)
		(end 391.776458 -27.7368)
		(stroke
			(width 0.508)
			(type default)
		)
		(layer "In1.Cu")
	)
	(gr_line
		(start 391.795254 -12.207748)
		(end 391.795254 -10.404348)
		(stroke
			(width 0.254)
			(type default)
		)
		(layer "In1.Cu")
	)
	(gr_line
		(start 391.795254 -12.207748)
		(end 391.795254 -10.226548)
		(stroke
			(width 0.762)
			(type default)
		)
		(layer "In1.Cu")
	)
	(gr_line
		(start 391.795254 -12.107672)
		(end 391.795254 -10.304272)
		(stroke
			(width 0.254)
			(type default)
		)
		(layer "In1.Cu")
	)
	(gr_line
		(start 391.795254 -12.107672)
		(end 391.795254 -10.126472)
		(stroke
			(width 0.762)
			(type default)
		)
		(layer "In1.Cu")
	)
	(gr_line
		(start 391.795254 -10.404348)
		(end 391.896854 -10.404348)
		(stroke
			(width 0.254)
			(type default)
		)
		(layer "In1.Cu")
	)
	(gr_line
		(start 391.795254 -10.304272)
		(end 391.896854 -10.304272)
		(stroke
			(width 0.254)
			(type default)
		)
		(layer "In1.Cu")
	)
	(gr_line
		(start 391.795254 -8.007604)
		(end 391.795254 -6.204204)
		(stroke
			(width 0.254)
			(type default)
		)
		(layer "In1.Cu")
	)
	(gr_line
		(start 391.795254 -8.007604)
		(end 391.795254 -6.026404)
		(stroke
			(width 0.762)
			(type default)
		)
		(layer "In1.Cu")
	)
	(gr_line
		(start 391.795254 -7.907528)
		(end 391.795254 -6.104128)
		(stroke
			(width 0.254)
			(type default)
		)
		(layer "In1.Cu")
	)
	(gr_line
		(start 391.795254 -7.907528)
		(end 391.795254 -5.926328)
		(stroke
			(width 0.762)
			(type default)
		)
		(layer "In1.Cu")
	)
	(gr_line
		(start 391.795254 -6.204204)
		(end 391.896854 -6.204204)
		(stroke
			(width 0.254)
			(type default)
		)
		(layer "In1.Cu")
	)
	(gr_line
		(start 391.795254 -6.104128)
		(end 391.896854 -6.104128)
		(stroke
			(width 0.254)
			(type default)
		)
		(layer "In1.Cu")
	)
	(gr_line
		(start 391.827258 -29.1084)
		(end 391.827258 -27.7622)
		(stroke
			(width 0.508)
			(type default)
		)
		(layer "In1.Cu")
	)
	(gr_line
		(start 391.827258 -29.083)
		(end 391.827258 -27.7368)
		(stroke
			(width 0.508)
			(type default)
		)
		(layer "In1.Cu")
	)
	(gr_line
		(start 391.850118 -23.69566)
		(end 393.120118 -23.69566)
		(stroke
			(width 0.7874)
			(type default)
		)
		(layer "In1.Cu")
	)
	(gr_line
		(start 391.878058 -29.083)
		(end 391.878058 -27.7368)
		(stroke
			(width 0.508)
			(type default)
		)
		(layer "In1.Cu")
	)
	(gr_line
		(start 391.896854 -12.309348)
		(end 391.846054 -12.309348)
		(stroke
			(width 0.254)
			(type default)
		)
		(layer "In1.Cu")
	)
	(gr_line
		(start 391.896854 -12.209272)
		(end 391.846054 -12.209272)
		(stroke
			(width 0.254)
			(type default)
		)
		(layer "In1.Cu")
	)
	(gr_line
		(start 391.896854 -10.404348)
		(end 391.896854 -12.309348)
		(stroke
			(width 0.254)
			(type default)
		)
		(layer "In1.Cu")
	)
	(gr_line
		(start 391.896854 -10.304272)
		(end 391.896854 -12.209272)
		(stroke
			(width 0.254)
			(type default)
		)
		(layer "In1.Cu")
	)
	(gr_line
		(start 391.896854 -8.109204)
		(end 391.846054 -8.109204)
		(stroke
			(width 0.254)
			(type default)
		)
		(layer "In1.Cu")
	)
	(gr_line
		(start 391.896854 -8.009128)
		(end 391.846054 -8.009128)
		(stroke
			(width 0.254)
			(type default)
		)
		(layer "In1.Cu")
	)
	(gr_line
		(start 391.896854 -6.204204)
		(end 391.896854 -8.109204)
		(stroke
			(width 0.254)
			(type default)
		)
		(layer "In1.Cu")
	)
	(gr_line
		(start 391.896854 -6.104128)
		(end 391.896854 -8.009128)
		(stroke
			(width 0.254)
			(type default)
		)
		(layer "In1.Cu")
	)
	(gr_line
		(start 391.897108 -26.826972)
		(end 392.735308 -26.826972)
		(stroke
			(width 0.1016)
			(type default)
		)
		(layer "In1.Cu")
	)
	(gr_line
		(start 391.897108 -24.972772)
		(end 391.897108 -26.826972)
		(stroke
			(width 0.1016)
			(type default)
		)
		(layer "In1.Cu")
	)
	(gr_line
		(start 391.903458 -29.0576)
		(end 391.903458 -27.7114)
		(stroke
			(width 0.508)
			(type default)
		)
		(layer "In1.Cu")
	)
	(gr_line
		(start 391.928858 -29.083)
		(end 391.928858 -27.7368)
		(stroke
			(width 0.508)
			(type default)
		)
		(layer "In1.Cu")
	)
	(gr_line
		(start 391.947654 -12.233148)
		(end 391.947654 -10.251948)
		(stroke
			(width 0.762)
			(type default)
		)
		(layer "In1.Cu")
	)
	(gr_line
		(start 391.947654 -12.133072)
		(end 391.947654 -10.151872)
		(stroke
			(width 0.762)
			(type default)
		)
		(layer "In1.Cu")
	)
	(gr_line
		(start 391.947654 -8.033004)
		(end 391.947654 -6.051804)
		(stroke
			(width 0.762)
			(type default)
		)
		(layer "In1.Cu")
	)
	(gr_line
		(start 391.947654 -7.932928)
		(end 391.947654 -5.951728)
		(stroke
			(width 0.762)
			(type default)
		)
		(layer "In1.Cu")
	)
	(gr_line
		(start 391.947908 -26.725372)
		(end 391.947908 -25.048972)
		(stroke
			(width 0.2032)
			(type default)
		)
		(layer "In1.Cu")
	)
	(gr_line
		(start 391.947908 -25.048972)
		(end 393.014708 -25.048972)
		(stroke
			(width 0.2032)
			(type default)
		)
		(layer "In1.Cu")
	)
	(gr_line
		(start 391.954258 -29.083)
		(end 391.954258 -27.7368)
		(stroke
			(width 0.508)
			(type default)
		)
		(layer "In1.Cu")
	)
	(gr_line
		(start 391.973308 -26.750772)
		(end 392.963908 -26.750772)
		(stroke
			(width 0.2032)
			(type default)
		)
		(layer "In1.Cu")
	)
	(gr_line
		(start 391.973308 -26.725372)
		(end 391.973308 -26.750772)
		(stroke
			(width 0.2032)
			(type default)
		)
		(layer "In1.Cu")
	)
	(gr_line
		(start 391.979658 -29.083)
		(end 391.979658 -27.7368)
		(stroke
			(width 0.508)
			(type default)
		)
		(layer "In1.Cu")
	)
	(gr_line
		(start 392.023854 -12.207748)
		(end 391.795254 -12.207748)
		(stroke
			(width 0.254)
			(type default)
		)
		(layer "In1.Cu")
	)
	(gr_line
		(start 392.023854 -12.107672)
		(end 391.795254 -12.107672)
		(stroke
			(width 0.254)
			(type default)
		)
		(layer "In1.Cu")
	)
	(gr_line
		(start 392.023854 -10.251948)
		(end 392.023854 -12.207748)
		(stroke
			(width 0.254)
			(type default)
		)
		(layer "In1.Cu")
	)
	(gr_line
		(start 392.023854 -10.151872)
		(end 392.023854 -12.107672)
		(stroke
			(width 0.254)
			(type default)
		)
		(layer "In1.Cu")
	)
	(gr_line
		(start 392.023854 -8.007604)
		(end 391.795254 -8.007604)
		(stroke
			(width 0.254)
			(type default)
		)
		(layer "In1.Cu")
	)
	(gr_line
		(start 392.023854 -7.907528)
		(end 391.795254 -7.907528)
		(stroke
			(width 0.254)
			(type default)
		)
		(layer "In1.Cu")
	)
	(gr_line
		(start 392.023854 -6.051804)
		(end 392.023854 -8.007604)
		(stroke
			(width 0.254)
			(type default)
		)
		(layer "In1.Cu")
	)
	(gr_line
		(start 392.023854 -5.951728)
		(end 392.023854 -7.907528)
		(stroke
			(width 0.254)
			(type default)
		)
		(layer "In1.Cu")
	)
	(gr_line
		(start 392.024108 -26.674572)
		(end 392.963908 -26.674572)
		(stroke
			(width 0.2032)
			(type default)
		)
		(layer "In1.Cu")
	)
	(gr_line
		(start 392.024108 -25.099772)
		(end 392.024108 -26.674572)
		(stroke
			(width 0.2032)
			(type default)
		)
		(layer "In1.Cu")
	)
	(gr_line
		(start 392.030458 -29.083)
		(end 392.030458 -27.7368)
		(stroke
			(width 0.508)
			(type default)
		)
		(layer "In1.Cu")
	)
	(gr_line
		(start 392.055858 -29.083)
		(end 392.055858 -27.7368)
		(stroke
			(width 0.508)
			(type default)
		)
		(layer "In1.Cu")
	)
	(gr_line
		(start 392.074654 -12.563348)
		(end 392.074654 -12.512548)
		(stroke
			(width 0.1016)
			(type default)
		)
		(layer "In1.Cu")
	)
	(gr_line
		(start 392.074654 -12.563348)
		(end 392.481054 -12.563348)
		(stroke
			(width 0.1016)
			(type default)
		)
		(layer "In1.Cu")
	)
	(gr_line
		(start 392.074654 -12.512548)
		(end 391.312654 -12.512548)
		(stroke
			(width 0.1016)
			(type default)
		)
		(layer "In1.Cu")
	)
	(gr_line
		(start 392.074654 -12.463272)
		(end 392.074654 -12.412472)
		(stroke
			(width 0.1016)
			(type default)
		)
		(layer "In1.Cu")
	)
	(gr_line
		(start 392.074654 -12.463272)
		(end 392.481054 -12.463272)
		(stroke
			(width 0.1016)
			(type default)
		)
		(layer "In1.Cu")
	)
	(gr_line
		(start 392.074654 -12.412472)
		(end 391.312654 -12.412472)
		(stroke
			(width 0.1016)
			(type default)
		)
		(layer "In1.Cu")
	)
	(gr_line
		(start 392.074654 -12.233148)
		(end 392.074654 -10.251948)
		(stroke
			(width 0.762)
			(type default)
		)
		(layer "In1.Cu")
	)
	(gr_line
		(start 392.074654 -12.133072)
		(end 392.074654 -10.151872)
		(stroke
			(width 0.762)
			(type default)
		)
		(layer "In1.Cu")
	)
	(gr_line
		(start 392.074654 -8.363204)
		(end 392.074654 -8.312404)
		(stroke
			(width 0.1016)
			(type default)
		)
		(layer "In1.Cu")
	)
	(gr_line
		(start 392.074654 -8.363204)
		(end 392.481054 -8.363204)
		(stroke
			(width 0.1016)
			(type default)
		)
		(layer "In1.Cu")
	)
	(gr_line
		(start 392.074654 -8.312404)
		(end 391.312654 -8.312404)
		(stroke
			(width 0.1016)
			(type default)
		)
		(layer "In1.Cu")
	)
	(gr_line
		(start 392.074654 -8.263128)
		(end 392.074654 -8.212328)
		(stroke
			(width 0.1016)
			(type default)
		)
		(layer "In1.Cu")
	)
	(gr_line
		(start 392.074654 -8.263128)
		(end 392.481054 -8.263128)
		(stroke
			(width 0.1016)
			(type default)
		)
		(layer "In1.Cu")
	)
	(gr_line
		(start 392.074654 -8.212328)
		(end 391.312654 -8.212328)
		(stroke
			(width 0.1016)
			(type default)
		)
		(layer "In1.Cu")
	)
	(gr_line
		(start 392.074654 -8.033004)
		(end 392.074654 -6.051804)
		(stroke
			(width 0.762)
			(type default)
		)
		(layer "In1.Cu")
	)
	(gr_line
		(start 392.074654 -7.932928)
		(end 392.074654 -5.951728)
		(stroke
			(width 0.762)
			(type default)
		)
		(layer "In1.Cu")
	)
	(gr_line
		(start 392.081258 -29.083)
		(end 392.081258 -27.7368)
		(stroke
			(width 0.508)
			(type default)
		)
		(layer "In1.Cu")
	)
	(gr_line
		(start 392.100054 -12.283948)
		(end 391.693654 -12.283948)
		(stroke
			(width 0.254)
			(type default)
		)
		(layer "In1.Cu")
	)
	(gr_line
		(start 392.100054 -12.183872)
		(end 391.693654 -12.183872)
		(stroke
			(width 0.254)
			(type default)
		)
		(layer "In1.Cu")
	)
	(gr_line
		(start 392.100054 -10.175748)
		(end 392.100054 -12.283948)
		(stroke
			(width 0.254)
			(type default)
		)
		(layer "In1.Cu")
	)
	(gr_line
		(start 392.100054 -10.075672)
		(end 392.100054 -12.183872)
		(stroke
			(width 0.254)
			(type default)
		)
		(layer "In1.Cu")
	)
	(gr_line
		(start 392.100054 -8.083804)
		(end 391.693654 -8.083804)
		(stroke
			(width 0.254)
			(type default)
		)
		(layer "In1.Cu")
	)
	(gr_line
		(start 392.100054 -7.983728)
		(end 391.693654 -7.983728)
		(stroke
			(width 0.254)
			(type default)
		)
		(layer "In1.Cu")
	)
	(gr_line
		(start 392.100054 -5.975604)
		(end 392.100054 -8.083804)
		(stroke
			(width 0.254)
			(type default)
		)
		(layer "In1.Cu")
	)
	(gr_line
		(start 392.100054 -5.875528)
		(end 392.100054 -7.983728)
		(stroke
			(width 0.254)
			(type default)
		)
		(layer "In1.Cu")
	)
	(gr_line
		(start 392.100308 -26.598372)
		(end 392.100308 -25.252172)
		(stroke
			(width 0.508)
			(type default)
		)
		(layer "In1.Cu")
	)
	(gr_line
		(start 392.106658 -29.083)
		(end 392.106658 -27.7368)
		(stroke
			(width 0.508)
			(type default)
		)
		(layer "In1.Cu")
	)
	(gr_line
		(start 392.125708 -26.598372)
		(end 392.786108 -26.598372)
		(stroke
			(width 0.508)
			(type default)
		)
		(layer "In1.Cu")
	)
	(gr_line
		(start 392.125708 -26.572972)
		(end 392.125708 -25.226772)
		(stroke
			(width 0.508)
			(type default)
		)
		(layer "In1.Cu")
	)
	(gr_line
		(start 392.125708 -25.201372)
		(end 392.760708 -25.201372)
		(stroke
			(width 0.508)
			(type default)
		)
		(layer "In1.Cu")
	)
	(gr_line
		(start 392.132058 -29.1084)
		(end 392.132058 -27.7622)
		(stroke
			(width 0.508)
			(type default)
		)
		(layer "In1.Cu")
	)
	(gr_line
		(start 392.150854 -12.233148)
		(end 392.150854 -10.251948)
		(stroke
			(width 0.762)
			(type default)
		)
		(layer "In1.Cu")
	)
	(gr_line
		(start 392.150854 -12.133072)
		(end 392.150854 -10.151872)
		(stroke
			(width 0.762)
			(type default)
		)
		(layer "In1.Cu")
	)
	(gr_line
		(start 392.150854 -8.033004)
		(end 392.150854 -6.051804)
		(stroke
			(width 0.762)
			(type default)
		)
		(layer "In1.Cu")
	)
	(gr_line
		(start 392.150854 -7.932928)
		(end 392.150854 -5.951728)
		(stroke
			(width 0.762)
			(type default)
		)
		(layer "In1.Cu")
	)
	(gr_line
		(start 392.151108 -26.572972)
		(end 392.151108 -25.226772)
		(stroke
			(width 0.508)
			(type default)
		)
		(layer "In1.Cu")
	)
	(gr_line
		(start 392.157458 -29.1084)
		(end 392.157458 -27.7622)
		(stroke
			(width 0.508)
			(type default)
		)
		(layer "In1.Cu")
	)
	(gr_line
		(start 392.157458 -29.083)
		(end 392.157458 -27.7368)
		(stroke
			(width 0.508)
			(type default)
		)
		(layer "In1.Cu")
	)
	(gr_line
		(start 392.176254 -12.360148)
		(end 391.617454 -12.360148)
		(stroke
			(width 0.254)
			(type default)
		)
		(layer "In1.Cu")
	)
	(gr_line
		(start 392.176254 -12.260072)
		(end 391.617454 -12.260072)
		(stroke
			(width 0.254)
			(type default)
		)
		(layer "In1.Cu")
	)
	(gr_line
		(start 392.176254 -10.124948)
		(end 392.176254 -12.360148)
		(stroke
			(width 0.254)
			(type default)
		)
		(layer "In1.Cu")
	)
	(gr_line
		(start 392.176254 -10.024872)
		(end 392.176254 -12.260072)
		(stroke
			(width 0.254)
			(type default)
		)
		(layer "In1.Cu")
	)
	(gr_line
		(start 392.176254 -8.160004)
		(end 391.617454 -8.160004)
		(stroke
			(width 0.254)
			(type default)
		)
		(layer "In1.Cu")
	)
	(gr_line
		(start 392.176254 -8.059928)
		(end 391.617454 -8.059928)
		(stroke
			(width 0.254)
			(type default)
		)
		(layer "In1.Cu")
	)
	(gr_line
		(start 392.176254 -5.924804)
		(end 392.176254 -8.160004)
		(stroke
			(width 0.254)
			(type default)
		)
		(layer "In1.Cu")
	)
	(gr_line
		(start 392.176254 -5.824728)
		(end 392.176254 -8.059928)
		(stroke
			(width 0.254)
			(type default)
		)
		(layer "In1.Cu")
	)
	(gr_line
		(start 392.176508 -26.572972)
		(end 392.176508 -25.226772)
		(stroke
			(width 0.508)
			(type default)
		)
		(layer "In1.Cu")
	)
	(gr_line
		(start 392.182858 -29.083)
		(end 392.182858 -27.7368)
		(stroke
			(width 0.508)
			(type default)
		)
		(layer "In1.Cu")
	)
	(gr_line
		(start 392.208258 -29.083)
		(end 392.208258 -27.7368)
		(stroke
			(width 0.508)
			(type default)
		)
		(layer "In1.Cu")
	)
	(gr_line
		(start 392.227308 -26.598372)
		(end 392.227308 -25.252172)
		(stroke
			(width 0.508)
			(type default)
		)
		(layer "In1.Cu")
	)
	(gr_line
		(start 392.227308 -26.572972)
		(end 392.227308 -25.226772)
		(stroke
			(width 0.508)
			(type default)
		)
		(layer "In1.Cu")
	)
	(gr_line
		(start 392.233658 -29.083)
		(end 392.233658 -27.7368)
		(stroke
			(width 0.508)
			(type default)
		)
		(layer "In1.Cu")
	)
	(gr_line
		(start 392.252454 -12.385548)
		(end 391.541254 -12.385548)
		(stroke
			(width 0.254)
			(type default)
		)
		(layer "In1.Cu")
	)
	(gr_line
		(start 392.252454 -12.285472)
		(end 391.541254 -12.285472)
		(stroke
			(width 0.254)
			(type default)
		)
		(layer "In1.Cu")
	)
	(gr_line
		(start 392.252454 -10.048748)
		(end 392.252454 -12.385548)
		(stroke
			(width 0.254)
			(type default)
		)
		(layer "In1.Cu")
	)
	(gr_line
		(start 392.252454 -9.948672)
		(end 392.252454 -12.285472)
		(stroke
			(width 0.254)
			(type default)
		)
		(layer "In1.Cu")
	)
	(gr_line
		(start 392.252454 -8.185404)
		(end 391.541254 -8.185404)
		(stroke
			(width 0.254)
			(type default)
		)
		(layer "In1.Cu")
	)
	(gr_line
		(start 392.252454 -8.085328)
		(end 391.541254 -8.085328)
		(stroke
			(width 0.254)
			(type default)
		)
		(layer "In1.Cu")
	)
	(gr_line
		(start 392.252454 -5.848604)
		(end 392.252454 -8.185404)
		(stroke
			(width 0.254)
			(type default)
		)
		(layer "In1.Cu")
	)
	(gr_line
		(start 392.252454 -5.748528)
		(end 392.252454 -8.085328)
		(stroke
			(width 0.254)
			(type default)
		)
		(layer "In1.Cu")
	)
	(gr_line
		(start 392.259058 -29.1084)
		(end 392.259058 -27.7622)
		(stroke
			(width 0.508)
			(type default)
		)
		(layer "In1.Cu")
	)
	(gr_line
		(start 392.259058 -29.083)
		(end 392.259058 -27.7368)
		(stroke
			(width 0.508)
			(type default)
		)
		(layer "In1.Cu")
	)
	(gr_line
		(start 392.277854 -12.512548)
		(end 391.287254 -12.512548)
		(stroke
			(width 0.1016)
			(type default)
		)
		(layer "In1.Cu")
	)
	(gr_line
		(start 392.277854 -12.436348)
		(end 391.465054 -12.436348)
		(stroke
			(width 0.254)
			(type default)
		)
		(layer "In1.Cu")
	)
	(gr_line
		(start 392.277854 -12.412472)
		(end 391.287254 -12.412472)
		(stroke
			(width 0.1016)
			(type default)
		)
		(layer "In1.Cu")
	)
	(gr_line
		(start 392.277854 -12.336272)
		(end 391.465054 -12.336272)
		(stroke
			(width 0.254)
			(type default)
		)
		(layer "In1.Cu")
	)
	(gr_line
		(start 392.277854 -10.023348)
		(end 392.277854 -12.436348)
		(stroke
			(width 0.254)
			(type default)
		)
		(layer "In1.Cu")
	)
	(gr_line
		(start 392.277854 -9.923272)
		(end 392.277854 -12.336272)
		(stroke
			(width 0.254)
			(type default)
		)
		(layer "In1.Cu")
	)
	(gr_line
		(start 392.277854 -8.312404)
		(end 391.287254 -8.312404)
		(stroke
			(width 0.1016)
			(type default)
		)
		(layer "In1.Cu")
	)
	(gr_line
		(start 392.277854 -8.236204)
		(end 391.465054 -8.236204)
		(stroke
			(width 0.254)
			(type default)
		)
		(layer "In1.Cu")
	)
	(gr_line
		(start 392.277854 -8.212328)
		(end 391.287254 -8.212328)
		(stroke
			(width 0.1016)
			(type default)
		)
		(layer "In1.Cu")
	)
	(gr_line
		(start 392.277854 -8.136128)
		(end 391.465054 -8.136128)
		(stroke
			(width 0.254)
			(type default)
		)
		(layer "In1.Cu")
	)
	(gr_line
		(start 392.277854 -5.823204)
		(end 392.277854 -8.236204)
		(stroke
			(width 0.254)
			(type default)
		)
		(layer "In1.Cu")
	)
	(gr_line
		(start 392.277854 -5.723128)
		(end 392.277854 -8.136128)
		(stroke
			(width 0.254)
			(type default)
		)
		(layer "In1.Cu")
	)
	(gr_line
		(start 392.278108 -26.572972)
		(end 392.278108 -25.226772)
		(stroke
			(width 0.508)
			(type default)
		)
		(layer "In1.Cu")
	)
	(gr_line
		(start 392.284458 -29.1084)
		(end 392.284458 -27.7622)
		(stroke
			(width 0.508)
			(type default)
		)
		(layer "In1.Cu")
	)
	(gr_line
		(start 392.284458 -29.083)
		(end 392.284458 -27.7368)
		(stroke
			(width 0.508)
			(type default)
		)
		(layer "In1.Cu")
	)
	(gr_line
		(start 392.303254 -12.461748)
		(end 391.439654 -12.461748)
		(stroke
			(width 0.254)
			(type default)
		)
		(layer "In1.Cu")
	)
	(gr_line
		(start 392.303254 -12.361672)
		(end 391.439654 -12.361672)
		(stroke
			(width 0.254)
			(type default)
		)
		(layer "In1.Cu")
	)
	(gr_line
		(start 392.303254 -9.997948)
		(end 392.303254 -12.461748)
		(stroke
			(width 0.254)
			(type default)
		)
		(layer "In1.Cu")
	)
	(gr_line
		(start 392.303254 -9.897872)
		(end 392.303254 -12.361672)
		(stroke
			(width 0.254)
			(type default)
		)
		(layer "In1.Cu")
	)
	(gr_line
		(start 392.303254 -8.261604)
		(end 391.439654 -8.261604)
		(stroke
			(width 0.254)
			(type default)
		)
		(layer "In1.Cu")
	)
	(gr_line
		(start 392.303254 -8.161528)
		(end 391.439654 -8.161528)
		(stroke
			(width 0.254)
			(type default)
		)
		(layer "In1.Cu")
	)
	(gr_line
		(start 392.303254 -5.797804)
		(end 392.303254 -8.261604)
		(stroke
			(width 0.254)
			(type default)
		)
		(layer "In1.Cu")
	)
	(gr_line
		(start 392.303254 -5.697728)
		(end 392.303254 -8.161528)
		(stroke
			(width 0.254)
			(type default)
		)
		(layer "In1.Cu")
	)
	(gr_line
		(start 392.303508 -26.547572)
		(end 392.303508 -25.201372)
		(stroke
			(width 0.508)
			(type default)
		)
		(layer "In1.Cu")
	)
	(gr_line
		(start 392.309858 -29.1084)
		(end 392.309858 -27.7622)
		(stroke
			(width 0.508)
			(type default)
		)
		(layer "In1.Cu")
	)
	(gr_line
		(start 392.328908 -26.572972)
		(end 392.328908 -25.226772)
		(stroke
			(width 0.508)
			(type default)
		)
		(layer "In1.Cu")
	)
	(gr_line
		(start 392.335258 -29.337)
		(end 392.665458 -29.337)
		(stroke
			(width 0.1016)
			(type default)
		)
		(layer "In1.Cu")
	)
	(gr_line
		(start 392.335258 -29.083)
		(end 392.335258 -27.7368)
		(stroke
			(width 0.508)
			(type default)
		)
		(layer "In1.Cu")
	)
	(gr_line
		(start 392.354054 -12.487148)
		(end 391.414254 -12.487148)
		(stroke
			(width 0.254)
			(type default)
		)
		(layer "In1.Cu")
	)
	(gr_line
		(start 392.354054 -12.387072)
		(end 391.414254 -12.387072)
		(stroke
			(width 0.254)
			(type default)
		)
		(layer "In1.Cu")
	)
	(gr_line
		(start 392.354054 -9.997948)
		(end 392.354054 -12.487148)
		(stroke
			(width 0.254)
			(type default)
		)
		(layer "In1.Cu")
	)
	(gr_line
		(start 392.354054 -9.897872)
		(end 392.354054 -12.387072)
		(stroke
			(width 0.254)
			(type default)
		)
		(layer "In1.Cu")
	)
	(gr_line
		(start 392.354054 -8.287004)
		(end 391.414254 -8.287004)
		(stroke
			(width 0.254)
			(type default)
		)
		(layer "In1.Cu")
	)
	(gr_line
		(start 392.354054 -8.186928)
		(end 391.414254 -8.186928)
		(stroke
			(width 0.254)
			(type default)
		)
		(layer "In1.Cu")
	)
	(gr_line
		(start 392.354054 -5.797804)
		(end 392.354054 -8.287004)
		(stroke
			(width 0.254)
			(type default)
		)
		(layer "In1.Cu")
	)
	(gr_line
		(start 392.354054 -5.697728)
		(end 392.354054 -8.186928)
		(stroke
			(width 0.254)
			(type default)
		)
		(layer "In1.Cu")
	)
	(gr_line
		(start 392.354308 -26.572972)
		(end 392.354308 -25.226772)
		(stroke
			(width 0.508)
			(type default)
		)
		(layer "In1.Cu")
	)
	(gr_line
		(start 392.360658 -29.1084)
		(end 392.360658 -27.7622)
		(stroke
			(width 0.508)
			(type default)
		)
		(layer "In1.Cu")
	)
	(gr_line
		(start 392.360658 -29.083)
		(end 392.360658 -27.7368)
		(stroke
			(width 0.508)
			(type default)
		)
		(layer "In1.Cu")
	)
	(gr_line
		(start 392.379454 -12.487148)
		(end 391.414254 -12.487148)
		(stroke
			(width 0.2032)
			(type default)
		)
		(layer "In1.Cu")
	)
	(gr_line
		(start 392.379454 -12.387072)
		(end 391.414254 -12.387072)
		(stroke
			(width 0.2032)
			(type default)
		)
		(layer "In1.Cu")
	)
	(gr_line
		(start 392.379454 -9.947148)
		(end 392.379454 -12.487148)
		(stroke
			(width 0.2032)
			(type default)
		)
		(layer "In1.Cu")
	)
	(gr_line
		(start 392.379454 -9.847072)
		(end 392.379454 -12.387072)
		(stroke
			(width 0.2032)
			(type default)
		)
		(layer "In1.Cu")
	)
	(gr_line
		(start 392.379454 -8.287004)
		(end 391.414254 -8.287004)
		(stroke
			(width 0.2032)
			(type default)
		)
		(layer "In1.Cu")
	)
	(gr_line
		(start 392.379454 -8.186928)
		(end 391.414254 -8.186928)
		(stroke
			(width 0.2032)
			(type default)
		)
		(layer "In1.Cu")
	)
	(gr_line
		(start 392.379454 -5.747004)
		(end 392.379454 -8.287004)
		(stroke
			(width 0.2032)
			(type default)
		)
		(layer "In1.Cu")
	)
	(gr_line
		(start 392.379454 -5.646928)
		(end 392.379454 -8.186928)
		(stroke
			(width 0.2032)
			(type default)
		)
		(layer "In1.Cu")
	)
	(gr_line
		(start 392.379708 -26.572972)
		(end 392.379708 -25.226772)
		(stroke
			(width 0.508)
			(type default)
		)
		(layer "In1.Cu")
	)
	(gr_line
		(start 392.386058 -29.1084)
		(end 392.386058 -27.7622)
		(stroke
			(width 0.508)
			(type default)
		)
		(layer "In1.Cu")
	)
	(gr_line
		(start 392.430254 -12.512548)
		(end 391.363454 -12.512548)
		(stroke
			(width 0.2032)
			(type default)
		)
		(layer "In1.Cu")
	)
	(gr_line
		(start 392.430254 -12.412472)
		(end 391.363454 -12.412472)
		(stroke
			(width 0.2032)
			(type default)
		)
		(layer "In1.Cu")
	)
	(gr_line
		(start 392.430254 -9.947148)
		(end 392.430254 -12.512548)
		(stroke
			(width 0.2032)
			(type default)
		)
		(layer "In1.Cu")
	)
	(gr_line
		(start 392.430254 -9.847072)
		(end 392.430254 -12.412472)
		(stroke
			(width 0.2032)
			(type default)
		)
		(layer "In1.Cu")
	)
	(gr_line
		(start 392.430254 -8.312404)
		(end 391.363454 -8.312404)
		(stroke
			(width 0.2032)
			(type default)
		)
		(layer "In1.Cu")
	)
	(gr_line
		(start 392.430254 -8.212328)
		(end 391.363454 -8.212328)
		(stroke
			(width 0.2032)
			(type default)
		)
		(layer "In1.Cu")
	)
	(gr_line
		(start 392.430254 -5.747004)
		(end 392.430254 -8.312404)
		(stroke
			(width 0.2032)
			(type default)
		)
		(layer "In1.Cu")
	)
	(gr_line
		(start 392.430254 -5.646928)
		(end 392.430254 -8.212328)
		(stroke
			(width 0.2032)
			(type default)
		)
		(layer "In1.Cu")
	)
	(gr_line
		(start 392.430508 -26.572972)
		(end 392.430508 -25.226772)
		(stroke
			(width 0.508)
			(type default)
		)
		(layer "In1.Cu")
	)
	(gr_line
		(start 392.455654 -12.512548)
		(end 391.338054 -12.512548)
		(stroke
			(width 0.1016)
			(type default)
		)
		(layer "In1.Cu")
	)
	(gr_line
		(start 392.455654 -12.412472)
		(end 391.338054 -12.412472)
		(stroke
			(width 0.1016)
			(type default)
		)
		(layer "In1.Cu")
	)
	(gr_line
		(start 392.455654 -9.921748)
		(end 392.455654 -12.512548)
		(stroke
			(width 0.1016)
			(type default)
		)
		(layer "In1.Cu")
	)
	(gr_line
		(start 392.455654 -9.821672)
		(end 392.455654 -12.412472)
		(stroke
			(width 0.1016)
			(type default)
		)
		(layer "In1.Cu")
	)
	(gr_line
		(start 392.455654 -8.312404)
		(end 391.338054 -8.312404)
		(stroke
			(width 0.1016)
			(type default)
		)
		(layer "In1.Cu")
	)
	(gr_line
		(start 392.455654 -8.212328)
		(end 391.338054 -8.212328)
		(stroke
			(width 0.1016)
			(type default)
		)
		(layer "In1.Cu")
	)
	(gr_line
		(start 392.455654 -5.721604)
		(end 392.455654 -8.312404)
		(stroke
			(width 0.1016)
			(type default)
		)
		(layer "In1.Cu")
	)
	(gr_line
		(start 392.455654 -5.621528)
		(end 392.455654 -8.212328)
		(stroke
			(width 0.1016)
			(type default)
		)
		(layer "In1.Cu")
	)
	(gr_line
		(start 392.455908 -26.572972)
		(end 392.455908 -25.226772)
		(stroke
			(width 0.508)
			(type default)
		)
		(layer "In1.Cu")
	)
	(gr_line
		(start 392.462258 -29.1084)
		(end 392.462258 -27.7622)
		(stroke
			(width 0.508)
			(type default)
		)
		(layer "In1.Cu")
	)
	(gr_line
		(start 392.481054 -12.563348)
		(end 392.074654 -12.563348)
		(stroke
			(width 0.1016)
			(type default)
		)
		(layer "In1.Cu")
	)
	(gr_line
		(start 392.481054 -12.563348)
		(end 392.481054 -9.896348)
		(stroke
			(width 0.1016)
			(type default)
		)
		(layer "In1.Cu")
	)
	(gr_line
		(start 392.481054 -12.463272)
		(end 392.074654 -12.463272)
		(stroke
			(width 0.1016)
			(type default)
		)
		(layer "In1.Cu")
	)
	(gr_line
		(start 392.481054 -12.463272)
		(end 392.481054 -9.796272)
		(stroke
			(width 0.1016)
			(type default)
		)
		(layer "In1.Cu")
	)
	(gr_line
		(start 392.481054 -9.896348)
		(end 391.287254 -9.896348)
		(stroke
			(width 0.1016)
			(type default)
		)
		(layer "In1.Cu")
	)
	(gr_line
		(start 392.481054 -9.896348)
		(end 392.481054 -12.563348)
		(stroke
			(width 0.1016)
			(type default)
		)
		(layer "In1.Cu")
	)
	(gr_line
		(start 392.481054 -9.796272)
		(end 391.287254 -9.796272)
		(stroke
			(width 0.1016)
			(type default)
		)
		(layer "In1.Cu")
	)
	(gr_line
		(start 392.481054 -9.796272)
		(end 392.481054 -12.463272)
		(stroke
			(width 0.1016)
			(type default)
		)
		(layer "In1.Cu")
	)
	(gr_line
		(start 392.481054 -8.363204)
		(end 392.074654 -8.363204)
		(stroke
			(width 0.1016)
			(type default)
		)
		(layer "In1.Cu")
	)
	(gr_line
		(start 392.481054 -8.363204)
		(end 392.481054 -5.696204)
		(stroke
			(width 0.1016)
			(type default)
		)
		(layer "In1.Cu")
	)
	(gr_line
		(start 392.481054 -8.263128)
		(end 392.074654 -8.263128)
		(stroke
			(width 0.1016)
			(type default)
		)
		(layer "In1.Cu")
	)
	(gr_line
		(start 392.481054 -8.263128)
		(end 392.481054 -5.596128)
		(stroke
			(width 0.1016)
			(type default)
		)
		(layer "In1.Cu")
	)
	(gr_line
		(start 392.481054 -5.696204)
		(end 391.287254 -5.696204)
		(stroke
			(width 0.1016)
			(type default)
		)
		(layer "In1.Cu")
	)
	(gr_line
		(start 392.481054 -5.696204)
		(end 392.481054 -8.363204)
		(stroke
			(width 0.1016)
			(type default)
		)
		(layer "In1.Cu")
	)
	(gr_line
		(start 392.481054 -5.596128)
		(end 391.287254 -5.596128)
		(stroke
			(width 0.1016)
			(type default)
		)
		(layer "In1.Cu")
	)
	(gr_line
		(start 392.481054 -5.596128)
		(end 392.481054 -8.263128)
		(stroke
			(width 0.1016)
			(type default)
		)
		(layer "In1.Cu")
	)
	(gr_line
		(start 392.481308 -26.572972)
		(end 392.481308 -25.226772)
		(stroke
			(width 0.508)
			(type default)
		)
		(layer "In1.Cu")
	)
	(gr_line
		(start 392.506708 -26.572972)
		(end 392.506708 -25.226772)
		(stroke
			(width 0.508)
			(type default)
		)
		(layer "In1.Cu")
	)
	(gr_line
		(start 392.532108 -26.598372)
		(end 392.532108 -25.252172)
		(stroke
			(width 0.508)
			(type default)
		)
		(layer "In1.Cu")
	)
	(gr_line
		(start 392.557508 -26.598372)
		(end 392.557508 -25.252172)
		(stroke
			(width 0.508)
			(type default)
		)
		(layer "In1.Cu")
	)
	(gr_line
		(start 392.557508 -26.572972)
		(end 392.557508 -25.226772)
		(stroke
			(width 0.508)
			(type default)
		)
		(layer "In1.Cu")
	)
	(gr_line
		(start 392.563858 -29.2608)
		(end 392.563858 -27.6098)
		(stroke
			(width 0.2032)
			(type default)
		)
		(layer "In1.Cu")
	)
	(gr_line
		(start 392.563858 -29.2354)
		(end 391.547858 -29.2354)
		(stroke
			(width 0.2032)
			(type default)
		)
		(layer "In1.Cu")
	)
	(gr_line
		(start 392.563858 -29.1846)
		(end 392.563858 -29.2354)
		(stroke
			(width 0.2032)
			(type default)
		)
		(layer "In1.Cu")
	)
	(gr_line
		(start 392.563858 -27.6098)
		(end 391.624058 -27.6098)
		(stroke
			(width 0.2032)
			(type default)
		)
		(layer "In1.Cu")
	)
	(gr_line
		(start 392.582908 -26.572972)
		(end 392.582908 -25.226772)
		(stroke
			(width 0.508)
			(type default)
		)
		(layer "In1.Cu")
	)
	(gr_line
		(start 392.608308 -26.572972)
		(end 392.608308 -25.226772)
		(stroke
			(width 0.508)
			(type default)
		)
		(layer "In1.Cu")
	)
	(gr_line
		(start 392.614658 -29.2354)
		(end 391.573258 -29.2354)
		(stroke
			(width 0.2032)
			(type default)
		)
		(layer "In1.Cu")
	)
	(gr_line
		(start 392.614658 -27.559)
		(end 392.614658 -29.2354)
		(stroke
			(width 0.2032)
			(type default)
		)
		(layer "In1.Cu")
	)
	(gr_line
		(start 392.633708 -26.572972)
		(end 392.633708 -25.226772)
		(stroke
			(width 0.508)
			(type default)
		)
		(layer "In1.Cu")
	)
	(gr_line
		(start 392.659108 -26.598372)
		(end 392.659108 -25.252172)
		(stroke
			(width 0.508)
			(type default)
		)
		(layer "In1.Cu")
	)
	(gr_line
		(start 392.659108 -26.572972)
		(end 392.659108 -25.226772)
		(stroke
			(width 0.508)
			(type default)
		)
		(layer "In1.Cu")
	)
	(gr_line
		(start 392.665458 -29.337)
		(end 392.665458 -27.4828)
		(stroke
			(width 0.1016)
			(type default)
		)
		(layer "In1.Cu")
	)
	(gr_line
		(start 392.665458 -27.4828)
		(end 391.497058 -27.4828)
		(stroke
			(width 0.1016)
			(type default)
		)
		(layer "In1.Cu")
	)
	(gr_line
		(start 392.684508 -26.598372)
		(end 392.684508 -25.252172)
		(stroke
			(width 0.508)
			(type default)
		)
		(layer "In1.Cu")
	)
	(gr_line
		(start 392.684508 -26.572972)
		(end 392.684508 -25.226772)
		(stroke
			(width 0.508)
			(type default)
		)
		(layer "In1.Cu")
	)
	(gr_line
		(start 392.709908 -26.598372)
		(end 392.709908 -25.252172)
		(stroke
			(width 0.508)
			(type default)
		)
		(layer "In1.Cu")
	)
	(gr_line
		(start 392.719814 -31.98622)
		(end 391.449814 -31.98622)
		(stroke
			(width 0.7874)
			(type default)
		)
		(layer "In1.Cu")
	)
	(gr_line
		(start 392.735308 -26.826972)
		(end 393.065508 -26.826972)
		(stroke
			(width 0.1016)
			(type default)
		)
		(layer "In1.Cu")
	)
	(gr_line
		(start 392.735308 -26.572972)
		(end 392.735308 -25.226772)
		(stroke
			(width 0.508)
			(type default)
		)
		(layer "In1.Cu")
	)
	(gr_line
		(start 392.760708 -26.598372)
		(end 392.760708 -25.252172)
		(stroke
			(width 0.508)
			(type default)
		)
		(layer "In1.Cu")
	)
	(gr_line
		(start 392.760708 -26.572972)
		(end 392.760708 -25.226772)
		(stroke
			(width 0.508)
			(type default)
		)
		(layer "In1.Cu")
	)
	(gr_line
		(start 392.786108 -26.598372)
		(end 392.786108 -25.252172)
		(stroke
			(width 0.508)
			(type default)
		)
		(layer "In1.Cu")
	)
	(gr_line
		(start 392.862308 -26.598372)
		(end 392.862308 -25.252172)
		(stroke
			(width 0.508)
			(type default)
		)
		(layer "In1.Cu")
	)
	(gr_line
		(start 392.963908 -26.750772)
		(end 392.963908 -25.099772)
		(stroke
			(width 0.2032)
			(type default)
		)
		(layer "In1.Cu")
	)
	(gr_line
		(start 392.963908 -26.725372)
		(end 391.947908 -26.725372)
		(stroke
			(width 0.2032)
			(type default)
		)
		(layer "In1.Cu")
	)
	(gr_line
		(start 392.963908 -26.674572)
		(end 392.963908 -26.725372)
		(stroke
			(width 0.2032)
			(type default)
		)
		(layer "In1.Cu")
	)
	(gr_line
		(start 392.963908 -25.099772)
		(end 392.024108 -25.099772)
		(stroke
			(width 0.2032)
			(type default)
		)
		(layer "In1.Cu")
	)
	(gr_line
		(start 393.014708 -26.725372)
		(end 391.973308 -26.725372)
		(stroke
			(width 0.2032)
			(type default)
		)
		(layer "In1.Cu")
	)
	(gr_line
		(start 393.014708 -25.048972)
		(end 393.014708 -26.725372)
		(stroke
			(width 0.2032)
			(type default)
		)
		(layer "In1.Cu")
	)
	(gr_line
		(start 393.065508 -26.826972)
		(end 393.065508 -24.972772)
		(stroke
			(width 0.1016)
			(type default)
		)
		(layer "In1.Cu")
	)
	(gr_line
		(start 393.065508 -24.972772)
		(end 391.897108 -24.972772)
		(stroke
			(width 0.1016)
			(type default)
		)
		(layer "In1.Cu")
	)
	(gr_line
		(start 393.28725 -13.8176)
		(end 394.07465 -13.8176)
		(stroke
			(width 0.1016)
			(type default)
		)
		(layer "In1.Cu")
	)
	(gr_line
		(start 393.28725 -13.7668)
		(end 393.28725 -11.1506)
		(stroke
			(width 0.1016)
			(type default)
		)
		(layer "In1.Cu")
	)
	(gr_line
		(start 393.28725 -11.1506)
		(end 393.28725 -13.8176)
		(stroke
			(width 0.1016)
			(type default)
		)
		(layer "In1.Cu")
	)
	(gr_line
		(start 393.28725 -11.1506)
		(end 394.48105 -11.1506)
		(stroke
			(width 0.1016)
			(type default)
		)
		(layer "In1.Cu")
	)
	(gr_line
		(start 393.28725 -9.617456)
		(end 394.07465 -9.617456)
		(stroke
			(width 0.1016)
			(type default)
		)
		(layer "In1.Cu")
	)
	(gr_line
		(start 393.28725 -9.566656)
		(end 393.28725 -6.950456)
		(stroke
			(width 0.1016)
			(type default)
		)
		(layer "In1.Cu")
	)
	(gr_line
		(start 393.28725 -6.950456)
		(end 393.28725 -9.617456)
		(stroke
			(width 0.1016)
			(type default)
		)
		(layer "In1.Cu")
	)
	(gr_line
		(start 393.28725 -6.950456)
		(end 394.48105 -6.950456)
		(stroke
			(width 0.1016)
			(type default)
		)
		(layer "In1.Cu")
	)
	(gr_line
		(start 393.28725 -5.417312)
		(end 394.07465 -5.417312)
		(stroke
			(width 0.1016)
			(type default)
		)
		(layer "In1.Cu")
	)
	(gr_line
		(start 393.28725 -5.366512)
		(end 393.28725 -2.750312)
		(stroke
			(width 0.1016)
			(type default)
		)
		(layer "In1.Cu")
	)
	(gr_line
		(start 393.28725 -2.750312)
		(end 393.28725 -5.417312)
		(stroke
			(width 0.1016)
			(type default)
		)
		(layer "In1.Cu")
	)
	(gr_line
		(start 393.28725 -2.750312)
		(end 394.48105 -2.750312)
		(stroke
			(width 0.1016)
			(type default)
		)
		(layer "In1.Cu")
	)
	(gr_line
		(start 393.31265 -13.7668)
		(end 393.31265 -11.176)
		(stroke
			(width 0.1016)
			(type default)
		)
		(layer "In1.Cu")
	)
	(gr_line
		(start 393.31265 -11.176)
		(end 394.45565 -11.176)
		(stroke
			(width 0.1016)
			(type default)
		)
		(layer "In1.Cu")
	)
	(gr_line
		(start 393.31265 -9.566656)
		(end 393.31265 -6.975856)
		(stroke
			(width 0.1016)
			(type default)
		)
		(layer "In1.Cu")
	)
	(gr_line
		(start 393.31265 -6.975856)
		(end 394.45565 -6.975856)
		(stroke
			(width 0.1016)
			(type default)
		)
		(layer "In1.Cu")
	)
	(gr_line
		(start 393.31265 -5.366512)
		(end 393.31265 -2.775712)
		(stroke
			(width 0.1016)
			(type default)
		)
		(layer "In1.Cu")
	)
	(gr_line
		(start 393.31265 -2.775712)
		(end 394.45565 -2.775712)
		(stroke
			(width 0.1016)
			(type default)
		)
		(layer "In1.Cu")
	)
	(gr_line
		(start 393.33805 -13.7668)
		(end 393.33805 -11.2014)
		(stroke
			(width 0.1016)
			(type default)
		)
		(layer "In1.Cu")
	)
	(gr_line
		(start 393.33805 -11.2014)
		(end 393.59205 -11.2014)
		(stroke
			(width 0.1016)
			(type default)
		)
		(layer "In1.Cu")
	)
	(gr_line
		(start 393.33805 -9.566656)
		(end 393.33805 -7.001256)
		(stroke
			(width 0.1016)
			(type default)
		)
		(layer "In1.Cu")
	)
	(gr_line
		(start 393.33805 -7.001256)
		(end 393.59205 -7.001256)
		(stroke
			(width 0.1016)
			(type default)
		)
		(layer "In1.Cu")
	)
	(gr_line
		(start 393.33805 -5.366512)
		(end 393.33805 -2.801112)
		(stroke
			(width 0.1016)
			(type default)
		)
		(layer "In1.Cu")
	)
	(gr_line
		(start 393.33805 -2.801112)
		(end 393.59205 -2.801112)
		(stroke
			(width 0.1016)
			(type default)
		)
		(layer "In1.Cu")
	)
	(gr_line
		(start 393.36345 -13.7668)
		(end 393.36345 -11.2014)
		(stroke
			(width 0.2032)
			(type default)
		)
		(layer "In1.Cu")
	)
	(gr_line
		(start 393.36345 -11.2014)
		(end 394.37945 -11.2014)
		(stroke
			(width 0.2032)
			(type default)
		)
		(layer "In1.Cu")
	)
	(gr_line
		(start 393.36345 -9.566656)
		(end 393.36345 -7.001256)
		(stroke
			(width 0.2032)
			(type default)
		)
		(layer "In1.Cu")
	)
	(gr_line
		(start 393.36345 -7.001256)
		(end 394.37945 -7.001256)
		(stroke
			(width 0.2032)
			(type default)
		)
		(layer "In1.Cu")
	)
	(gr_line
		(start 393.36345 -5.366512)
		(end 393.36345 -2.801112)
		(stroke
			(width 0.2032)
			(type default)
		)
		(layer "In1.Cu")
	)
	(gr_line
		(start 393.36345 -2.801112)
		(end 394.37945 -2.801112)
		(stroke
			(width 0.2032)
			(type default)
		)
		(layer "In1.Cu")
	)
	(gr_line
		(start 393.41425 -13.7414)
		(end 393.41425 -11.2522)
		(stroke
			(width 0.2032)
			(type default)
		)
		(layer "In1.Cu")
	)
	(gr_line
		(start 393.41425 -13.7414)
		(end 393.41425 -11.2522)
		(stroke
			(width 0.254)
			(type default)
		)
		(layer "In1.Cu")
	)
	(gr_line
		(start 393.41425 -11.2522)
		(end 393.61745 -11.2522)
		(stroke
			(width 0.2032)
			(type default)
		)
		(layer "In1.Cu")
	)
	(gr_line
		(start 393.41425 -11.2522)
		(end 394.30325 -11.2522)
		(stroke
			(width 0.254)
			(type default)
		)
		(layer "In1.Cu")
	)
	(gr_line
		(start 393.41425 -9.541256)
		(end 393.41425 -7.052056)
		(stroke
			(width 0.2032)
			(type default)
		)
		(layer "In1.Cu")
	)
	(gr_line
		(start 393.41425 -9.541256)
		(end 393.41425 -7.052056)
		(stroke
			(width 0.254)
			(type default)
		)
		(layer "In1.Cu")
	)
	(gr_line
		(start 393.41425 -7.052056)
		(end 393.61745 -7.052056)
		(stroke
			(width 0.2032)
			(type default)
		)
		(layer "In1.Cu")
	)
	(gr_line
		(start 393.41425 -7.052056)
		(end 394.30325 -7.052056)
		(stroke
			(width 0.254)
			(type default)
		)
		(layer "In1.Cu")
	)
	(gr_line
		(start 393.41425 -5.341112)
		(end 393.41425 -2.851912)
		(stroke
			(width 0.2032)
			(type default)
		)
		(layer "In1.Cu")
	)
	(gr_line
		(start 393.41425 -5.341112)
		(end 393.41425 -2.851912)
		(stroke
			(width 0.254)
			(type default)
		)
		(layer "In1.Cu")
	)
	(gr_line
		(start 393.41425 -2.851912)
		(end 393.61745 -2.851912)
		(stroke
			(width 0.2032)
			(type default)
		)
		(layer "In1.Cu")
	)
	(gr_line
		(start 393.41425 -2.851912)
		(end 394.30325 -2.851912)
		(stroke
			(width 0.254)
			(type default)
		)
		(layer "In1.Cu")
	)
	(gr_line
		(start 393.43965 -13.716)
		(end 393.43965 -11.2776)
		(stroke
			(width 0.254)
			(type default)
		)
		(layer "In1.Cu")
	)
	(gr_line
		(start 393.43965 -11.2776)
		(end 394.27785 -11.2776)
		(stroke
			(width 0.254)
			(type default)
		)
		(layer "In1.Cu")
	)
	(gr_line
		(start 393.43965 -9.515856)
		(end 393.43965 -7.077456)
		(stroke
			(width 0.254)
			(type default)
		)
		(layer "In1.Cu")
	)
	(gr_line
		(start 393.43965 -7.077456)
		(end 394.27785 -7.077456)
		(stroke
			(width 0.254)
			(type default)
		)
		(layer "In1.Cu")
	)
	(gr_line
		(start 393.43965 -5.315712)
		(end 393.43965 -2.877312)
		(stroke
			(width 0.254)
			(type default)
		)
		(layer "In1.Cu")
	)
	(gr_line
		(start 393.43965 -2.877312)
		(end 394.27785 -2.877312)
		(stroke
			(width 0.254)
			(type default)
		)
		(layer "In1.Cu")
	)
	(gr_line
		(start 393.46505 -13.6906)
		(end 393.46505 -11.303)
		(stroke
			(width 0.254)
			(type default)
		)
		(layer "In1.Cu")
	)
	(gr_line
		(start 393.46505 -11.303)
		(end 394.25245 -11.303)
		(stroke
			(width 0.254)
			(type default)
		)
		(layer "In1.Cu")
	)
	(gr_line
		(start 393.46505 -9.490456)
		(end 393.46505 -7.102856)
		(stroke
			(width 0.254)
			(type default)
		)
		(layer "In1.Cu")
	)
	(gr_line
		(start 393.46505 -7.102856)
		(end 394.25245 -7.102856)
		(stroke
			(width 0.254)
			(type default)
		)
		(layer "In1.Cu")
	)
	(gr_line
		(start 393.46505 -5.290312)
		(end 393.46505 -2.902712)
		(stroke
			(width 0.254)
			(type default)
		)
		(layer "In1.Cu")
	)
	(gr_line
		(start 393.46505 -2.902712)
		(end 394.25245 -2.902712)
		(stroke
			(width 0.254)
			(type default)
		)
		(layer "In1.Cu")
	)
	(gr_line
		(start 393.49045 -13.6144)
		(end 394.12545 -13.6144)
		(stroke
			(width 0.508)
			(type default)
		)
		(layer "In1.Cu")
	)
	(gr_line
		(start 393.49045 -11.43)
		(end 394.12545 -11.43)
		(stroke
			(width 0.508)
			(type default)
		)
		(layer "In1.Cu")
	)
	(gr_line
		(start 393.49045 -11.3792)
		(end 394.12545 -11.3792)
		(stroke
			(width 0.508)
			(type default)
		)
		(layer "In1.Cu")
	)
	(gr_line
		(start 393.49045 -9.414256)
		(end 394.12545 -9.414256)
		(stroke
			(width 0.508)
			(type default)
		)
		(layer "In1.Cu")
	)
	(gr_line
		(start 393.49045 -7.229856)
		(end 394.12545 -7.229856)
		(stroke
			(width 0.508)
			(type default)
		)
		(layer "In1.Cu")
	)
	(gr_line
		(start 393.49045 -7.179056)
		(end 394.12545 -7.179056)
		(stroke
			(width 0.508)
			(type default)
		)
		(layer "In1.Cu")
	)
	(gr_line
		(start 393.49045 -5.214112)
		(end 394.12545 -5.214112)
		(stroke
			(width 0.508)
			(type default)
		)
		(layer "In1.Cu")
	)
	(gr_line
		(start 393.49045 -3.029712)
		(end 394.12545 -3.029712)
		(stroke
			(width 0.508)
			(type default)
		)
		(layer "In1.Cu")
	)
	(gr_line
		(start 393.49045 -2.978912)
		(end 394.12545 -2.978912)
		(stroke
			(width 0.508)
			(type default)
		)
		(layer "In1.Cu")
	)
	(gr_line
		(start 393.51585 -11.684)
		(end 394.15085 -11.684)
		(stroke
			(width 0.508)
			(type default)
		)
		(layer "In1.Cu")
	)
	(gr_line
		(start 393.51585 -7.483856)
		(end 394.15085 -7.483856)
		(stroke
			(width 0.508)
			(type default)
		)
		(layer "In1.Cu")
	)
	(gr_line
		(start 393.51585 -3.283712)
		(end 394.15085 -3.283712)
		(stroke
			(width 0.508)
			(type default)
		)
		(layer "In1.Cu")
	)
	(gr_line
		(start 393.54125 -13.6398)
		(end 393.54125 -11.3792)
		(stroke
			(width 0.254)
			(type default)
		)
		(layer "In1.Cu")
	)
	(gr_line
		(start 393.54125 -13.4874)
		(end 394.17625 -13.4874)
		(stroke
			(width 0.508)
			(type default)
		)
		(layer "In1.Cu")
	)
	(gr_line
		(start 393.54125 -11.3792)
		(end 394.17625 -11.3792)
		(stroke
			(width 0.254)
			(type default)
		)
		(layer "In1.Cu")
	)
	(gr_line
		(start 393.54125 -9.439656)
		(end 393.54125 -7.179056)
		(stroke
			(width 0.254)
			(type default)
		)
		(layer "In1.Cu")
	)
	(gr_line
		(start 393.54125 -9.287256)
		(end 394.17625 -9.287256)
		(stroke
			(width 0.508)
			(type default)
		)
		(layer "In1.Cu")
	)
	(gr_line
		(start 393.54125 -7.179056)
		(end 394.17625 -7.179056)
		(stroke
			(width 0.254)
			(type default)
		)
		(layer "In1.Cu")
	)
	(gr_line
		(start 393.54125 -5.239512)
		(end 393.54125 -2.978912)
		(stroke
			(width 0.254)
			(type default)
		)
		(layer "In1.Cu")
	)
	(gr_line
		(start 393.54125 -5.087112)
		(end 394.17625 -5.087112)
		(stroke
			(width 0.508)
			(type default)
		)
		(layer "In1.Cu")
	)
	(gr_line
		(start 393.54125 -2.978912)
		(end 394.17625 -2.978912)
		(stroke
			(width 0.254)
			(type default)
		)
		(layer "In1.Cu")
	)
	(gr_line
		(start 393.56665 -13.335)
		(end 394.20165 -13.335)
		(stroke
			(width 0.508)
			(type default)
		)
		(layer "In1.Cu")
	)
	(gr_line
		(start 393.56665 -9.134856)
		(end 394.20165 -9.134856)
		(stroke
			(width 0.508)
			(type default)
		)
		(layer "In1.Cu")
	)
	(gr_line
		(start 393.56665 -4.934712)
		(end 394.20165 -4.934712)
		(stroke
			(width 0.508)
			(type default)
		)
		(layer "In1.Cu")
	)
	(gr_line
		(start 393.59205 -13.6144)
		(end 394.22705 -13.6144)
		(stroke
			(width 0.508)
			(type default)
		)
		(layer "In1.Cu")
	)
	(gr_line
		(start 393.59205 -11.2014)
		(end 394.43025 -11.2014)
		(stroke
			(width 0.2032)
			(type default)
		)
		(layer "In1.Cu")
	)
	(gr_line
		(start 393.59205 -9.414256)
		(end 394.22705 -9.414256)
		(stroke
			(width 0.508)
			(type default)
		)
		(layer "In1.Cu")
	)
	(gr_line
		(start 393.59205 -7.001256)
		(end 394.43025 -7.001256)
		(stroke
			(width 0.2032)
			(type default)
		)
		(layer "In1.Cu")
	)
	(gr_line
		(start 393.59205 -5.214112)
		(end 394.22705 -5.214112)
		(stroke
			(width 0.508)
			(type default)
		)
		(layer "In1.Cu")
	)
	(gr_line
		(start 393.59205 -2.801112)
		(end 394.43025 -2.801112)
		(stroke
			(width 0.2032)
			(type default)
		)
		(layer "In1.Cu")
	)
	(gr_line
		(start 393.61745 -13.6144)
		(end 393.61745 -11.43)
		(stroke
			(width 0.254)
			(type default)
		)
		(layer "In1.Cu")
	)
	(gr_line
		(start 393.61745 -11.43)
		(end 394.10005 -11.43)
		(stroke
			(width 0.254)
			(type default)
		)
		(layer "In1.Cu")
	)
	(gr_line
		(start 393.61745 -11.2522)
		(end 394.35405 -11.2522)
		(stroke
			(width 0.254)
			(type default)
		)
		(layer "In1.Cu")
	)
	(gr_line
		(start 393.61745 -9.414256)
		(end 393.61745 -7.229856)
		(stroke
			(width 0.254)
			(type default)
		)
		(layer "In1.Cu")
	)
	(gr_line
		(start 393.61745 -7.229856)
		(end 394.10005 -7.229856)
		(stroke
			(width 0.254)
			(type default)
		)
		(layer "In1.Cu")
	)
	(gr_line
		(start 393.61745 -7.052056)
		(end 394.35405 -7.052056)
		(stroke
			(width 0.254)
			(type default)
		)
		(layer "In1.Cu")
	)
	(gr_line
		(start 393.61745 -5.214112)
		(end 393.61745 -3.029712)
		(stroke
			(width 0.254)
			(type default)
		)
		(layer "In1.Cu")
	)
	(gr_line
		(start 393.61745 -3.029712)
		(end 394.10005 -3.029712)
		(stroke
			(width 0.254)
			(type default)
		)
		(layer "In1.Cu")
	)
	(gr_line
		(start 393.61745 -2.851912)
		(end 394.35405 -2.851912)
		(stroke
			(width 0.254)
			(type default)
		)
		(layer "In1.Cu")
	)
	(gr_line
		(start 393.635992 -11.36523)
		(end 394.270992 -11.36523)
		(stroke
			(width 0.508)
			(type default)
		)
		(layer "In1.Cu")
	)
	(gr_line
		(start 393.635992 -7.165086)
		(end 394.270992 -7.165086)
		(stroke
			(width 0.508)
			(type default)
		)
		(layer "In1.Cu")
	)
	(gr_line
		(start 393.635992 -2.964942)
		(end 394.270992 -2.964942)
		(stroke
			(width 0.508)
			(type default)
		)
		(layer "In1.Cu")
	)
	(gr_line
		(start 393.64285 -13.6144)
		(end 394.27785 -13.6144)
		(stroke
			(width 0.508)
			(type default)
		)
		(layer "In1.Cu")
	)
	(gr_line
		(start 393.64285 -13.4874)
		(end 393.64285 -11.5062)
		(stroke
			(width 0.762)
			(type default)
		)
		(layer "In1.Cu")
	)
	(gr_line
		(start 393.64285 -11.5062)
		(end 394.27785 -11.5062)
		(stroke
			(width 0.508)
			(type default)
		)
		(layer "In1.Cu")
	)
	(gr_line
		(start 393.64285 -9.414256)
		(end 394.27785 -9.414256)
		(stroke
			(width 0.508)
			(type default)
		)
		(layer "In1.Cu")
	)
	(gr_line
		(start 393.64285 -9.287256)
		(end 393.64285 -7.306056)
		(stroke
			(width 0.762)
			(type default)
		)
		(layer "In1.Cu")
	)
	(gr_line
		(start 393.64285 -7.306056)
		(end 394.27785 -7.306056)
		(stroke
			(width 0.508)
			(type default)
		)
		(layer "In1.Cu")
	)
	(gr_line
		(start 393.64285 -5.214112)
		(end 394.27785 -5.214112)
		(stroke
			(width 0.508)
			(type default)
		)
		(layer "In1.Cu")
	)
	(gr_line
		(start 393.64285 -5.087112)
		(end 393.64285 -3.105912)
		(stroke
			(width 0.762)
			(type default)
		)
		(layer "In1.Cu")
	)
	(gr_line
		(start 393.64285 -3.105912)
		(end 394.27785 -3.105912)
		(stroke
			(width 0.508)
			(type default)
		)
		(layer "In1.Cu")
	)
	(gr_line
		(start 393.69365 -13.5382)
		(end 393.69365 -11.5062)
		(stroke
			(width 0.254)
			(type default)
		)
		(layer "In1.Cu")
	)
	(gr_line
		(start 393.69365 -11.5062)
		(end 394.02385 -11.5062)
		(stroke
			(width 0.254)
			(type default)
		)
		(layer "In1.Cu")
	)
	(gr_line
		(start 393.69365 -9.338056)
		(end 393.69365 -7.306056)
		(stroke
			(width 0.254)
			(type default)
		)
		(layer "In1.Cu")
	)
	(gr_line
		(start 393.69365 -7.306056)
		(end 394.02385 -7.306056)
		(stroke
			(width 0.254)
			(type default)
		)
		(layer "In1.Cu")
	)
	(gr_line
		(start 393.69365 -5.137912)
		(end 393.69365 -3.105912)
		(stroke
			(width 0.254)
			(type default)
		)
		(layer "In1.Cu")
	)
	(gr_line
		(start 393.69365 -3.105912)
		(end 394.02385 -3.105912)
		(stroke
			(width 0.254)
			(type default)
		)
		(layer "In1.Cu")
	)
	(gr_line
		(start 393.79525 -13.462)
		(end 393.79525 -11.6586)
		(stroke
			(width 0.254)
			(type default)
		)
		(layer "In1.Cu")
	)
	(gr_line
		(start 393.79525 -13.462)
		(end 393.79525 -11.4808)
		(stroke
			(width 0.762)
			(type default)
		)
		(layer "In1.Cu")
	)
	(gr_line
		(start 393.79525 -11.6586)
		(end 393.89685 -11.6586)
		(stroke
			(width 0.254)
			(type default)
		)
		(layer "In1.Cu")
	)
	(gr_line
		(start 393.79525 -9.261856)
		(end 393.79525 -7.458456)
		(stroke
			(width 0.254)
			(type default)
		)
		(layer "In1.Cu")
	)
	(gr_line
		(start 393.79525 -9.261856)
		(end 393.79525 -7.280656)
		(stroke
			(width 0.762)
			(type default)
		)
		(layer "In1.Cu")
	)
	(gr_line
		(start 393.79525 -7.458456)
		(end 393.89685 -7.458456)
		(stroke
			(width 0.254)
			(type default)
		)
		(layer "In1.Cu")
	)
	(gr_line
		(start 393.79525 -5.061712)
		(end 393.79525 -3.258312)
		(stroke
			(width 0.254)
			(type default)
		)
		(layer "In1.Cu")
	)
	(gr_line
		(start 393.79525 -5.061712)
		(end 393.79525 -3.080512)
		(stroke
			(width 0.762)
			(type default)
		)
		(layer "In1.Cu")
	)
	(gr_line
		(start 393.79525 -3.258312)
		(end 393.89685 -3.258312)
		(stroke
			(width 0.254)
			(type default)
		)
		(layer "In1.Cu")
	)
	(gr_line
		(start 393.89685 -29.337)
		(end 394.73505 -29.337)
		(stroke
			(width 0.1016)
			(type default)
		)
		(layer "In1.Cu")
	)
	(gr_line
		(start 393.89685 -27.4828)
		(end 393.89685 -29.337)
		(stroke
			(width 0.1016)
			(type default)
		)
		(layer "In1.Cu")
	)
	(gr_line
		(start 393.89685 -13.5636)
		(end 393.84605 -13.5636)
		(stroke
			(width 0.254)
			(type default)
		)
		(layer "In1.Cu")
	)
	(gr_line
		(start 393.89685 -11.6586)
		(end 393.89685 -13.5636)
		(stroke
			(width 0.254)
			(type default)
		)
		(layer "In1.Cu")
	)
	(gr_line
		(start 393.89685 -9.363456)
		(end 393.84605 -9.363456)
		(stroke
			(width 0.254)
			(type default)
		)
		(layer "In1.Cu")
	)
	(gr_line
		(start 393.89685 -7.458456)
		(end 393.89685 -9.363456)
		(stroke
			(width 0.254)
			(type default)
		)
		(layer "In1.Cu")
	)
	(gr_line
		(start 393.89685 -5.163312)
		(end 393.84605 -5.163312)
		(stroke
			(width 0.254)
			(type default)
		)
		(layer "In1.Cu")
	)
	(gr_line
		(start 393.89685 -3.258312)
		(end 393.89685 -5.163312)
		(stroke
			(width 0.254)
			(type default)
		)
		(layer "In1.Cu")
	)
	(gr_line
		(start 393.94765 -29.2354)
		(end 393.94765 -27.559)
		(stroke
			(width 0.2032)
			(type default)
		)
		(layer "In1.Cu")
	)
	(gr_line
		(start 393.94765 -27.559)
		(end 395.01445 -27.559)
		(stroke
			(width 0.2032)
			(type default)
		)
		(layer "In1.Cu")
	)
	(gr_line
		(start 393.94765 -13.4874)
		(end 393.94765 -11.5062)
		(stroke
			(width 0.762)
			(type default)
		)
		(layer "In1.Cu")
	)
	(gr_line
		(start 393.94765 -9.287256)
		(end 393.94765 -7.306056)
		(stroke
			(width 0.762)
			(type default)
		)
		(layer "In1.Cu")
	)
	(gr_line
		(start 393.94765 -5.087112)
		(end 393.94765 -3.105912)
		(stroke
			(width 0.762)
			(type default)
		)
		(layer "In1.Cu")
	)
	(gr_line
		(start 393.97305 -29.2608)
		(end 394.96365 -29.2608)
		(stroke
			(width 0.2032)
			(type default)
		)
		(layer "In1.Cu")
	)
	(gr_line
		(start 393.97305 -29.2354)
		(end 393.97305 -29.2608)
		(stroke
			(width 0.2032)
			(type default)
		)
		(layer "In1.Cu")
	)
	(gr_line
		(start 394.02385 -29.1846)
		(end 394.96365 -29.1846)
		(stroke
			(width 0.2032)
			(type default)
		)
		(layer "In1.Cu")
	)
	(gr_line
		(start 394.02385 -27.6098)
		(end 394.02385 -29.1846)
		(stroke
			(width 0.2032)
			(type default)
		)
		(layer "In1.Cu")
	)
	(gr_line
		(start 394.02385 -13.462)
		(end 393.79525 -13.462)
		(stroke
			(width 0.254)
			(type default)
		)
		(layer "In1.Cu")
	)
	(gr_line
		(start 394.02385 -11.5062)
		(end 394.02385 -13.462)
		(stroke
			(width 0.254)
			(type default)
		)
		(layer "In1.Cu")
	)
	(gr_line
		(start 394.02385 -9.261856)
		(end 393.79525 -9.261856)
		(stroke
			(width 0.254)
			(type default)
		)
		(layer "In1.Cu")
	)
	(gr_line
		(start 394.02385 -7.306056)
		(end 394.02385 -9.261856)
		(stroke
			(width 0.254)
			(type default)
		)
		(layer "In1.Cu")
	)
	(gr_line
		(start 394.02385 -5.061712)
		(end 393.79525 -5.061712)
		(stroke
			(width 0.254)
			(type default)
		)
		(layer "In1.Cu")
	)
	(gr_line
		(start 394.02385 -3.105912)
		(end 394.02385 -5.061712)
		(stroke
			(width 0.254)
			(type default)
		)
		(layer "In1.Cu")
	)
	(gr_line
		(start 394.07465 -13.8176)
		(end 394.07465 -13.7668)
		(stroke
			(width 0.1016)
			(type default)
		)
		(layer "In1.Cu")
	)
	(gr_line
		(start 394.07465 -13.8176)
		(end 394.48105 -13.8176)
		(stroke
			(width 0.1016)
			(type default)
		)
		(layer "In1.Cu")
	)
	(gr_line
		(start 394.07465 -13.7668)
		(end 393.31265 -13.7668)
		(stroke
			(width 0.1016)
			(type default)
		)
		(layer "In1.Cu")
	)
	(gr_line
		(start 394.07465 -13.4874)
		(end 394.07465 -11.5062)
		(stroke
			(width 0.762)
			(type default)
		)
		(layer "In1.Cu")
	)
	(gr_line
		(start 394.07465 -9.617456)
		(end 394.07465 -9.566656)
		(stroke
			(width 0.1016)
			(type default)
		)
		(layer "In1.Cu")
	)
	(gr_line
		(start 394.07465 -9.617456)
		(end 394.48105 -9.617456)
		(stroke
			(width 0.1016)
			(type default)
		)
		(layer "In1.Cu")
	)
	(gr_line
		(start 394.07465 -9.566656)
		(end 393.31265 -9.566656)
		(stroke
			(width 0.1016)
			(type default)
		)
		(layer "In1.Cu")
	)
	(gr_line
		(start 394.07465 -9.287256)
		(end 394.07465 -7.306056)
		(stroke
			(width 0.762)
			(type default)
		)
		(layer "In1.Cu")
	)
	(gr_line
		(start 394.07465 -5.417312)
		(end 394.07465 -5.366512)
		(stroke
			(width 0.1016)
			(type default)
		)
		(layer "In1.Cu")
	)
	(gr_line
		(start 394.07465 -5.417312)
		(end 394.48105 -5.417312)
		(stroke
			(width 0.1016)
			(type default)
		)
		(layer "In1.Cu")
	)
	(gr_line
		(start 394.07465 -5.366512)
		(end 393.31265 -5.366512)
		(stroke
			(width 0.1016)
			(type default)
		)
		(layer "In1.Cu")
	)
	(gr_line
		(start 394.07465 -5.087112)
		(end 394.07465 -3.105912)
		(stroke
			(width 0.762)
			(type default)
		)
		(layer "In1.Cu")
	)
	(gr_line
		(start 394.10005 -29.1084)
		(end 394.10005 -27.7622)
		(stroke
			(width 0.508)
			(type default)
		)
		(layer "In1.Cu")
	)
	(gr_line
		(start 394.10005 -13.5382)
		(end 393.69365 -13.5382)
		(stroke
			(width 0.254)
			(type default)
		)
		(layer "In1.Cu")
	)
	(gr_line
		(start 394.10005 -11.43)
		(end 394.10005 -13.5382)
		(stroke
			(width 0.254)
			(type default)
		)
		(layer "In1.Cu")
	)
	(gr_line
		(start 394.10005 -9.338056)
		(end 393.69365 -9.338056)
		(stroke
			(width 0.254)
			(type default)
		)
		(layer "In1.Cu")
	)
	(gr_line
		(start 394.10005 -7.229856)
		(end 394.10005 -9.338056)
		(stroke
			(width 0.254)
			(type default)
		)
		(layer "In1.Cu")
	)
	(gr_line
		(start 394.10005 -5.137912)
		(end 393.69365 -5.137912)
		(stroke
			(width 0.254)
			(type default)
		)
		(layer "In1.Cu")
	)
	(gr_line
		(start 394.10005 -3.029712)
		(end 394.10005 -5.137912)
		(stroke
			(width 0.254)
			(type default)
		)
		(layer "In1.Cu")
	)
	(gr_line
		(start 394.12545 -29.1084)
		(end 394.78585 -29.1084)
		(stroke
			(width 0.508)
			(type default)
		)
		(layer "In1.Cu")
	)
	(gr_line
		(start 394.12545 -29.083)
		(end 394.12545 -27.7368)
		(stroke
			(width 0.508)
			(type default)
		)
		(layer "In1.Cu")
	)
	(gr_line
		(start 394.12545 -27.7114)
		(end 394.76045 -27.7114)
		(stroke
			(width 0.508)
			(type default)
		)
		(layer "In1.Cu")
	)
	(gr_line
		(start 394.15085 -29.083)
		(end 394.15085 -27.7368)
		(stroke
			(width 0.508)
			(type default)
		)
		(layer "In1.Cu")
	)
	(gr_line
		(start 394.15085 -13.4874)
		(end 394.15085 -11.5062)
		(stroke
			(width 0.762)
			(type default)
		)
		(layer "In1.Cu")
	)
	(gr_line
		(start 394.15085 -9.287256)
		(end 394.15085 -7.306056)
		(stroke
			(width 0.762)
			(type default)
		)
		(layer "In1.Cu")
	)
	(gr_line
		(start 394.15085 -5.087112)
		(end 394.15085 -3.105912)
		(stroke
			(width 0.762)
			(type default)
		)
		(layer "In1.Cu")
	)
	(gr_line
		(start 394.17625 -29.083)
		(end 394.17625 -27.7368)
		(stroke
			(width 0.508)
			(type default)
		)
		(layer "In1.Cu")
	)
	(gr_line
		(start 394.17625 -13.6144)
		(end 393.61745 -13.6144)
		(stroke
			(width 0.254)
			(type default)
		)
		(layer "In1.Cu")
	)
	(gr_line
		(start 394.17625 -11.3792)
		(end 394.17625 -13.6144)
		(stroke
			(width 0.254)
			(type default)
		)
		(layer "In1.Cu")
	)
	(gr_line
		(start 394.17625 -9.414256)
		(end 393.61745 -9.414256)
		(stroke
			(width 0.254)
			(type default)
		)
		(layer "In1.Cu")
	)
	(gr_line
		(start 394.17625 -7.179056)
		(end 394.17625 -9.414256)
		(stroke
			(width 0.254)
			(type default)
		)
		(layer "In1.Cu")
	)
	(gr_line
		(start 394.17625 -5.214112)
		(end 393.61745 -5.214112)
		(stroke
			(width 0.254)
			(type default)
		)
		(layer "In1.Cu")
	)
	(gr_line
		(start 394.17625 -2.978912)
		(end 394.17625 -5.214112)
		(stroke
			(width 0.254)
			(type default)
		)
		(layer "In1.Cu")
	)
	(gr_line
		(start 394.22705 -29.1084)
		(end 394.22705 -27.7622)
		(stroke
			(width 0.508)
			(type default)
		)
		(layer "In1.Cu")
	)
	(gr_line
		(start 394.22705 -29.083)
		(end 394.22705 -27.7368)
		(stroke
			(width 0.508)
			(type default)
		)
		(layer "In1.Cu")
	)
	(gr_line
		(start 394.25245 -13.6398)
		(end 393.54125 -13.6398)
		(stroke
			(width 0.254)
			(type default)
		)
		(layer "In1.Cu")
	)
	(gr_line
		(start 394.25245 -11.303)
		(end 394.25245 -13.6398)
		(stroke
			(width 0.254)
			(type default)
		)
		(layer "In1.Cu")
	)
	(gr_line
		(start 394.25245 -9.439656)
		(end 393.54125 -9.439656)
		(stroke
			(width 0.254)
			(type default)
		)
		(layer "In1.Cu")
	)
	(gr_line
		(start 394.25245 -7.102856)
		(end 394.25245 -9.439656)
		(stroke
			(width 0.254)
			(type default)
		)
		(layer "In1.Cu")
	)
	(gr_line
		(start 394.25245 -5.239512)
		(end 393.54125 -5.239512)
		(stroke
			(width 0.254)
			(type default)
		)
		(layer "In1.Cu")
	)
	(gr_line
		(start 394.25245 -2.902712)
		(end 394.25245 -5.239512)
		(stroke
			(width 0.254)
			(type default)
		)
		(layer "In1.Cu")
	)
	(gr_line
		(start 394.27785 -29.083)
		(end 394.27785 -27.7368)
		(stroke
			(width 0.508)
			(type default)
		)
		(layer "In1.Cu")
	)
	(gr_line
		(start 394.27785 -13.7668)
		(end 393.28725 -13.7668)
		(stroke
			(width 0.1016)
			(type default)
		)
		(layer "In1.Cu")
	)
	(gr_line
		(start 394.27785 -13.6906)
		(end 393.46505 -13.6906)
		(stroke
			(width 0.254)
			(type default)
		)
		(layer "In1.Cu")
	)
	(gr_line
		(start 394.27785 -11.2776)
		(end 394.27785 -13.6906)
		(stroke
			(width 0.254)
			(type default)
		)
		(layer "In1.Cu")
	)
	(gr_line
		(start 394.27785 -9.566656)
		(end 393.28725 -9.566656)
		(stroke
			(width 0.1016)
			(type default)
		)
		(layer "In1.Cu")
	)
	(gr_line
		(start 394.27785 -9.490456)
		(end 393.46505 -9.490456)
		(stroke
			(width 0.254)
			(type default)
		)
		(layer "In1.Cu")
	)
	(gr_line
		(start 394.27785 -7.077456)
		(end 394.27785 -9.490456)
		(stroke
			(width 0.254)
			(type default)
		)
		(layer "In1.Cu")
	)
	(gr_line
		(start 394.27785 -5.366512)
		(end 393.28725 -5.366512)
		(stroke
			(width 0.1016)
			(type default)
		)
		(layer "In1.Cu")
	)
	(gr_line
		(start 394.27785 -5.290312)
		(end 393.46505 -5.290312)
		(stroke
			(width 0.254)
			(type default)
		)
		(layer "In1.Cu")
	)
	(gr_line
		(start 394.27785 -2.877312)
		(end 394.27785 -5.290312)
		(stroke
			(width 0.254)
			(type default)
		)
		(layer "In1.Cu")
	)
	(gr_line
		(start 394.2969 -26.826972)
		(end 395.1351 -26.826972)
		(stroke
			(width 0.1016)
			(type default)
		)
		(layer "In1.Cu")
	)
	(gr_line
		(start 394.2969 -24.972772)
		(end 394.2969 -26.826972)
		(stroke
			(width 0.1016)
			(type default)
		)
		(layer "In1.Cu")
	)
	(gr_line
		(start 394.30325 -29.0576)
		(end 394.30325 -27.7114)
		(stroke
			(width 0.508)
			(type default)
		)
		(layer "In1.Cu")
	)
	(gr_line
		(start 394.30325 -13.716)
		(end 393.43965 -13.716)
		(stroke
			(width 0.254)
			(type default)
		)
		(layer "In1.Cu")
	)
	(gr_line
		(start 394.30325 -11.2522)
		(end 394.30325 -13.716)
		(stroke
			(width 0.254)
			(type default)
		)
		(layer "In1.Cu")
	)
	(gr_line
		(start 394.30325 -9.515856)
		(end 393.43965 -9.515856)
		(stroke
			(width 0.254)
			(type default)
		)
		(layer "In1.Cu")
	)
	(gr_line
		(start 394.30325 -7.052056)
		(end 394.30325 -9.515856)
		(stroke
			(width 0.254)
			(type default)
		)
		(layer "In1.Cu")
	)
	(gr_line
		(start 394.30325 -5.315712)
		(end 393.43965 -5.315712)
		(stroke
			(width 0.254)
			(type default)
		)
		(layer "In1.Cu")
	)
	(gr_line
		(start 394.30325 -2.851912)
		(end 394.30325 -5.315712)
		(stroke
			(width 0.254)
			(type default)
		)
		(layer "In1.Cu")
	)
	(gr_line
		(start 394.32865 -29.083)
		(end 394.32865 -27.7368)
		(stroke
			(width 0.508)
			(type default)
		)
		(layer "In1.Cu")
	)
	(gr_line
		(start 394.3477 -26.725372)
		(end 394.3477 -25.048972)
		(stroke
			(width 0.2032)
			(type default)
		)
		(layer "In1.Cu")
	)
	(gr_line
		(start 394.3477 -25.048972)
		(end 395.4145 -25.048972)
		(stroke
			(width 0.2032)
			(type default)
		)
		(layer "In1.Cu")
	)
	(gr_line
		(start 394.35405 -29.083)
		(end 394.35405 -27.7368)
		(stroke
			(width 0.508)
			(type default)
		)
		(layer "In1.Cu")
	)
	(gr_line
		(start 394.35405 -13.7414)
		(end 393.41425 -13.7414)
		(stroke
			(width 0.254)
			(type default)
		)
		(layer "In1.Cu")
	)
	(gr_line
		(start 394.35405 -11.2522)
		(end 394.35405 -13.7414)
		(stroke
			(width 0.254)
			(type default)
		)
		(layer "In1.Cu")
	)
	(gr_line
		(start 394.35405 -9.541256)
		(end 393.41425 -9.541256)
		(stroke
			(width 0.254)
			(type default)
		)
		(layer "In1.Cu")
	)
	(gr_line
		(start 394.35405 -7.052056)
		(end 394.35405 -9.541256)
		(stroke
			(width 0.254)
			(type default)
		)
		(layer "In1.Cu")
	)
	(gr_line
		(start 394.35405 -5.341112)
		(end 393.41425 -5.341112)
		(stroke
			(width 0.254)
			(type default)
		)
		(layer "In1.Cu")
	)
	(gr_line
		(start 394.35405 -2.851912)
		(end 394.35405 -5.341112)
		(stroke
			(width 0.254)
			(type default)
		)
		(layer "In1.Cu")
	)
	(gr_line
		(start 394.3731 -26.750772)
		(end 395.3637 -26.750772)
		(stroke
			(width 0.2032)
			(type default)
		)
		(layer "In1.Cu")
	)
	(gr_line
		(start 394.3731 -26.725372)
		(end 394.3731 -26.750772)
		(stroke
			(width 0.2032)
			(type default)
		)
		(layer "In1.Cu")
	)
	(gr_line
		(start 394.37945 -29.083)
		(end 394.37945 -27.7368)
		(stroke
			(width 0.508)
			(type default)
		)
		(layer "In1.Cu")
	)
	(gr_line
		(start 394.37945 -13.7414)
		(end 393.41425 -13.7414)
		(stroke
			(width 0.2032)
			(type default)
		)
		(layer "In1.Cu")
	)
	(gr_line
		(start 394.37945 -11.2014)
		(end 394.37945 -13.7414)
		(stroke
			(width 0.2032)
			(type default)
		)
		(layer "In1.Cu")
	)
	(gr_line
		(start 394.37945 -9.541256)
		(end 393.41425 -9.541256)
		(stroke
			(width 0.2032)
			(type default)
		)
		(layer "In1.Cu")
	)
	(gr_line
		(start 394.37945 -7.001256)
		(end 394.37945 -9.541256)
		(stroke
			(width 0.2032)
			(type default)
		)
		(layer "In1.Cu")
	)
	(gr_line
		(start 394.37945 -5.341112)
		(end 393.41425 -5.341112)
		(stroke
			(width 0.2032)
			(type default)
		)
		(layer "In1.Cu")
	)
	(gr_line
		(start 394.37945 -2.801112)
		(end 394.37945 -5.341112)
		(stroke
			(width 0.2032)
			(type default)
		)
		(layer "In1.Cu")
	)
	(gr_line
		(start 394.4239 -26.674572)
		(end 395.3637 -26.674572)
		(stroke
			(width 0.2032)
			(type default)
		)
		(layer "In1.Cu")
	)
	(gr_line
		(start 394.4239 -25.099772)
		(end 394.4239 -26.674572)
		(stroke
			(width 0.2032)
			(type default)
		)
		(layer "In1.Cu")
	)
	(gr_line
		(start 394.43025 -29.083)
		(end 394.43025 -27.7368)
		(stroke
			(width 0.508)
			(type default)
		)
		(layer "In1.Cu")
	)
	(gr_line
		(start 394.43025 -13.7668)
		(end 393.36345 -13.7668)
		(stroke
			(width 0.2032)
			(type default)
		)
		(layer "In1.Cu")
	)
	(gr_line
		(start 394.43025 -11.2014)
		(end 394.43025 -13.7668)
		(stroke
			(width 0.2032)
			(type default)
		)
		(layer "In1.Cu")
	)
	(gr_line
		(start 394.43025 -9.566656)
		(end 393.36345 -9.566656)
		(stroke
			(width 0.2032)
			(type default)
		)
		(layer "In1.Cu")
	)
	(gr_line
		(start 394.43025 -7.001256)
		(end 394.43025 -9.566656)
		(stroke
			(width 0.2032)
			(type default)
		)
		(layer "In1.Cu")
	)
	(gr_line
		(start 394.43025 -5.366512)
		(end 393.36345 -5.366512)
		(stroke
			(width 0.2032)
			(type default)
		)
		(layer "In1.Cu")
	)
	(gr_line
		(start 394.43025 -2.801112)
		(end 394.43025 -5.366512)
		(stroke
			(width 0.2032)
			(type default)
		)
		(layer "In1.Cu")
	)
	(gr_line
		(start 394.45565 -29.083)
		(end 394.45565 -27.7368)
		(stroke
			(width 0.508)
			(type default)
		)
		(layer "In1.Cu")
	)
	(gr_line
		(start 394.45565 -13.7668)
		(end 393.33805 -13.7668)
		(stroke
			(width 0.1016)
			(type default)
		)
		(layer "In1.Cu")
	)
	(gr_line
		(start 394.45565 -11.176)
		(end 394.45565 -13.7668)
		(stroke
			(width 0.1016)
			(type default)
		)
		(layer "In1.Cu")
	)
	(gr_line
		(start 394.45565 -9.566656)
		(end 393.33805 -9.566656)
		(stroke
			(width 0.1016)
			(type default)
		)
		(layer "In1.Cu")
	)
	(gr_line
		(start 394.45565 -6.975856)
		(end 394.45565 -9.566656)
		(stroke
			(width 0.1016)
			(type default)
		)
		(layer "In1.Cu")
	)
	(gr_line
		(start 394.45565 -5.366512)
		(end 393.33805 -5.366512)
		(stroke
			(width 0.1016)
			(type default)
		)
		(layer "In1.Cu")
	)
	(gr_line
		(start 394.45565 -2.775712)
		(end 394.45565 -5.366512)
		(stroke
			(width 0.1016)
			(type default)
		)
		(layer "In1.Cu")
	)
	(gr_line
		(start 394.48105 -29.083)
		(end 394.48105 -27.7368)
		(stroke
			(width 0.508)
			(type default)
		)
		(layer "In1.Cu")
	)
	(gr_line
		(start 394.48105 -13.8176)
		(end 394.07465 -13.8176)
		(stroke
			(width 0.1016)
			(type default)
		)
		(layer "In1.Cu")
	)
	(gr_line
		(start 394.48105 -13.8176)
		(end 394.48105 -11.1506)
		(stroke
			(width 0.1016)
			(type default)
		)
		(layer "In1.Cu")
	)
	(gr_line
		(start 394.48105 -11.1506)
		(end 393.28725 -11.1506)
		(stroke
			(width 0.1016)
			(type default)
		)
		(layer "In1.Cu")
	)
	(gr_line
		(start 394.48105 -11.1506)
		(end 394.48105 -13.8176)
		(stroke
			(width 0.1016)
			(type default)
		)
		(layer "In1.Cu")
	)
	(gr_line
		(start 394.48105 -9.617456)
		(end 394.07465 -9.617456)
		(stroke
			(width 0.1016)
			(type default)
		)
		(layer "In1.Cu")
	)
	(gr_line
		(start 394.48105 -9.617456)
		(end 394.48105 -6.950456)
		(stroke
			(width 0.1016)
			(type default)
		)
		(layer "In1.Cu")
	)
	(gr_line
		(start 394.48105 -6.950456)
		(end 393.28725 -6.950456)
		(stroke
			(width 0.1016)
			(type default)
		)
		(layer "In1.Cu")
	)
	(gr_line
		(start 394.48105 -6.950456)
		(end 394.48105 -9.617456)
		(stroke
			(width 0.1016)
			(type default)
		)
		(layer "In1.Cu")
	)
	(gr_line
		(start 394.48105 -5.417312)
		(end 394.07465 -5.417312)
		(stroke
			(width 0.1016)
			(type default)
		)
		(layer "In1.Cu")
	)
	(gr_line
		(start 394.48105 -5.417312)
		(end 394.48105 -2.750312)
		(stroke
			(width 0.1016)
			(type default)
		)
		(layer "In1.Cu")
	)
	(gr_line
		(start 394.48105 -2.750312)
		(end 393.28725 -2.750312)
		(stroke
			(width 0.1016)
			(type default)
		)
		(layer "In1.Cu")
	)
	(gr_line
		(start 394.48105 -2.750312)
		(end 394.48105 -5.417312)
		(stroke
			(width 0.1016)
			(type default)
		)
		(layer "In1.Cu")
	)
	(gr_line
		(start 394.5001 -26.598372)
		(end 394.5001 -25.252172)
		(stroke
			(width 0.508)
			(type default)
		)
		(layer "In1.Cu")
	)
	(gr_line
		(start 394.50645 -29.083)
		(end 394.50645 -27.7368)
		(stroke
			(width 0.508)
			(type default)
		)
		(layer "In1.Cu")
	)
	(gr_line
		(start 394.5255 -26.598372)
		(end 395.1859 -26.598372)
		(stroke
			(width 0.508)
			(type default)
		)
		(layer "In1.Cu")
	)
	(gr_line
		(start 394.5255 -26.572972)
		(end 394.5255 -25.226772)
		(stroke
			(width 0.508)
			(type default)
		)
		(layer "In1.Cu")
	)
	(gr_line
		(start 394.5255 -25.201372)
		(end 395.1605 -25.201372)
		(stroke
			(width 0.508)
			(type default)
		)
		(layer "In1.Cu")
	)
	(gr_line
		(start 394.53185 -29.1084)
		(end 394.53185 -27.7622)
		(stroke
			(width 0.508)
			(type default)
		)
		(layer "In1.Cu")
	)
	(gr_line
		(start 394.5509 -26.572972)
		(end 394.5509 -25.226772)
		(stroke
			(width 0.508)
			(type default)
		)
		(layer "In1.Cu")
	)
	(gr_line
		(start 394.55725 -29.1084)
		(end 394.55725 -27.7622)
		(stroke
			(width 0.508)
			(type default)
		)
		(layer "In1.Cu")
	)
	(gr_line
		(start 394.55725 -29.083)
		(end 394.55725 -27.7368)
		(stroke
			(width 0.508)
			(type default)
		)
		(layer "In1.Cu")
	)
	(gr_line
		(start 394.5763 -26.572972)
		(end 394.5763 -25.226772)
		(stroke
			(width 0.508)
			(type default)
		)
		(layer "In1.Cu")
	)
	(gr_line
		(start 394.58265 -29.083)
		(end 394.58265 -27.7368)
		(stroke
			(width 0.508)
			(type default)
		)
		(layer "In1.Cu")
	)
	(gr_line
		(start 394.60805 -29.083)
		(end 394.60805 -27.7368)
		(stroke
			(width 0.508)
			(type default)
		)
		(layer "In1.Cu")
	)
	(gr_line
		(start 394.6271 -26.598372)
		(end 394.6271 -25.252172)
		(stroke
			(width 0.508)
			(type default)
		)
		(layer "In1.Cu")
	)
	(gr_line
		(start 394.6271 -26.572972)
		(end 394.6271 -25.226772)
		(stroke
			(width 0.508)
			(type default)
		)
		(layer "In1.Cu")
	)
	(gr_line
		(start 394.63345 -29.083)
		(end 394.63345 -27.7368)
		(stroke
			(width 0.508)
			(type default)
		)
		(layer "In1.Cu")
	)
	(gr_line
		(start 394.65885 -29.1084)
		(end 394.65885 -27.7622)
		(stroke
			(width 0.508)
			(type default)
		)
		(layer "In1.Cu")
	)
	(gr_line
		(start 394.65885 -29.083)
		(end 394.65885 -27.7368)
		(stroke
			(width 0.508)
			(type default)
		)
		(layer "In1.Cu")
	)
	(gr_line
		(start 394.6779 -26.572972)
		(end 394.6779 -25.226772)
		(stroke
			(width 0.508)
			(type default)
		)
		(layer "In1.Cu")
	)
	(gr_line
		(start 394.68425 -29.1084)
		(end 394.68425 -27.7622)
		(stroke
			(width 0.508)
			(type default)
		)
		(layer "In1.Cu")
	)
	(gr_line
		(start 394.68425 -29.083)
		(end 394.68425 -27.7368)
		(stroke
			(width 0.508)
			(type default)
		)
		(layer "In1.Cu")
	)
	(gr_line
		(start 394.7033 -26.547572)
		(end 394.7033 -25.201372)
		(stroke
			(width 0.508)
			(type default)
		)
		(layer "In1.Cu")
	)
	(gr_line
		(start 394.70965 -29.1084)
		(end 394.70965 -27.7622)
		(stroke
			(width 0.508)
			(type default)
		)
		(layer "In1.Cu")
	)
	(gr_line
		(start 394.7287 -26.572972)
		(end 394.7287 -25.226772)
		(stroke
			(width 0.508)
			(type default)
		)
		(layer "In1.Cu")
	)
	(gr_line
		(start 394.73505 -29.337)
		(end 395.06525 -29.337)
		(stroke
			(width 0.1016)
			(type default)
		)
		(layer "In1.Cu")
	)
	(gr_line
		(start 394.73505 -29.083)
		(end 394.73505 -27.7368)
		(stroke
			(width 0.508)
			(type default)
		)
		(layer "In1.Cu")
	)
	(gr_line
		(start 394.7541 -26.572972)
		(end 394.7541 -25.226772)
		(stroke
			(width 0.508)
			(type default)
		)
		(layer "In1.Cu")
	)
	(gr_line
		(start 394.76045 -29.1084)
		(end 394.76045 -27.7622)
		(stroke
			(width 0.508)
			(type default)
		)
		(layer "In1.Cu")
	)
	(gr_line
		(start 394.76045 -29.083)
		(end 394.76045 -27.7368)
		(stroke
			(width 0.508)
			(type default)
		)
		(layer "In1.Cu")
	)
	(gr_line
		(start 394.7795 -26.572972)
		(end 394.7795 -25.226772)
		(stroke
			(width 0.508)
			(type default)
		)
		(layer "In1.Cu")
	)
	(gr_line
		(start 394.78585 -29.1084)
		(end 394.78585 -27.7622)
		(stroke
			(width 0.508)
			(type default)
		)
		(layer "In1.Cu")
	)
	(gr_line
		(start 394.8303 -26.572972)
		(end 394.8303 -25.226772)
		(stroke
			(width 0.508)
			(type default)
		)
		(layer "In1.Cu")
	)
	(gr_line
		(start 394.8557 -26.572972)
		(end 394.8557 -25.226772)
		(stroke
			(width 0.508)
			(type default)
		)
		(layer "In1.Cu")
	)
	(gr_line
		(start 394.86205 -29.1084)
		(end 394.86205 -27.7622)
		(stroke
			(width 0.508)
			(type default)
		)
		(layer "In1.Cu")
	)
	(gr_line
		(start 394.8811 -26.572972)
		(end 394.8811 -25.226772)
		(stroke
			(width 0.508)
			(type default)
		)
		(layer "In1.Cu")
	)
	(gr_line
		(start 394.9065 -26.572972)
		(end 394.9065 -25.226772)
		(stroke
			(width 0.508)
			(type default)
		)
		(layer "In1.Cu")
	)
	(gr_line
		(start 394.9319 -26.598372)
		(end 394.9319 -25.252172)
		(stroke
			(width 0.508)
			(type default)
		)
		(layer "In1.Cu")
	)
	(gr_line
		(start 394.9573 -26.598372)
		(end 394.9573 -25.252172)
		(stroke
			(width 0.508)
			(type default)
		)
		(layer "In1.Cu")
	)
	(gr_line
		(start 394.9573 -26.572972)
		(end 394.9573 -25.226772)
		(stroke
			(width 0.508)
			(type default)
		)
		(layer "In1.Cu")
	)
	(gr_line
		(start 394.96365 -29.2608)
		(end 394.96365 -27.6098)
		(stroke
			(width 0.2032)
			(type default)
		)
		(layer "In1.Cu")
	)
	(gr_line
		(start 394.96365 -29.2354)
		(end 393.94765 -29.2354)
		(stroke
			(width 0.2032)
			(type default)
		)
		(layer "In1.Cu")
	)
	(gr_line
		(start 394.96365 -29.1846)
		(end 394.96365 -29.2354)
		(stroke
			(width 0.2032)
			(type default)
		)
		(layer "In1.Cu")
	)
	(gr_line
		(start 394.96365 -27.6098)
		(end 394.02385 -27.6098)
		(stroke
			(width 0.2032)
			(type default)
		)
		(layer "In1.Cu")
	)
	(gr_line
		(start 394.9827 -26.572972)
		(end 394.9827 -25.226772)
		(stroke
			(width 0.508)
			(type default)
		)
		(layer "In1.Cu")
	)
	(gr_line
		(start 395.0081 -26.572972)
		(end 395.0081 -25.226772)
		(stroke
			(width 0.508)
			(type default)
		)
		(layer "In1.Cu")
	)
	(gr_line
		(start 395.01445 -29.2354)
		(end 393.97305 -29.2354)
		(stroke
			(width 0.2032)
			(type default)
		)
		(layer "In1.Cu")
	)
	(gr_line
		(start 395.01445 -27.559)
		(end 395.01445 -29.2354)
		(stroke
			(width 0.2032)
			(type default)
		)
		(layer "In1.Cu")
	)
	(gr_line
		(start 395.0335 -26.572972)
		(end 395.0335 -25.226772)
		(stroke
			(width 0.508)
			(type default)
		)
		(layer "In1.Cu")
	)
	(gr_line
		(start 395.0589 -26.598372)
		(end 395.0589 -25.252172)
		(stroke
			(width 0.508)
			(type default)
		)
		(layer "In1.Cu")
	)
	(gr_line
		(start 395.0589 -26.572972)
		(end 395.0589 -25.226772)
		(stroke
			(width 0.508)
			(type default)
		)
		(layer "In1.Cu")
	)
	(gr_line
		(start 395.06525 -29.337)
		(end 395.06525 -27.4828)
		(stroke
			(width 0.1016)
			(type default)
		)
		(layer "In1.Cu")
	)
	(gr_line
		(start 395.06525 -27.4828)
		(end 393.89685 -27.4828)
		(stroke
			(width 0.1016)
			(type default)
		)
		(layer "In1.Cu")
	)
	(gr_line
		(start 395.0843 -26.598372)
		(end 395.0843 -25.252172)
		(stroke
			(width 0.508)
			(type default)
		)
		(layer "In1.Cu")
	)
	(gr_line
		(start 395.0843 -26.572972)
		(end 395.0843 -25.226772)
		(stroke
			(width 0.508)
			(type default)
		)
		(layer "In1.Cu")
	)
	(gr_line
		(start 395.1097 -26.598372)
		(end 395.1097 -25.252172)
		(stroke
			(width 0.508)
			(type default)
		)
		(layer "In1.Cu")
	)
	(gr_line
		(start 395.1351 -26.826972)
		(end 395.4653 -26.826972)
		(stroke
			(width 0.1016)
			(type default)
		)
		(layer "In1.Cu")
	)
	(gr_line
		(start 395.1351 -26.572972)
		(end 395.1351 -25.226772)
		(stroke
			(width 0.508)
			(type default)
		)
		(layer "In1.Cu")
	)
	(gr_line
		(start 395.14526 -32.9184)
		(end 393.87526 -32.9184)
		(stroke
			(width 0.7874)
			(type default)
		)
		(layer "In1.Cu")
	)
	(gr_line
		(start 395.1605 -26.598372)
		(end 395.1605 -25.252172)
		(stroke
			(width 0.508)
			(type default)
		)
		(layer "In1.Cu")
	)
	(gr_line
		(start 395.1605 -26.572972)
		(end 395.1605 -25.226772)
		(stroke
			(width 0.508)
			(type default)
		)
		(layer "In1.Cu")
	)
	(gr_line
		(start 395.1859 -26.598372)
		(end 395.1859 -25.252172)
		(stroke
			(width 0.508)
			(type default)
		)
		(layer "In1.Cu")
	)
	(gr_line
		(start 395.2621 -26.598372)
		(end 395.2621 -25.252172)
		(stroke
			(width 0.508)
			(type default)
		)
		(layer "In1.Cu")
	)
	(gr_line
		(start 395.287246 -12.563348)
		(end 396.074646 -12.563348)
		(stroke
			(width 0.1016)
			(type default)
		)
		(layer "In1.Cu")
	)
	(gr_line
		(start 395.287246 -12.512548)
		(end 395.287246 -9.896348)
		(stroke
			(width 0.1016)
			(type default)
		)
		(layer "In1.Cu")
	)
	(gr_line
		(start 395.287246 -12.463272)
		(end 396.074646 -12.463272)
		(stroke
			(width 0.1016)
			(type default)
		)
		(layer "In1.Cu")
	)
	(gr_line
		(start 395.287246 -12.412472)
		(end 395.287246 -9.796272)
		(stroke
			(width 0.1016)
			(type default)
		)
		(layer "In1.Cu")
	)
	(gr_line
		(start 395.287246 -9.896348)
		(end 395.287246 -12.563348)
		(stroke
			(width 0.1016)
			(type default)
		)
		(layer "In1.Cu")
	)
	(gr_line
		(start 395.287246 -9.896348)
		(end 396.481046 -9.896348)
		(stroke
			(width 0.1016)
			(type default)
		)
		(layer "In1.Cu")
	)
	(gr_line
		(start 395.287246 -9.796272)
		(end 395.287246 -12.463272)
		(stroke
			(width 0.1016)
			(type default)
		)
		(layer "In1.Cu")
	)
	(gr_line
		(start 395.287246 -9.796272)
		(end 396.481046 -9.796272)
		(stroke
			(width 0.1016)
			(type default)
		)
		(layer "In1.Cu")
	)
	(gr_line
		(start 395.287246 -8.363204)
		(end 396.074646 -8.363204)
		(stroke
			(width 0.1016)
			(type default)
		)
		(layer "In1.Cu")
	)
	(gr_line
		(start 395.287246 -8.312404)
		(end 395.287246 -5.696204)
		(stroke
			(width 0.1016)
			(type default)
		)
		(layer "In1.Cu")
	)
	(gr_line
		(start 395.287246 -8.263128)
		(end 396.074646 -8.263128)
		(stroke
			(width 0.1016)
			(type default)
		)
		(layer "In1.Cu")
	)
	(gr_line
		(start 395.287246 -8.212328)
		(end 395.287246 -5.596128)
		(stroke
			(width 0.1016)
			(type default)
		)
		(layer "In1.Cu")
	)
	(gr_line
		(start 395.287246 -5.696204)
		(end 395.287246 -8.363204)
		(stroke
			(width 0.1016)
			(type default)
		)
		(layer "In1.Cu")
	)
	(gr_line
		(start 395.287246 -5.696204)
		(end 396.481046 -5.696204)
		(stroke
			(width 0.1016)
			(type default)
		)
		(layer "In1.Cu")
	)
	(gr_line
		(start 395.287246 -5.596128)
		(end 395.287246 -8.263128)
		(stroke
			(width 0.1016)
			(type default)
		)
		(layer "In1.Cu")
	)
	(gr_line
		(start 395.287246 -5.596128)
		(end 396.481046 -5.596128)
		(stroke
			(width 0.1016)
			(type default)
		)
		(layer "In1.Cu")
	)
	(gr_line
		(start 395.287246 -4.16306)
		(end 396.074646 -4.16306)
		(stroke
			(width 0.1016)
			(type default)
		)
		(layer "In1.Cu")
	)
	(gr_line
		(start 395.287246 -4.11226)
		(end 395.287246 -1.49606)
		(stroke
			(width 0.1016)
			(type default)
		)
		(layer "In1.Cu")
	)
	(gr_line
		(start 395.287246 -4.062984)
		(end 396.074646 -4.062984)
		(stroke
			(width 0.1016)
			(type default)
		)
		(layer "In1.Cu")
	)
	(gr_line
		(start 395.287246 -4.012184)
		(end 395.287246 -1.395984)
		(stroke
			(width 0.1016)
			(type default)
		)
		(layer "In1.Cu")
	)
	(gr_line
		(start 395.287246 -1.49606)
		(end 395.287246 -4.16306)
		(stroke
			(width 0.1016)
			(type default)
		)
		(layer "In1.Cu")
	)
	(gr_line
		(start 395.287246 -1.49606)
		(end 396.481046 -1.49606)
		(stroke
			(width 0.1016)
			(type default)
		)
		(layer "In1.Cu")
	)
	(gr_line
		(start 395.287246 -1.395984)
		(end 395.287246 -4.062984)
		(stroke
			(width 0.1016)
			(type default)
		)
		(layer "In1.Cu")
	)
	(gr_line
		(start 395.287246 -1.395984)
		(end 396.481046 -1.395984)
		(stroke
			(width 0.1016)
			(type default)
		)
		(layer "In1.Cu")
	)
	(gr_line
		(start 395.312646 -12.512548)
		(end 395.312646 -9.921748)
		(stroke
			(width 0.1016)
			(type default)
		)
		(layer "In1.Cu")
	)
	(gr_line
		(start 395.312646 -12.412472)
		(end 395.312646 -9.821672)
		(stroke
			(width 0.1016)
			(type default)
		)
		(layer "In1.Cu")
	)
	(gr_line
		(start 395.312646 -9.921748)
		(end 396.455646 -9.921748)
		(stroke
			(width 0.1016)
			(type default)
		)
		(layer "In1.Cu")
	)
	(gr_line
		(start 395.312646 -9.821672)
		(end 396.455646 -9.821672)
		(stroke
			(width 0.1016)
			(type default)
		)
		(layer "In1.Cu")
	)
	(gr_line
		(start 395.312646 -8.312404)
		(end 395.312646 -5.721604)
		(stroke
			(width 0.1016)
			(type default)
		)
		(layer "In1.Cu")
	)
	(gr_line
		(start 395.312646 -8.212328)
		(end 395.312646 -5.621528)
		(stroke
			(width 0.1016)
			(type default)
		)
		(layer "In1.Cu")
	)
	(gr_line
		(start 395.312646 -5.721604)
		(end 396.455646 -5.721604)
		(stroke
			(width 0.1016)
			(type default)
		)
		(layer "In1.Cu")
	)
	(gr_line
		(start 395.312646 -5.621528)
		(end 396.455646 -5.621528)
		(stroke
			(width 0.1016)
			(type default)
		)
		(layer "In1.Cu")
	)
	(gr_line
		(start 395.312646 -4.11226)
		(end 395.312646 -1.52146)
		(stroke
			(width 0.1016)
			(type default)
		)
		(layer "In1.Cu")
	)
	(gr_line
		(start 395.312646 -4.012184)
		(end 395.312646 -1.421384)
		(stroke
			(width 0.1016)
			(type default)
		)
		(layer "In1.Cu")
	)
	(gr_line
		(start 395.312646 -1.52146)
		(end 396.455646 -1.52146)
		(stroke
			(width 0.1016)
			(type default)
		)
		(layer "In1.Cu")
	)
	(gr_line
		(start 395.312646 -1.421384)
		(end 396.455646 -1.421384)
		(stroke
			(width 0.1016)
			(type default)
		)
		(layer "In1.Cu")
	)
	(gr_line
		(start 395.338046 -12.512548)
		(end 395.338046 -9.947148)
		(stroke
			(width 0.1016)
			(type default)
		)
		(layer "In1.Cu")
	)
	(gr_line
		(start 395.338046 -12.412472)
		(end 395.338046 -9.847072)
		(stroke
			(width 0.1016)
			(type default)
		)
		(layer "In1.Cu")
	)
	(gr_line
		(start 395.338046 -9.947148)
		(end 395.592046 -9.947148)
		(stroke
			(width 0.1016)
			(type default)
		)
		(layer "In1.Cu")
	)
	(gr_line
		(start 395.338046 -9.847072)
		(end 395.592046 -9.847072)
		(stroke
			(width 0.1016)
			(type default)
		)
		(layer "In1.Cu")
	)
	(gr_line
		(start 395.338046 -8.312404)
		(end 395.338046 -5.747004)
		(stroke
			(width 0.1016)
			(type default)
		)
		(layer "In1.Cu")
	)
	(gr_line
		(start 395.338046 -8.212328)
		(end 395.338046 -5.646928)
		(stroke
			(width 0.1016)
			(type default)
		)
		(layer "In1.Cu")
	)
	(gr_line
		(start 395.338046 -5.747004)
		(end 395.592046 -5.747004)
		(stroke
			(width 0.1016)
			(type default)
		)
		(layer "In1.Cu")
	)
	(gr_line
		(start 395.338046 -5.646928)
		(end 395.592046 -5.646928)
		(stroke
			(width 0.1016)
			(type default)
		)
		(layer "In1.Cu")
	)
	(gr_line
		(start 395.338046 -4.11226)
		(end 395.338046 -1.54686)
		(stroke
			(width 0.1016)
			(type default)
		)
		(layer "In1.Cu")
	)
	(gr_line
		(start 395.338046 -4.012184)
		(end 395.338046 -1.446784)
		(stroke
			(width 0.1016)
			(type default)
		)
		(layer "In1.Cu")
	)
	(gr_line
		(start 395.338046 -1.54686)
		(end 395.592046 -1.54686)
		(stroke
			(width 0.1016)
			(type default)
		)
		(layer "In1.Cu")
	)
	(gr_line
		(start 395.338046 -1.446784)
		(end 395.592046 -1.446784)
		(stroke
			(width 0.1016)
			(type default)
		)
		(layer "In1.Cu")
	)
	(gr_line
		(start 395.363446 -12.512548)
		(end 395.363446 -9.947148)
		(stroke
			(width 0.2032)
			(type default)
		)
		(layer "In1.Cu")
	)
	(gr_line
		(start 395.363446 -12.412472)
		(end 395.363446 -9.847072)
		(stroke
			(width 0.2032)
			(type default)
		)
		(layer "In1.Cu")
	)
	(gr_line
		(start 395.363446 -9.947148)
		(end 396.379446 -9.947148)
		(stroke
			(width 0.2032)
			(type default)
		)
		(layer "In1.Cu")
	)
	(gr_line
		(start 395.363446 -9.847072)
		(end 396.379446 -9.847072)
		(stroke
			(width 0.2032)
			(type default)
		)
		(layer "In1.Cu")
	)
	(gr_line
		(start 395.363446 -8.312404)
		(end 395.363446 -5.747004)
		(stroke
			(width 0.2032)
			(type default)
		)
		(layer "In1.Cu")
	)
	(gr_line
		(start 395.363446 -8.212328)
		(end 395.363446 -5.646928)
		(stroke
			(width 0.2032)
			(type default)
		)
		(layer "In1.Cu")
	)
	(gr_line
		(start 395.363446 -5.747004)
		(end 396.379446 -5.747004)
		(stroke
			(width 0.2032)
			(type default)
		)
		(layer "In1.Cu")
	)
	(gr_line
		(start 395.363446 -5.646928)
		(end 396.379446 -5.646928)
		(stroke
			(width 0.2032)
			(type default)
		)
		(layer "In1.Cu")
	)
	(gr_line
		(start 395.363446 -4.11226)
		(end 395.363446 -1.54686)
		(stroke
			(width 0.2032)
			(type default)
		)
		(layer "In1.Cu")
	)
	(gr_line
		(start 395.363446 -4.012184)
		(end 395.363446 -1.446784)
		(stroke
			(width 0.2032)
			(type default)
		)
		(layer "In1.Cu")
	)
	(gr_line
		(start 395.363446 -1.54686)
		(end 396.379446 -1.54686)
		(stroke
			(width 0.2032)
			(type default)
		)
		(layer "In1.Cu")
	)
	(gr_line
		(start 395.363446 -1.446784)
		(end 396.379446 -1.446784)
		(stroke
			(width 0.2032)
			(type default)
		)
		(layer "In1.Cu")
	)
	(gr_line
		(start 395.363446 -0.126746)
		(end 396.328646 -0.126746)
		(stroke
			(width 0.254)
			(type default)
		)
		(layer "In1.Cu")
	)
	(gr_line
		(start 395.363446 -0.101346)
		(end 396.328646 -0.101346)
		(stroke
			(width 0.254)
			(type default)
		)
		(layer "In1.Cu")
	)
	(gr_line
		(start 395.3637 -26.750772)
		(end 395.3637 -25.099772)
		(stroke
			(width 0.2032)
			(type default)
		)
		(layer "In1.Cu")
	)
	(gr_line
		(start 395.3637 -26.725372)
		(end 394.3477 -26.725372)
		(stroke
			(width 0.2032)
			(type default)
		)
		(layer "In1.Cu")
	)
	(gr_line
		(start 395.3637 -26.674572)
		(end 395.3637 -26.725372)
		(stroke
			(width 0.2032)
			(type default)
		)
		(layer "In1.Cu")
	)
	(gr_line
		(start 395.3637 -25.099772)
		(end 394.4239 -25.099772)
		(stroke
			(width 0.2032)
			(type default)
		)
		(layer "In1.Cu")
	)
	(gr_line
		(start 395.388846 -0.152146)
		(end 396.354046 -0.152146)
		(stroke
			(width 0.254)
			(type default)
		)
		(layer "In1.Cu")
	)
	(gr_line
		(start 395.388846 -0.126746)
		(end 396.354046 -0.126746)
		(stroke
			(width 0.254)
			(type default)
		)
		(layer "In1.Cu")
	)
	(gr_line
		(start 395.414246 -12.487148)
		(end 395.414246 -9.997948)
		(stroke
			(width 0.2032)
			(type default)
		)
		(layer "In1.Cu")
	)
	(gr_line
		(start 395.414246 -12.487148)
		(end 395.414246 -9.997948)
		(stroke
			(width 0.254)
			(type default)
		)
		(layer "In1.Cu")
	)
	(gr_line
		(start 395.414246 -12.387072)
		(end 395.414246 -9.897872)
		(stroke
			(width 0.2032)
			(type default)
		)
		(layer "In1.Cu")
	)
	(gr_line
		(start 395.414246 -12.387072)
		(end 395.414246 -9.897872)
		(stroke
			(width 0.254)
			(type default)
		)
		(layer "In1.Cu")
	)
	(gr_line
		(start 395.414246 -9.997948)
		(end 395.617446 -9.997948)
		(stroke
			(width 0.2032)
			(type default)
		)
		(layer "In1.Cu")
	)
	(gr_line
		(start 395.414246 -9.997948)
		(end 396.303246 -9.997948)
		(stroke
			(width 0.254)
			(type default)
		)
		(layer "In1.Cu")
	)
	(gr_line
		(start 395.414246 -9.897872)
		(end 395.617446 -9.897872)
		(stroke
			(width 0.2032)
			(type default)
		)
		(layer "In1.Cu")
	)
	(gr_line
		(start 395.414246 -9.897872)
		(end 396.303246 -9.897872)
		(stroke
			(width 0.254)
			(type default)
		)
		(layer "In1.Cu")
	)
	(gr_line
		(start 395.414246 -8.287004)
		(end 395.414246 -5.797804)
		(stroke
			(width 0.2032)
			(type default)
		)
		(layer "In1.Cu")
	)
	(gr_line
		(start 395.414246 -8.287004)
		(end 395.414246 -5.797804)
		(stroke
			(width 0.254)
			(type default)
		)
		(layer "In1.Cu")
	)
	(gr_line
		(start 395.414246 -8.186928)
		(end 395.414246 -5.697728)
		(stroke
			(width 0.2032)
			(type default)
		)
		(layer "In1.Cu")
	)
	(gr_line
		(start 395.414246 -8.186928)
		(end 395.414246 -5.697728)
		(stroke
			(width 0.254)
			(type default)
		)
		(layer "In1.Cu")
	)
	(gr_line
		(start 395.414246 -5.797804)
		(end 395.617446 -5.797804)
		(stroke
			(width 0.2032)
			(type default)
		)
		(layer "In1.Cu")
	)
	(gr_line
		(start 395.414246 -5.797804)
		(end 396.303246 -5.797804)
		(stroke
			(width 0.254)
			(type default)
		)
		(layer "In1.Cu")
	)
	(gr_line
		(start 395.414246 -5.697728)
		(end 395.617446 -5.697728)
		(stroke
			(width 0.2032)
			(type default)
		)
		(layer "In1.Cu")
	)
	(gr_line
		(start 395.414246 -5.697728)
		(end 396.303246 -5.697728)
		(stroke
			(width 0.254)
			(type default)
		)
		(layer "In1.Cu")
	)
	(gr_line
		(start 395.414246 -4.08686)
		(end 395.414246 -1.59766)
		(stroke
			(width 0.2032)
			(type default)
		)
		(layer "In1.Cu")
	)
	(gr_line
		(start 395.414246 -4.08686)
		(end 395.414246 -1.59766)
		(stroke
			(width 0.254)
			(type default)
		)
		(layer "In1.Cu")
	)
	(gr_line
		(start 395.414246 -3.986784)
		(end 395.414246 -1.497584)
		(stroke
			(width 0.2032)
			(type default)
		)
		(layer "In1.Cu")
	)
	(gr_line
		(start 395.414246 -3.986784)
		(end 395.414246 -1.497584)
		(stroke
			(width 0.254)
			(type default)
		)
		(layer "In1.Cu")
	)
	(gr_line
		(start 395.414246 -1.59766)
		(end 395.617446 -1.59766)
		(stroke
			(width 0.2032)
			(type default)
		)
		(layer "In1.Cu")
	)
	(gr_line
		(start 395.414246 -1.59766)
		(end 396.303246 -1.59766)
		(stroke
			(width 0.254)
			(type default)
		)
		(layer "In1.Cu")
	)
	(gr_line
		(start 395.414246 -1.497584)
		(end 395.617446 -1.497584)
		(stroke
			(width 0.2032)
			(type default)
		)
		(layer "In1.Cu")
	)
	(gr_line
		(start 395.414246 -1.497584)
		(end 396.303246 -1.497584)
		(stroke
			(width 0.254)
			(type default)
		)
		(layer "In1.Cu")
	)
	(gr_line
		(start 395.414246 -0.126746)
		(end 396.379446 -0.126746)
		(stroke
			(width 0.254)
			(type default)
		)
		(layer "In1.Cu")
	)
	(gr_line
		(start 395.4145 -26.725372)
		(end 394.3731 -26.725372)
		(stroke
			(width 0.2032)
			(type default)
		)
		(layer "In1.Cu")
	)
	(gr_line
		(start 395.4145 -25.048972)
		(end 395.4145 -26.725372)
		(stroke
			(width 0.2032)
			(type default)
		)
		(layer "In1.Cu")
	)
	(gr_line
		(start 395.439646 -12.461748)
		(end 395.439646 -10.023348)
		(stroke
			(width 0.254)
			(type default)
		)
		(layer "In1.Cu")
	)
	(gr_line
		(start 395.439646 -12.361672)
		(end 395.439646 -9.923272)
		(stroke
			(width 0.254)
			(type default)
		)
		(layer "In1.Cu")
	)
	(gr_line
		(start 395.439646 -10.023348)
		(end 396.277846 -10.023348)
		(stroke
			(width 0.254)
			(type default)
		)
		(layer "In1.Cu")
	)
	(gr_line
		(start 395.439646 -9.923272)
		(end 396.277846 -9.923272)
		(stroke
			(width 0.254)
			(type default)
		)
		(layer "In1.Cu")
	)
	(gr_line
		(start 395.439646 -8.261604)
		(end 395.439646 -5.823204)
		(stroke
			(width 0.254)
			(type default)
		)
		(layer "In1.Cu")
	)
	(gr_line
		(start 395.439646 -8.161528)
		(end 395.439646 -5.723128)
		(stroke
			(width 0.254)
			(type default)
		)
		(layer "In1.Cu")
	)
	(gr_line
		(start 395.439646 -5.823204)
		(end 396.277846 -5.823204)
		(stroke
			(width 0.254)
			(type default)
		)
		(layer "In1.Cu")
	)
	(gr_line
		(start 395.439646 -5.723128)
		(end 396.277846 -5.723128)
		(stroke
			(width 0.254)
			(type default)
		)
		(layer "In1.Cu")
	)
	(gr_line
		(start 395.439646 -4.06146)
		(end 395.439646 -1.62306)
		(stroke
			(width 0.254)
			(type default)
		)
		(layer "In1.Cu")
	)
	(gr_line
		(start 395.439646 -3.961384)
		(end 395.439646 -1.522984)
		(stroke
			(width 0.254)
			(type default)
		)
		(layer "In1.Cu")
	)
	(gr_line
		(start 395.439646 -1.62306)
		(end 396.277846 -1.62306)
		(stroke
			(width 0.254)
			(type default)
		)
		(layer "In1.Cu")
	)
	(gr_line
		(start 395.439646 -1.522984)
		(end 396.277846 -1.522984)
		(stroke
			(width 0.254)
			(type default)
		)
		(layer "In1.Cu")
	)
	(gr_line
		(start 395.439646 -0.101346)
		(end 396.404846 -0.101346)
		(stroke
			(width 0.254)
			(type default)
		)
		(layer "In1.Cu")
	)
	(gr_line
		(start 395.465046 -12.436348)
		(end 395.465046 -10.048748)
		(stroke
			(width 0.254)
			(type default)
		)
		(layer "In1.Cu")
	)
	(gr_line
		(start 395.465046 -12.336272)
		(end 395.465046 -9.948672)
		(stroke
			(width 0.254)
			(type default)
		)
		(layer "In1.Cu")
	)
	(gr_line
		(start 395.465046 -10.048748)
		(end 396.252446 -10.048748)
		(stroke
			(width 0.254)
			(type default)
		)
		(layer "In1.Cu")
	)
	(gr_line
		(start 395.465046 -9.948672)
		(end 396.252446 -9.948672)
		(stroke
			(width 0.254)
			(type default)
		)
		(layer "In1.Cu")
	)
	(gr_line
		(start 395.465046 -8.236204)
		(end 395.465046 -5.848604)
		(stroke
			(width 0.254)
			(type default)
		)
		(layer "In1.Cu")
	)
	(gr_line
		(start 395.465046 -8.136128)
		(end 395.465046 -5.748528)
		(stroke
			(width 0.254)
			(type default)
		)
		(layer "In1.Cu")
	)
	(gr_line
		(start 395.465046 -5.848604)
		(end 396.252446 -5.848604)
		(stroke
			(width 0.254)
			(type default)
		)
		(layer "In1.Cu")
	)
	(gr_line
		(start 395.465046 -5.748528)
		(end 396.252446 -5.748528)
		(stroke
			(width 0.254)
			(type default)
		)
		(layer "In1.Cu")
	)
	(gr_line
		(start 395.465046 -4.03606)
		(end 395.465046 -1.64846)
		(stroke
			(width 0.254)
			(type default)
		)
		(layer "In1.Cu")
	)
	(gr_line
		(start 395.465046 -3.935984)
		(end 395.465046 -1.548384)
		(stroke
			(width 0.254)
			(type default)
		)
		(layer "In1.Cu")
	)
	(gr_line
		(start 395.465046 -1.64846)
		(end 396.252446 -1.64846)
		(stroke
			(width 0.254)
			(type default)
		)
		(layer "In1.Cu")
	)
	(gr_line
		(start 395.465046 -1.548384)
		(end 396.252446 -1.548384)
		(stroke
			(width 0.254)
			(type default)
		)
		(layer "In1.Cu")
	)
	(gr_line
		(start 395.4653 -26.826972)
		(end 395.4653 -24.972772)
		(stroke
			(width 0.1016)
			(type default)
		)
		(layer "In1.Cu")
	)
	(gr_line
		(start 395.4653 -24.972772)
		(end 394.2969 -24.972772)
		(stroke
			(width 0.1016)
			(type default)
		)
		(layer "In1.Cu")
	)
	(gr_line
		(start 395.490446 -12.360148)
		(end 396.125446 -12.360148)
		(stroke
			(width 0.508)
			(type default)
		)
		(layer "In1.Cu")
	)
	(gr_line
		(start 395.490446 -12.260072)
		(end 396.125446 -12.260072)
		(stroke
			(width 0.508)
			(type default)
		)
		(layer "In1.Cu")
	)
	(gr_line
		(start 395.490446 -10.175748)
		(end 396.125446 -10.175748)
		(stroke
			(width 0.508)
			(type default)
		)
		(layer "In1.Cu")
	)
	(gr_line
		(start 395.490446 -10.124948)
		(end 396.125446 -10.124948)
		(stroke
			(width 0.508)
			(type default)
		)
		(layer "In1.Cu")
	)
	(gr_line
		(start 395.490446 -10.075672)
		(end 396.125446 -10.075672)
		(stroke
			(width 0.508)
			(type default)
		)
		(layer "In1.Cu")
	)
	(gr_line
		(start 395.490446 -10.024872)
		(end 396.125446 -10.024872)
		(stroke
			(width 0.508)
			(type default)
		)
		(layer "In1.Cu")
	)
	(gr_line
		(start 395.490446 -8.160004)
		(end 396.125446 -8.160004)
		(stroke
			(width 0.508)
			(type default)
		)
		(layer "In1.Cu")
	)
	(gr_line
		(start 395.490446 -8.059928)
		(end 396.125446 -8.059928)
		(stroke
			(width 0.508)
			(type default)
		)
		(layer "In1.Cu")
	)
	(gr_line
		(start 395.490446 -5.975604)
		(end 396.125446 -5.975604)
		(stroke
			(width 0.508)
			(type default)
		)
		(layer "In1.Cu")
	)
	(gr_line
		(start 395.490446 -5.924804)
		(end 396.125446 -5.924804)
		(stroke
			(width 0.508)
			(type default)
		)
		(layer "In1.Cu")
	)
	(gr_line
		(start 395.490446 -5.875528)
		(end 396.125446 -5.875528)
		(stroke
			(width 0.508)
			(type default)
		)
		(layer "In1.Cu")
	)
	(gr_line
		(start 395.490446 -5.824728)
		(end 396.125446 -5.824728)
		(stroke
			(width 0.508)
			(type default)
		)
		(layer "In1.Cu")
	)
	(gr_line
		(start 395.490446 -3.95986)
		(end 396.125446 -3.95986)
		(stroke
			(width 0.508)
			(type default)
		)
		(layer "In1.Cu")
	)
	(gr_line
		(start 395.490446 -3.859784)
		(end 396.125446 -3.859784)
		(stroke
			(width 0.508)
			(type default)
		)
		(layer "In1.Cu")
	)
	(gr_line
		(start 395.490446 -1.77546)
		(end 396.125446 -1.77546)
		(stroke
			(width 0.508)
			(type default)
		)
		(layer "In1.Cu")
	)
	(gr_line
		(start 395.490446 -1.72466)
		(end 396.125446 -1.72466)
		(stroke
			(width 0.508)
			(type default)
		)
		(layer "In1.Cu")
	)
	(gr_line
		(start 395.490446 -1.675384)
		(end 396.125446 -1.675384)
		(stroke
			(width 0.508)
			(type default)
		)
		(layer "In1.Cu")
	)
	(gr_line
		(start 395.490446 -1.624584)
		(end 396.125446 -1.624584)
		(stroke
			(width 0.508)
			(type default)
		)
		(layer "In1.Cu")
	)
	(gr_line
		(start 395.515846 -10.429748)
		(end 396.150846 -10.429748)
		(stroke
			(width 0.508)
			(type default)
		)
		(layer "In1.Cu")
	)
	(gr_line
		(start 395.515846 -10.329672)
		(end 396.150846 -10.329672)
		(stroke
			(width 0.508)
			(type default)
		)
		(layer "In1.Cu")
	)
	(gr_line
		(start 395.515846 -6.229604)
		(end 396.150846 -6.229604)
		(stroke
			(width 0.508)
			(type default)
		)
		(layer "In1.Cu")
	)
	(gr_line
		(start 395.515846 -6.129528)
		(end 396.150846 -6.129528)
		(stroke
			(width 0.508)
			(type default)
		)
		(layer "In1.Cu")
	)
	(gr_line
		(start 395.515846 -2.02946)
		(end 396.150846 -2.02946)
		(stroke
			(width 0.508)
			(type default)
		)
		(layer "In1.Cu")
	)
	(gr_line
		(start 395.515846 -1.929384)
		(end 396.150846 -1.929384)
		(stroke
			(width 0.508)
			(type default)
		)
		(layer "In1.Cu")
	)
	(gr_line
		(start 395.541246 -12.385548)
		(end 395.541246 -10.124948)
		(stroke
			(width 0.254)
			(type default)
		)
		(layer "In1.Cu")
	)
	(gr_line
		(start 395.541246 -12.285472)
		(end 395.541246 -10.024872)
		(stroke
			(width 0.254)
			(type default)
		)
		(layer "In1.Cu")
	)
	(gr_line
		(start 395.541246 -12.233148)
		(end 396.176246 -12.233148)
		(stroke
			(width 0.508)
			(type default)
		)
		(layer "In1.Cu")
	)
	(gr_line
		(start 395.541246 -12.133072)
		(end 396.176246 -12.133072)
		(stroke
			(width 0.508)
			(type default)
		)
		(layer "In1.Cu")
	)
	(gr_line
		(start 395.541246 -10.124948)
		(end 396.176246 -10.124948)
		(stroke
			(width 0.254)
			(type default)
		)
		(layer "In1.Cu")
	)
	(gr_line
		(start 395.541246 -10.024872)
		(end 396.176246 -10.024872)
		(stroke
			(width 0.254)
			(type default)
		)
		(layer "In1.Cu")
	)
	(gr_line
		(start 395.541246 -8.185404)
		(end 395.541246 -5.924804)
		(stroke
			(width 0.254)
			(type default)
		)
		(layer "In1.Cu")
	)
	(gr_line
		(start 395.541246 -8.085328)
		(end 395.541246 -5.824728)
		(stroke
			(width 0.254)
			(type default)
		)
		(layer "In1.Cu")
	)
	(gr_line
		(start 395.541246 -8.033004)
		(end 396.176246 -8.033004)
		(stroke
			(width 0.508)
			(type default)
		)
		(layer "In1.Cu")
	)
	(gr_line
		(start 395.541246 -7.932928)
		(end 396.176246 -7.932928)
		(stroke
			(width 0.508)
			(type default)
		)
		(layer "In1.Cu")
	)
	(gr_line
		(start 395.541246 -5.924804)
		(end 396.176246 -5.924804)
		(stroke
			(width 0.254)
			(type default)
		)
		(layer "In1.Cu")
	)
	(gr_line
		(start 395.541246 -5.824728)
		(end 396.176246 -5.824728)
		(stroke
			(width 0.254)
			(type default)
		)
		(layer "In1.Cu")
	)
	(gr_line
		(start 395.541246 -3.98526)
		(end 395.541246 -1.72466)
		(stroke
			(width 0.254)
			(type default)
		)
		(layer "In1.Cu")
	)
	(gr_line
		(start 395.541246 -3.885184)
		(end 395.541246 -1.624584)
		(stroke
			(width 0.254)
			(type default)
		)
		(layer "In1.Cu")
	)
	(gr_line
		(start 395.541246 -3.83286)
		(end 396.176246 -3.83286)
		(stroke
			(width 0.508)
			(type default)
		)
		(layer "In1.Cu")
	)
	(gr_line
		(start 395.541246 -3.732784)
		(end 396.176246 -3.732784)
		(stroke
			(width 0.508)
			(type default)
		)
		(layer "In1.Cu")
	)
	(gr_line
		(start 395.541246 -1.72466)
		(end 396.176246 -1.72466)
		(stroke
			(width 0.254)
			(type default)
		)
		(layer "In1.Cu")
	)
	(gr_line
		(start 395.541246 -1.624584)
		(end 396.176246 -1.624584)
		(stroke
			(width 0.254)
			(type default)
		)
		(layer "In1.Cu")
	)
	(gr_line
		(start 395.566646 -12.080748)
		(end 396.201646 -12.080748)
		(stroke
			(width 0.508)
			(type default)
		)
		(layer "In1.Cu")
	)
	(gr_line
		(start 395.566646 -11.980672)
		(end 396.201646 -11.980672)
		(stroke
			(width 0.508)
			(type default)
		)
		(layer "In1.Cu")
	)
	(gr_line
		(start 395.566646 -7.880604)
		(end 396.201646 -7.880604)
		(stroke
			(width 0.508)
			(type default)
		)
		(layer "In1.Cu")
	)
	(gr_line
		(start 395.566646 -7.780528)
		(end 396.201646 -7.780528)
		(stroke
			(width 0.508)
			(type default)
		)
		(layer "In1.Cu")
	)
	(gr_line
		(start 395.566646 -3.68046)
		(end 396.201646 -3.68046)
		(stroke
			(width 0.508)
			(type default)
		)
		(layer "In1.Cu")
	)
	(gr_line
		(start 395.566646 -3.580384)
		(end 396.201646 -3.580384)
		(stroke
			(width 0.508)
			(type default)
		)
		(layer "In1.Cu")
	)
	(gr_line
		(start 395.592046 -12.360148)
		(end 396.227046 -12.360148)
		(stroke
			(width 0.508)
			(type default)
		)
		(layer "In1.Cu")
	)
	(gr_line
		(start 395.592046 -12.260072)
		(end 396.227046 -12.260072)
		(stroke
			(width 0.508)
			(type default)
		)
		(layer "In1.Cu")
	)
	(gr_line
		(start 395.592046 -9.947148)
		(end 396.430246 -9.947148)
		(stroke
			(width 0.2032)
			(type default)
		)
		(layer "In1.Cu")
	)
	(gr_line
		(start 395.592046 -9.847072)
		(end 396.430246 -9.847072)
		(stroke
			(width 0.2032)
			(type default)
		)
		(layer "In1.Cu")
	)
	(gr_line
		(start 395.592046 -8.160004)
		(end 396.227046 -8.160004)
		(stroke
			(width 0.508)
			(type default)
		)
		(layer "In1.Cu")
	)
	(gr_line
		(start 395.592046 -8.059928)
		(end 396.227046 -8.059928)
		(stroke
			(width 0.508)
			(type default)
		)
		(layer "In1.Cu")
	)
	(gr_line
		(start 395.592046 -5.747004)
		(end 396.430246 -5.747004)
		(stroke
			(width 0.2032)
			(type default)
		)
		(layer "In1.Cu")
	)
	(gr_line
		(start 395.592046 -5.646928)
		(end 396.430246 -5.646928)
		(stroke
			(width 0.2032)
			(type default)
		)
		(layer "In1.Cu")
	)
	(gr_line
		(start 395.592046 -3.95986)
		(end 396.227046 -3.95986)
		(stroke
			(width 0.508)
			(type default)
		)
		(layer "In1.Cu")
	)
	(gr_line
		(start 395.592046 -3.859784)
		(end 396.227046 -3.859784)
		(stroke
			(width 0.508)
			(type default)
		)
		(layer "In1.Cu")
	)
	(gr_line
		(start 395.592046 -1.54686)
		(end 396.430246 -1.54686)
		(stroke
			(width 0.2032)
			(type default)
		)
		(layer "In1.Cu")
	)
	(gr_line
		(start 395.592046 -1.446784)
		(end 396.430246 -1.446784)
		(stroke
			(width 0.2032)
			(type default)
		)
		(layer "In1.Cu")
	)
	(gr_line
		(start 395.617446 -12.360148)
		(end 395.617446 -10.175748)
		(stroke
			(width 0.254)
			(type default)
		)
		(layer "In1.Cu")
	)
	(gr_line
		(start 395.617446 -12.260072)
		(end 395.617446 -10.075672)
		(stroke
			(width 0.254)
			(type default)
		)
		(layer "In1.Cu")
	)
	(gr_line
		(start 395.617446 -10.175748)
		(end 396.100046 -10.175748)
		(stroke
			(width 0.254)
			(type default)
		)
		(layer "In1.Cu")
	)
	(gr_line
		(start 395.617446 -10.075672)
		(end 396.100046 -10.075672)
		(stroke
			(width 0.254)
			(type default)
		)
		(layer "In1.Cu")
	)
	(gr_line
		(start 395.617446 -9.997948)
		(end 396.354046 -9.997948)
		(stroke
			(width 0.254)
			(type default)
		)
		(layer "In1.Cu")
	)
	(gr_line
		(start 395.617446 -9.897872)
		(end 396.354046 -9.897872)
		(stroke
			(width 0.254)
			(type default)
		)
		(layer "In1.Cu")
	)
	(gr_line
		(start 395.617446 -8.160004)
		(end 395.617446 -5.975604)
		(stroke
			(width 0.254)
			(type default)
		)
		(layer "In1.Cu")
	)
	(gr_line
		(start 395.617446 -8.059928)
		(end 395.617446 -5.875528)
		(stroke
			(width 0.254)
			(type default)
		)
		(layer "In1.Cu")
	)
	(gr_line
		(start 395.617446 -5.975604)
		(end 396.100046 -5.975604)
		(stroke
			(width 0.254)
			(type default)
		)
		(layer "In1.Cu")
	)
	(gr_line
		(start 395.617446 -5.875528)
		(end 396.100046 -5.875528)
		(stroke
			(width 0.254)
			(type default)
		)
		(layer "In1.Cu")
	)
	(gr_line
		(start 395.617446 -5.797804)
		(end 396.354046 -5.797804)
		(stroke
			(width 0.254)
			(type default)
		)
		(layer "In1.Cu")
	)
	(gr_line
		(start 395.617446 -5.697728)
		(end 396.354046 -5.697728)
		(stroke
			(width 0.254)
			(type default)
		)
		(layer "In1.Cu")
	)
	(gr_line
		(start 395.617446 -3.95986)
		(end 395.617446 -1.77546)
		(stroke
			(width 0.254)
			(type default)
		)
		(layer "In1.Cu")
	)
	(gr_line
		(start 395.617446 -3.859784)
		(end 395.617446 -1.675384)
		(stroke
			(width 0.254)
			(type default)
		)
		(layer "In1.Cu")
	)
	(gr_line
		(start 395.617446 -1.77546)
		(end 396.100046 -1.77546)
		(stroke
			(width 0.254)
			(type default)
		)
		(layer "In1.Cu")
	)
	(gr_line
		(start 395.617446 -1.675384)
		(end 396.100046 -1.675384)
		(stroke
			(width 0.254)
			(type default)
		)
		(layer "In1.Cu")
	)
	(gr_line
		(start 395.617446 -1.59766)
		(end 396.354046 -1.59766)
		(stroke
			(width 0.254)
			(type default)
		)
		(layer "In1.Cu")
	)
	(gr_line
		(start 395.617446 -1.497584)
		(end 396.354046 -1.497584)
		(stroke
			(width 0.254)
			(type default)
		)
		(layer "In1.Cu")
	)
	(gr_line
		(start 395.635988 -10.110978)
		(end 396.270988 -10.110978)
		(stroke
			(width 0.508)
			(type default)
		)
		(layer "In1.Cu")
	)
	(gr_line
		(start 395.635988 -10.010902)
		(end 396.270988 -10.010902)
		(stroke
			(width 0.508)
			(type default)
		)
		(layer "In1.Cu")
	)
	(gr_line
		(start 395.635988 -5.910834)
		(end 396.270988 -5.910834)
		(stroke
			(width 0.508)
			(type default)
		)
		(layer "In1.Cu")
	)
	(gr_line
		(start 395.635988 -5.810758)
		(end 396.270988 -5.810758)
		(stroke
			(width 0.508)
			(type default)
		)
		(layer "In1.Cu")
	)
	(gr_line
		(start 395.635988 -1.71069)
		(end 396.270988 -1.71069)
		(stroke
			(width 0.508)
			(type default)
		)
		(layer "In1.Cu")
	)
	(gr_line
		(start 395.635988 -1.610614)
		(end 396.270988 -1.610614)
		(stroke
			(width 0.508)
			(type default)
		)
		(layer "In1.Cu")
	)
	(gr_line
		(start 395.642846 -12.360148)
		(end 396.277846 -12.360148)
		(stroke
			(width 0.508)
			(type default)
		)
		(layer "In1.Cu")
	)
	(gr_line
		(start 395.642846 -12.260072)
		(end 396.277846 -12.260072)
		(stroke
			(width 0.508)
			(type default)
		)
		(layer "In1.Cu")
	)
	(gr_line
		(start 395.642846 -12.233148)
		(end 395.642846 -10.251948)
		(stroke
			(width 0.762)
			(type default)
		)
		(layer "In1.Cu")
	)
	(gr_line
		(start 395.642846 -12.133072)
		(end 395.642846 -10.151872)
		(stroke
			(width 0.762)
			(type default)
		)
		(layer "In1.Cu")
	)
	(gr_line
		(start 395.642846 -10.251948)
		(end 396.277846 -10.251948)
		(stroke
			(width 0.508)
			(type default)
		)
		(layer "In1.Cu")
	)
	(gr_line
		(start 395.642846 -10.151872)
		(end 396.277846 -10.151872)
		(stroke
			(width 0.508)
			(type default)
		)
		(layer "In1.Cu")
	)
	(gr_line
		(start 395.642846 -8.160004)
		(end 396.277846 -8.160004)
		(stroke
			(width 0.508)
			(type default)
		)
		(layer "In1.Cu")
	)
	(gr_line
		(start 395.642846 -8.059928)
		(end 396.277846 -8.059928)
		(stroke
			(width 0.508)
			(type default)
		)
		(layer "In1.Cu")
	)
	(gr_line
		(start 395.642846 -8.033004)
		(end 395.642846 -6.051804)
		(stroke
			(width 0.762)
			(type default)
		)
		(layer "In1.Cu")
	)
	(gr_line
		(start 395.642846 -7.932928)
		(end 395.642846 -5.951728)
		(stroke
			(width 0.762)
			(type default)
		)
		(layer "In1.Cu")
	)
	(gr_line
		(start 395.642846 -6.051804)
		(end 396.277846 -6.051804)
		(stroke
			(width 0.508)
			(type default)
		)
		(layer "In1.Cu")
	)
	(gr_line
		(start 395.642846 -5.951728)
		(end 396.277846 -5.951728)
		(stroke
			(width 0.508)
			(type default)
		)
		(layer "In1.Cu")
	)
	(gr_line
		(start 395.642846 -3.95986)
		(end 396.277846 -3.95986)
		(stroke
			(width 0.508)
			(type default)
		)
		(layer "In1.Cu")
	)
	(gr_line
		(start 395.642846 -3.859784)
		(end 396.277846 -3.859784)
		(stroke
			(width 0.508)
			(type default)
		)
		(layer "In1.Cu")
	)
	(gr_line
		(start 395.642846 -3.83286)
		(end 395.642846 -1.85166)
		(stroke
			(width 0.762)
			(type default)
		)
		(layer "In1.Cu")
	)
	(gr_line
		(start 395.642846 -3.732784)
		(end 395.642846 -1.751584)
		(stroke
			(width 0.762)
			(type default)
		)
		(layer "In1.Cu")
	)
	(gr_line
		(start 395.642846 -1.85166)
		(end 396.277846 -1.85166)
		(stroke
			(width 0.508)
			(type default)
		)
		(layer "In1.Cu")
	)
	(gr_line
		(start 395.642846 -1.751584)
		(end 396.277846 -1.751584)
		(stroke
			(width 0.508)
			(type default)
		)
		(layer "In1.Cu")
	)
	(gr_line
		(start 395.693646 -12.283948)
		(end 395.693646 -10.251948)
		(stroke
			(width 0.254)
			(type default)
		)
		(layer "In1.Cu")
	)
	(gr_line
		(start 395.693646 -12.183872)
		(end 395.693646 -10.151872)
		(stroke
			(width 0.254)
			(type default)
		)
		(layer "In1.Cu")
	)
	(gr_line
		(start 395.693646 -10.251948)
		(end 396.023846 -10.251948)
		(stroke
			(width 0.254)
			(type default)
		)
		(layer "In1.Cu")
	)
	(gr_line
		(start 395.693646 -10.151872)
		(end 396.023846 -10.151872)
		(stroke
			(width 0.254)
			(type default)
		)
		(layer "In1.Cu")
	)
	(gr_line
		(start 395.693646 -8.083804)
		(end 395.693646 -6.051804)
		(stroke
			(width 0.254)
			(type default)
		)
		(layer "In1.Cu")
	)
	(gr_line
		(start 395.693646 -7.983728)
		(end 395.693646 -5.951728)
		(stroke
			(width 0.254)
			(type default)
		)
		(layer "In1.Cu")
	)
	(gr_line
		(start 395.693646 -6.051804)
		(end 396.023846 -6.051804)
		(stroke
			(width 0.254)
			(type default)
		)
		(layer "In1.Cu")
	)
	(gr_line
		(start 395.693646 -5.951728)
		(end 396.023846 -5.951728)
		(stroke
			(width 0.254)
			(type default)
		)
		(layer "In1.Cu")
	)
	(gr_line
		(start 395.693646 -3.88366)
		(end 395.693646 -1.85166)
		(stroke
			(width 0.254)
			(type default)
		)
		(layer "In1.Cu")
	)
	(gr_line
		(start 395.693646 -3.783584)
		(end 395.693646 -1.751584)
		(stroke
			(width 0.254)
			(type default)
		)
		(layer "In1.Cu")
	)
	(gr_line
		(start 395.693646 -1.85166)
		(end 396.023846 -1.85166)
		(stroke
			(width 0.254)
			(type default)
		)
		(layer "In1.Cu")
	)
	(gr_line
		(start 395.693646 -1.751584)
		(end 396.023846 -1.751584)
		(stroke
			(width 0.254)
			(type default)
		)
		(layer "In1.Cu")
	)
	(gr_line
		(start 395.795246 -12.207748)
		(end 395.795246 -10.404348)
		(stroke
			(width 0.254)
			(type default)
		)
		(layer "In1.Cu")
	)
	(gr_line
		(start 395.795246 -12.207748)
		(end 395.795246 -10.226548)
		(stroke
			(width 0.762)
			(type default)
		)
		(layer "In1.Cu")
	)
	(gr_line
		(start 395.795246 -12.107672)
		(end 395.795246 -10.304272)
		(stroke
			(width 0.254)
			(type default)
		)
		(layer "In1.Cu")
	)
	(gr_line
		(start 395.795246 -12.107672)
		(end 395.795246 -10.126472)
		(stroke
			(width 0.762)
			(type default)
		)
		(layer "In1.Cu")
	)
	(gr_line
		(start 395.795246 -10.404348)
		(end 395.896846 -10.404348)
		(stroke
			(width 0.254)
			(type default)
		)
		(layer "In1.Cu")
	)
	(gr_line
		(start 395.795246 -10.304272)
		(end 395.896846 -10.304272)
		(stroke
			(width 0.254)
			(type default)
		)
		(layer "In1.Cu")
	)
	(gr_line
		(start 395.795246 -8.007604)
		(end 395.795246 -6.204204)
		(stroke
			(width 0.254)
			(type default)
		)
		(layer "In1.Cu")
	)
	(gr_line
		(start 395.795246 -8.007604)
		(end 395.795246 -6.026404)
		(stroke
			(width 0.762)
			(type default)
		)
		(layer "In1.Cu")
	)
	(gr_line
		(start 395.795246 -7.907528)
		(end 395.795246 -6.104128)
		(stroke
			(width 0.254)
			(type default)
		)
		(layer "In1.Cu")
	)
	(gr_line
		(start 395.795246 -7.907528)
		(end 395.795246 -5.926328)
		(stroke
			(width 0.762)
			(type default)
		)
		(layer "In1.Cu")
	)
	(gr_line
		(start 395.795246 -6.204204)
		(end 395.896846 -6.204204)
		(stroke
			(width 0.254)
			(type default)
		)
		(layer "In1.Cu")
	)
	(gr_line
		(start 395.795246 -6.104128)
		(end 395.896846 -6.104128)
		(stroke
			(width 0.254)
			(type default)
		)
		(layer "In1.Cu")
	)
	(gr_line
		(start 395.795246 -3.80746)
		(end 395.795246 -2.00406)
		(stroke
			(width 0.254)
			(type default)
		)
		(layer "In1.Cu")
	)
	(gr_line
		(start 395.795246 -3.80746)
		(end 395.795246 -1.82626)
		(stroke
			(width 0.762)
			(type default)
		)
		(layer "In1.Cu")
	)
	(gr_line
		(start 395.795246 -3.707384)
		(end 395.795246 -1.903984)
		(stroke
			(width 0.254)
			(type default)
		)
		(layer "In1.Cu")
	)
	(gr_line
		(start 395.795246 -3.707384)
		(end 395.795246 -1.726184)
		(stroke
			(width 0.762)
			(type default)
		)
		(layer "In1.Cu")
	)
	(gr_line
		(start 395.795246 -2.00406)
		(end 395.896846 -2.00406)
		(stroke
			(width 0.254)
			(type default)
		)
		(layer "In1.Cu")
	)
	(gr_line
		(start 395.795246 -1.903984)
		(end 395.896846 -1.903984)
		(stroke
			(width 0.254)
			(type default)
		)
		(layer "In1.Cu")
	)
	(gr_line
		(start 395.896846 -12.309348)
		(end 395.846046 -12.309348)
		(stroke
			(width 0.254)
			(type default)
		)
		(layer "In1.Cu")
	)
	(gr_line
		(start 395.896846 -12.209272)
		(end 395.846046 -12.209272)
		(stroke
			(width 0.254)
			(type default)
		)
		(layer "In1.Cu")
	)
	(gr_line
		(start 395.896846 -10.404348)
		(end 395.896846 -12.309348)
		(stroke
			(width 0.254)
			(type default)
		)
		(layer "In1.Cu")
	)
	(gr_line
		(start 395.896846 -10.304272)
		(end 395.896846 -12.209272)
		(stroke
			(width 0.254)
			(type default)
		)
		(layer "In1.Cu")
	)
	(gr_line
		(start 395.896846 -8.109204)
		(end 395.846046 -8.109204)
		(stroke
			(width 0.254)
			(type default)
		)
		(layer "In1.Cu")
	)
	(gr_line
		(start 395.896846 -8.009128)
		(end 395.846046 -8.009128)
		(stroke
			(width 0.254)
			(type default)
		)
		(layer "In1.Cu")
	)
	(gr_line
		(start 395.896846 -6.204204)
		(end 395.896846 -8.109204)
		(stroke
			(width 0.254)
			(type default)
		)
		(layer "In1.Cu")
	)
	(gr_line
		(start 395.896846 -6.104128)
		(end 395.896846 -8.009128)
		(stroke
			(width 0.254)
			(type default)
		)
		(layer "In1.Cu")
	)
	(gr_line
		(start 395.896846 -3.90906)
		(end 395.846046 -3.90906)
		(stroke
			(width 0.254)
			(type default)
		)
		(layer "In1.Cu")
	)
	(gr_line
		(start 395.896846 -3.808984)
		(end 395.846046 -3.808984)
		(stroke
			(width 0.254)
			(type default)
		)
		(layer "In1.Cu")
	)
	(gr_line
		(start 395.896846 -2.00406)
		(end 395.896846 -3.90906)
		(stroke
			(width 0.254)
			(type default)
		)
		(layer "In1.Cu")
	)
	(gr_line
		(start 395.896846 -1.903984)
		(end 395.896846 -3.808984)
		(stroke
			(width 0.254)
			(type default)
		)
		(layer "In1.Cu")
	)
	(gr_line
		(start 395.947646 -12.233148)
		(end 395.947646 -10.251948)
		(stroke
			(width 0.762)
			(type default)
		)
		(layer "In1.Cu")
	)
	(gr_line
		(start 395.947646 -12.133072)
		(end 395.947646 -10.151872)
		(stroke
			(width 0.762)
			(type default)
		)
		(layer "In1.Cu")
	)
	(gr_line
		(start 395.947646 -8.033004)
		(end 395.947646 -6.051804)
		(stroke
			(width 0.762)
			(type default)
		)
		(layer "In1.Cu")
	)
	(gr_line
		(start 395.947646 -7.932928)
		(end 395.947646 -5.951728)
		(stroke
			(width 0.762)
			(type default)
		)
		(layer "In1.Cu")
	)
	(gr_line
		(start 395.947646 -3.83286)
		(end 395.947646 -1.85166)
		(stroke
			(width 0.762)
			(type default)
		)
		(layer "In1.Cu")
	)
	(gr_line
		(start 395.947646 -3.732784)
		(end 395.947646 -1.751584)
		(stroke
			(width 0.762)
			(type default)
		)
		(layer "In1.Cu")
	)
	(gr_line
		(start 396.023846 -12.207748)
		(end 395.795246 -12.207748)
		(stroke
			(width 0.254)
			(type default)
		)
		(layer "In1.Cu")
	)
	(gr_line
		(start 396.023846 -12.107672)
		(end 395.795246 -12.107672)
		(stroke
			(width 0.254)
			(type default)
		)
		(layer "In1.Cu")
	)
	(gr_line
		(start 396.023846 -10.251948)
		(end 396.023846 -12.207748)
		(stroke
			(width 0.254)
			(type default)
		)
		(layer "In1.Cu")
	)
	(gr_line
		(start 396.023846 -10.151872)
		(end 396.023846 -12.107672)
		(stroke
			(width 0.254)
			(type default)
		)
		(layer "In1.Cu")
	)
	(gr_line
		(start 396.023846 -8.007604)
		(end 395.795246 -8.007604)
		(stroke
			(width 0.254)
			(type default)
		)
		(layer "In1.Cu")
	)
	(gr_line
		(start 396.023846 -7.907528)
		(end 395.795246 -7.907528)
		(stroke
			(width 0.254)
			(type default)
		)
		(layer "In1.Cu")
	)
	(gr_line
		(start 396.023846 -6.051804)
		(end 396.023846 -8.007604)
		(stroke
			(width 0.254)
			(type default)
		)
		(layer "In1.Cu")
	)
	(gr_line
		(start 396.023846 -5.951728)
		(end 396.023846 -7.907528)
		(stroke
			(width 0.254)
			(type default)
		)
		(layer "In1.Cu")
	)
	(gr_line
		(start 396.023846 -3.80746)
		(end 395.795246 -3.80746)
		(stroke
			(width 0.254)
			(type default)
		)
		(layer "In1.Cu")
	)
	(gr_line
		(start 396.023846 -3.707384)
		(end 395.795246 -3.707384)
		(stroke
			(width 0.254)
			(type default)
		)
		(layer "In1.Cu")
	)
	(gr_line
		(start 396.023846 -1.85166)
		(end 396.023846 -3.80746)
		(stroke
			(width 0.254)
			(type default)
		)
		(layer "In1.Cu")
	)
	(gr_line
		(start 396.023846 -1.751584)
		(end 396.023846 -3.707384)
		(stroke
			(width 0.254)
			(type default)
		)
		(layer "In1.Cu")
	)
	(gr_line
		(start 396.074646 -12.563348)
		(end 396.074646 -12.512548)
		(stroke
			(width 0.1016)
			(type default)
		)
		(layer "In1.Cu")
	)
	(gr_line
		(start 396.074646 -12.563348)
		(end 396.481046 -12.563348)
		(stroke
			(width 0.1016)
			(type default)
		)
		(layer "In1.Cu")
	)
	(gr_line
		(start 396.074646 -12.512548)
		(end 395.312646 -12.512548)
		(stroke
			(width 0.1016)
			(type default)
		)
		(layer "In1.Cu")
	)
	(gr_line
		(start 396.074646 -12.463272)
		(end 396.074646 -12.412472)
		(stroke
			(width 0.1016)
			(type default)
		)
		(layer "In1.Cu")
	)
	(gr_line
		(start 396.074646 -12.463272)
		(end 396.481046 -12.463272)
		(stroke
			(width 0.1016)
			(type default)
		)
		(layer "In1.Cu")
	)
	(gr_line
		(start 396.074646 -12.412472)
		(end 395.312646 -12.412472)
		(stroke
			(width 0.1016)
			(type default)
		)
		(layer "In1.Cu")
	)
	(gr_line
		(start 396.074646 -12.233148)
		(end 396.074646 -10.251948)
		(stroke
			(width 0.762)
			(type default)
		)
		(layer "In1.Cu")
	)
	(gr_line
		(start 396.074646 -12.133072)
		(end 396.074646 -10.151872)
		(stroke
			(width 0.762)
			(type default)
		)
		(layer "In1.Cu")
	)
	(gr_line
		(start 396.074646 -8.363204)
		(end 396.074646 -8.312404)
		(stroke
			(width 0.1016)
			(type default)
		)
		(layer "In1.Cu")
	)
	(gr_line
		(start 396.074646 -8.363204)
		(end 396.481046 -8.363204)
		(stroke
			(width 0.1016)
			(type default)
		)
		(layer "In1.Cu")
	)
	(gr_line
		(start 396.074646 -8.312404)
		(end 395.312646 -8.312404)
		(stroke
			(width 0.1016)
			(type default)
		)
		(layer "In1.Cu")
	)
	(gr_line
		(start 396.074646 -8.263128)
		(end 396.074646 -8.212328)
		(stroke
			(width 0.1016)
			(type default)
		)
		(layer "In1.Cu")
	)
	(gr_line
		(start 396.074646 -8.263128)
		(end 396.481046 -8.263128)
		(stroke
			(width 0.1016)
			(type default)
		)
		(layer "In1.Cu")
	)
	(gr_line
		(start 396.074646 -8.212328)
		(end 395.312646 -8.212328)
		(stroke
			(width 0.1016)
			(type default)
		)
		(layer "In1.Cu")
	)
	(gr_line
		(start 396.074646 -8.033004)
		(end 396.074646 -6.051804)
		(stroke
			(width 0.762)
			(type default)
		)
		(layer "In1.Cu")
	)
	(gr_line
		(start 396.074646 -7.932928)
		(end 396.074646 -5.951728)
		(stroke
			(width 0.762)
			(type default)
		)
		(layer "In1.Cu")
	)
	(gr_line
		(start 396.074646 -4.16306)
		(end 396.074646 -4.11226)
		(stroke
			(width 0.1016)
			(type default)
		)
		(layer "In1.Cu")
	)
	(gr_line
		(start 396.074646 -4.16306)
		(end 396.481046 -4.16306)
		(stroke
			(width 0.1016)
			(type default)
		)
		(layer "In1.Cu")
	)
	(gr_line
		(start 396.074646 -4.11226)
		(end 395.312646 -4.11226)
		(stroke
			(width 0.1016)
			(type default)
		)
		(layer "In1.Cu")
	)
	(gr_line
		(start 396.074646 -4.062984)
		(end 396.074646 -4.012184)
		(stroke
			(width 0.1016)
			(type default)
		)
		(layer "In1.Cu")
	)
	(gr_line
		(start 396.074646 -4.062984)
		(end 396.481046 -4.062984)
		(stroke
			(width 0.1016)
			(type default)
		)
		(layer "In1.Cu")
	)
	(gr_line
		(start 396.074646 -4.012184)
		(end 395.312646 -4.012184)
		(stroke
			(width 0.1016)
			(type default)
		)
		(layer "In1.Cu")
	)
	(gr_line
		(start 396.074646 -3.83286)
		(end 396.074646 -1.85166)
		(stroke
			(width 0.762)
			(type default)
		)
		(layer "In1.Cu")
	)
	(gr_line
		(start 396.074646 -3.732784)
		(end 396.074646 -1.751584)
		(stroke
			(width 0.762)
			(type default)
		)
		(layer "In1.Cu")
	)
	(gr_line
		(start 396.100046 -12.283948)
		(end 395.693646 -12.283948)
		(stroke
			(width 0.254)
			(type default)
		)
		(layer "In1.Cu")
	)
	(gr_line
		(start 396.100046 -12.183872)
		(end 395.693646 -12.183872)
		(stroke
			(width 0.254)
			(type default)
		)
		(layer "In1.Cu")
	)
	(gr_line
		(start 396.100046 -10.175748)
		(end 396.100046 -12.283948)
		(stroke
			(width 0.254)
			(type default)
		)
		(layer "In1.Cu")
	)
	(gr_line
		(start 396.100046 -10.075672)
		(end 396.100046 -12.183872)
		(stroke
			(width 0.254)
			(type default)
		)
		(layer "In1.Cu")
	)
	(gr_line
		(start 396.100046 -8.083804)
		(end 395.693646 -8.083804)
		(stroke
			(width 0.254)
			(type default)
		)
		(layer "In1.Cu")
	)
	(gr_line
		(start 396.100046 -7.983728)
		(end 395.693646 -7.983728)
		(stroke
			(width 0.254)
			(type default)
		)
		(layer "In1.Cu")
	)
	(gr_line
		(start 396.100046 -5.975604)
		(end 396.100046 -8.083804)
		(stroke
			(width 0.254)
			(type default)
		)
		(layer "In1.Cu")
	)
	(gr_line
		(start 396.100046 -5.875528)
		(end 396.100046 -7.983728)
		(stroke
			(width 0.254)
			(type default)
		)
		(layer "In1.Cu")
	)
	(gr_line
		(start 396.100046 -3.88366)
		(end 395.693646 -3.88366)
		(stroke
			(width 0.254)
			(type default)
		)
		(layer "In1.Cu")
	)
	(gr_line
		(start 396.100046 -3.783584)
		(end 395.693646 -3.783584)
		(stroke
			(width 0.254)
			(type default)
		)
		(layer "In1.Cu")
	)
	(gr_line
		(start 396.100046 -1.77546)
		(end 396.100046 -3.88366)
		(stroke
			(width 0.254)
			(type default)
		)
		(layer "In1.Cu")
	)
	(gr_line
		(start 396.100046 -1.675384)
		(end 396.100046 -3.783584)
		(stroke
			(width 0.254)
			(type default)
		)
		(layer "In1.Cu")
	)
	(gr_line
		(start 396.150846 -12.233148)
		(end 396.150846 -10.251948)
		(stroke
			(width 0.762)
			(type default)
		)
		(layer "In1.Cu")
	)
	(gr_line
		(start 396.150846 -12.133072)
		(end 396.150846 -10.151872)
		(stroke
			(width 0.762)
			(type default)
		)
		(layer "In1.Cu")
	)
	(gr_line
		(start 396.150846 -8.033004)
		(end 396.150846 -6.051804)
		(stroke
			(width 0.762)
			(type default)
		)
		(layer "In1.Cu")
	)
	(gr_line
		(start 396.150846 -7.932928)
		(end 396.150846 -5.951728)
		(stroke
			(width 0.762)
			(type default)
		)
		(layer "In1.Cu")
	)
	(gr_line
		(start 396.150846 -3.83286)
		(end 396.150846 -1.85166)
		(stroke
			(width 0.762)
			(type default)
		)
		(layer "In1.Cu")
	)
	(gr_line
		(start 396.150846 -3.732784)
		(end 396.150846 -1.751584)
		(stroke
			(width 0.762)
			(type default)
		)
		(layer "In1.Cu")
	)
	(gr_line
		(start 396.176246 -12.360148)
		(end 395.617446 -12.360148)
		(stroke
			(width 0.254)
			(type default)
		)
		(layer "In1.Cu")
	)
	(gr_line
		(start 396.176246 -12.260072)
		(end 395.617446 -12.260072)
		(stroke
			(width 0.254)
			(type default)
		)
		(layer "In1.Cu")
	)
	(gr_line
		(start 396.176246 -10.124948)
		(end 396.176246 -12.360148)
		(stroke
			(width 0.254)
			(type default)
		)
		(layer "In1.Cu")
	)
	(gr_line
		(start 396.176246 -10.024872)
		(end 396.176246 -12.260072)
		(stroke
			(width 0.254)
			(type default)
		)
		(layer "In1.Cu")
	)
	(gr_line
		(start 396.176246 -8.160004)
		(end 395.617446 -8.160004)
		(stroke
			(width 0.254)
			(type default)
		)
		(layer "In1.Cu")
	)
	(gr_line
		(start 396.176246 -8.059928)
		(end 395.617446 -8.059928)
		(stroke
			(width 0.254)
			(type default)
		)
		(layer "In1.Cu")
	)
	(gr_line
		(start 396.176246 -5.924804)
		(end 396.176246 -8.160004)
		(stroke
			(width 0.254)
			(type default)
		)
		(layer "In1.Cu")
	)
	(gr_line
		(start 396.176246 -5.824728)
		(end 396.176246 -8.059928)
		(stroke
			(width 0.254)
			(type default)
		)
		(layer "In1.Cu")
	)
	(gr_line
		(start 396.176246 -3.95986)
		(end 395.617446 -3.95986)
		(stroke
			(width 0.254)
			(type default)
		)
		(layer "In1.Cu")
	)
	(gr_line
		(start 396.176246 -3.859784)
		(end 395.617446 -3.859784)
		(stroke
			(width 0.254)
			(type default)
		)
		(layer "In1.Cu")
	)
	(gr_line
		(start 396.176246 -1.72466)
		(end 396.176246 -3.95986)
		(stroke
			(width 0.254)
			(type default)
		)
		(layer "In1.Cu")
	)
	(gr_line
		(start 396.176246 -1.624584)
		(end 396.176246 -3.859784)
		(stroke
			(width 0.254)
			(type default)
		)
		(layer "In1.Cu")
	)
	(gr_line
		(start 396.252446 -12.385548)
		(end 395.541246 -12.385548)
		(stroke
			(width 0.254)
			(type default)
		)
		(layer "In1.Cu")
	)
	(gr_line
		(start 396.252446 -12.285472)
		(end 395.541246 -12.285472)
		(stroke
			(width 0.254)
			(type default)
		)
		(layer "In1.Cu")
	)
	(gr_line
		(start 396.252446 -10.048748)
		(end 396.252446 -12.385548)
		(stroke
			(width 0.254)
			(type default)
		)
		(layer "In1.Cu")
	)
	(gr_line
		(start 396.252446 -9.948672)
		(end 396.252446 -12.285472)
		(stroke
			(width 0.254)
			(type default)
		)
		(layer "In1.Cu")
	)
	(gr_line
		(start 396.252446 -8.185404)
		(end 395.541246 -8.185404)
		(stroke
			(width 0.254)
			(type default)
		)
		(layer "In1.Cu")
	)
	(gr_line
		(start 396.252446 -8.085328)
		(end 395.541246 -8.085328)
		(stroke
			(width 0.254)
			(type default)
		)
		(layer "In1.Cu")
	)
	(gr_line
		(start 396.252446 -5.848604)
		(end 396.252446 -8.185404)
		(stroke
			(width 0.254)
			(type default)
		)
		(layer "In1.Cu")
	)
	(gr_line
		(start 396.252446 -5.748528)
		(end 396.252446 -8.085328)
		(stroke
			(width 0.254)
			(type default)
		)
		(layer "In1.Cu")
	)
	(gr_line
		(start 396.252446 -3.98526)
		(end 395.541246 -3.98526)
		(stroke
			(width 0.254)
			(type default)
		)
		(layer "In1.Cu")
	)
	(gr_line
		(start 396.252446 -3.885184)
		(end 395.541246 -3.885184)
		(stroke
			(width 0.254)
			(type default)
		)
		(layer "In1.Cu")
	)
	(gr_line
		(start 396.252446 -1.64846)
		(end 396.252446 -3.98526)
		(stroke
			(width 0.254)
			(type default)
		)
		(layer "In1.Cu")
	)
	(gr_line
		(start 396.252446 -1.548384)
		(end 396.252446 -3.885184)
		(stroke
			(width 0.254)
			(type default)
		)
		(layer "In1.Cu")
	)
	(gr_line
		(start 396.277846 -12.512548)
		(end 395.287246 -12.512548)
		(stroke
			(width 0.1016)
			(type default)
		)
		(layer "In1.Cu")
	)
	(gr_line
		(start 396.277846 -12.436348)
		(end 395.465046 -12.436348)
		(stroke
			(width 0.254)
			(type default)
		)
		(layer "In1.Cu")
	)
	(gr_line
		(start 396.277846 -12.412472)
		(end 395.287246 -12.412472)
		(stroke
			(width 0.1016)
			(type default)
		)
		(layer "In1.Cu")
	)
	(gr_line
		(start 396.277846 -12.336272)
		(end 395.465046 -12.336272)
		(stroke
			(width 0.254)
			(type default)
		)
		(layer "In1.Cu")
	)
	(gr_line
		(start 396.277846 -10.023348)
		(end 396.277846 -12.436348)
		(stroke
			(width 0.254)
			(type default)
		)
		(layer "In1.Cu")
	)
	(gr_line
		(start 396.277846 -9.923272)
		(end 396.277846 -12.336272)
		(stroke
			(width 0.254)
			(type default)
		)
		(layer "In1.Cu")
	)
	(gr_line
		(start 396.277846 -8.312404)
		(end 395.287246 -8.312404)
		(stroke
			(width 0.1016)
			(type default)
		)
		(layer "In1.Cu")
	)
	(gr_line
		(start 396.277846 -8.236204)
		(end 395.465046 -8.236204)
		(stroke
			(width 0.254)
			(type default)
		)
		(layer "In1.Cu")
	)
	(gr_line
		(start 396.277846 -8.212328)
		(end 395.287246 -8.212328)
		(stroke
			(width 0.1016)
			(type default)
		)
		(layer "In1.Cu")
	)
	(gr_line
		(start 396.277846 -8.136128)
		(end 395.465046 -8.136128)
		(stroke
			(width 0.254)
			(type default)
		)
		(layer "In1.Cu")
	)
	(gr_line
		(start 396.277846 -5.823204)
		(end 396.277846 -8.236204)
		(stroke
			(width 0.254)
			(type default)
		)
		(layer "In1.Cu")
	)
	(gr_line
		(start 396.277846 -5.723128)
		(end 396.277846 -8.136128)
		(stroke
			(width 0.254)
			(type default)
		)
		(layer "In1.Cu")
	)
	(gr_line
		(start 396.277846 -4.11226)
		(end 395.287246 -4.11226)
		(stroke
			(width 0.1016)
			(type default)
		)
		(layer "In1.Cu")
	)
	(gr_line
		(start 396.277846 -4.03606)
		(end 395.465046 -4.03606)
		(stroke
			(width 0.254)
			(type default)
		)
		(layer "In1.Cu")
	)
	(gr_line
		(start 396.277846 -4.012184)
		(end 395.287246 -4.012184)
		(stroke
			(width 0.1016)
			(type default)
		)
		(layer "In1.Cu")
	)
	(gr_line
		(start 396.277846 -3.935984)
		(end 395.465046 -3.935984)
		(stroke
			(width 0.254)
			(type default)
		)
		(layer "In1.Cu")
	)
	(gr_line
		(start 396.277846 -1.62306)
		(end 396.277846 -4.03606)
		(stroke
			(width 0.254)
			(type default)
		)
		(layer "In1.Cu")
	)
	(gr_line
		(start 396.277846 -1.522984)
		(end 396.277846 -3.935984)
		(stroke
			(width 0.254)
			(type default)
		)
		(layer "In1.Cu")
	)
	(gr_line
		(start 396.296896 -29.337)
		(end 397.135096 -29.337)
		(stroke
			(width 0.1016)
			(type default)
		)
		(layer "In1.Cu")
	)
	(gr_line
		(start 396.296896 -27.4828)
		(end 396.296896 -29.337)
		(stroke
			(width 0.1016)
			(type default)
		)
		(layer "In1.Cu")
	)
	(gr_line
		(start 396.303246 -12.461748)
		(end 395.439646 -12.461748)
		(stroke
			(width 0.254)
			(type default)
		)
		(layer "In1.Cu")
	)
	(gr_line
		(start 396.303246 -12.361672)
		(end 395.439646 -12.361672)
		(stroke
			(width 0.254)
			(type default)
		)
		(layer "In1.Cu")
	)
	(gr_line
		(start 396.303246 -9.997948)
		(end 396.303246 -12.461748)
		(stroke
			(width 0.254)
			(type default)
		)
		(layer "In1.Cu")
	)
	(gr_line
		(start 396.303246 -9.897872)
		(end 396.303246 -12.361672)
		(stroke
			(width 0.254)
			(type default)
		)
		(layer "In1.Cu")
	)
	(gr_line
		(start 396.303246 -8.261604)
		(end 395.439646 -8.261604)
		(stroke
			(width 0.254)
			(type default)
		)
		(layer "In1.Cu")
	)
	(gr_line
		(start 396.303246 -8.161528)
		(end 395.439646 -8.161528)
		(stroke
			(width 0.254)
			(type default)
		)
		(layer "In1.Cu")
	)
	(gr_line
		(start 396.303246 -5.797804)
		(end 396.303246 -8.261604)
		(stroke
			(width 0.254)
			(type default)
		)
		(layer "In1.Cu")
	)
	(gr_line
		(start 396.303246 -5.697728)
		(end 396.303246 -8.161528)
		(stroke
			(width 0.254)
			(type default)
		)
		(layer "In1.Cu")
	)
	(gr_line
		(start 396.303246 -4.06146)
		(end 395.439646 -4.06146)
		(stroke
			(width 0.254)
			(type default)
		)
		(layer "In1.Cu")
	)
	(gr_line
		(start 396.303246 -3.961384)
		(end 395.439646 -3.961384)
		(stroke
			(width 0.254)
			(type default)
		)
		(layer "In1.Cu")
	)
	(gr_line
		(start 396.303246 -1.59766)
		(end 396.303246 -4.06146)
		(stroke
			(width 0.254)
			(type default)
		)
		(layer "In1.Cu")
	)
	(gr_line
		(start 396.303246 -1.497584)
		(end 396.303246 -3.961384)
		(stroke
			(width 0.254)
			(type default)
		)
		(layer "In1.Cu")
	)
	(gr_line
		(start 396.347696 -29.2354)
		(end 396.347696 -27.559)
		(stroke
			(width 0.2032)
			(type default)
		)
		(layer "In1.Cu")
	)
	(gr_line
		(start 396.347696 -27.559)
		(end 397.414496 -27.559)
		(stroke
			(width 0.2032)
			(type default)
		)
		(layer "In1.Cu")
	)
	(gr_line
		(start 396.354046 -12.487148)
		(end 395.414246 -12.487148)
		(stroke
			(width 0.254)
			(type default)
		)
		(layer "In1.Cu")
	)
	(gr_line
		(start 396.354046 -12.387072)
		(end 395.414246 -12.387072)
		(stroke
			(width 0.254)
			(type default)
		)
		(layer "In1.Cu")
	)
	(gr_line
		(start 396.354046 -9.997948)
		(end 396.354046 -12.487148)
		(stroke
			(width 0.254)
			(type default)
		)
		(layer "In1.Cu")
	)
	(gr_line
		(start 396.354046 -9.897872)
		(end 396.354046 -12.387072)
		(stroke
			(width 0.254)
			(type default)
		)
		(layer "In1.Cu")
	)
	(gr_line
		(start 396.354046 -8.287004)
		(end 395.414246 -8.287004)
		(stroke
			(width 0.254)
			(type default)
		)
		(layer "In1.Cu")
	)
	(gr_line
		(start 396.354046 -8.186928)
		(end 395.414246 -8.186928)
		(stroke
			(width 0.254)
			(type default)
		)
		(layer "In1.Cu")
	)
	(gr_line
		(start 396.354046 -5.797804)
		(end 396.354046 -8.287004)
		(stroke
			(width 0.254)
			(type default)
		)
		(layer "In1.Cu")
	)
	(gr_line
		(start 396.354046 -5.697728)
		(end 396.354046 -8.186928)
		(stroke
			(width 0.254)
			(type default)
		)
		(layer "In1.Cu")
	)
	(gr_line
		(start 396.354046 -4.08686)
		(end 395.414246 -4.08686)
		(stroke
			(width 0.254)
			(type default)
		)
		(layer "In1.Cu")
	)
	(gr_line
		(start 396.354046 -3.986784)
		(end 395.414246 -3.986784)
		(stroke
			(width 0.254)
			(type default)
		)
		(layer "In1.Cu")
	)
	(gr_line
		(start 396.354046 -1.59766)
		(end 396.354046 -4.08686)
		(stroke
			(width 0.254)
			(type default)
		)
		(layer "In1.Cu")
	)
	(gr_line
		(start 396.354046 -1.497584)
		(end 396.354046 -3.986784)
		(stroke
			(width 0.254)
			(type default)
		)
		(layer "In1.Cu")
	)
	(gr_line
		(start 396.373096 -29.2608)
		(end 397.363696 -29.2608)
		(stroke
			(width 0.2032)
			(type default)
		)
		(layer "In1.Cu")
	)
	(gr_line
		(start 396.373096 -29.2354)
		(end 396.373096 -29.2608)
		(stroke
			(width 0.2032)
			(type default)
		)
		(layer "In1.Cu")
	)
	(gr_line
		(start 396.379446 -12.487148)
		(end 395.414246 -12.487148)
		(stroke
			(width 0.2032)
			(type default)
		)
		(layer "In1.Cu")
	)
	(gr_line
		(start 396.379446 -12.387072)
		(end 395.414246 -12.387072)
		(stroke
			(width 0.2032)
			(type default)
		)
		(layer "In1.Cu")
	)
	(gr_line
		(start 396.379446 -9.947148)
		(end 396.379446 -12.487148)
		(stroke
			(width 0.2032)
			(type default)
		)
		(layer "In1.Cu")
	)
	(gr_line
		(start 396.379446 -9.847072)
		(end 396.379446 -12.387072)
		(stroke
			(width 0.2032)
			(type default)
		)
		(layer "In1.Cu")
	)
	(gr_line
		(start 396.379446 -8.287004)
		(end 395.414246 -8.287004)
		(stroke
			(width 0.2032)
			(type default)
		)
		(layer "In1.Cu")
	)
	(gr_line
		(start 396.379446 -8.186928)
		(end 395.414246 -8.186928)
		(stroke
			(width 0.2032)
			(type default)
		)
		(layer "In1.Cu")
	)
	(gr_line
		(start 396.379446 -5.747004)
		(end 396.379446 -8.287004)
		(stroke
			(width 0.2032)
			(type default)
		)
		(layer "In1.Cu")
	)
	(gr_line
		(start 396.379446 -5.646928)
		(end 396.379446 -8.186928)
		(stroke
			(width 0.2032)
			(type default)
		)
		(layer "In1.Cu")
	)
	(gr_line
		(start 396.379446 -4.08686)
		(end 395.414246 -4.08686)
		(stroke
			(width 0.2032)
			(type default)
		)
		(layer "In1.Cu")
	)
	(gr_line
		(start 396.379446 -3.986784)
		(end 395.414246 -3.986784)
		(stroke
			(width 0.2032)
			(type default)
		)
		(layer "In1.Cu")
	)
	(gr_line
		(start 396.379446 -1.54686)
		(end 396.379446 -4.08686)
		(stroke
			(width 0.2032)
			(type default)
		)
		(layer "In1.Cu")
	)
	(gr_line
		(start 396.379446 -1.446784)
		(end 396.379446 -3.986784)
		(stroke
			(width 0.2032)
			(type default)
		)
		(layer "In1.Cu")
	)
	(gr_line
		(start 396.423896 -29.1846)
		(end 397.363696 -29.1846)
		(stroke
			(width 0.2032)
			(type default)
		)
		(layer "In1.Cu")
	)
	(gr_line
		(start 396.423896 -27.6098)
		(end 396.423896 -29.1846)
		(stroke
			(width 0.2032)
			(type default)
		)
		(layer "In1.Cu")
	)
	(gr_line
		(start 396.430246 -12.512548)
		(end 395.363446 -12.512548)
		(stroke
			(width 0.2032)
			(type default)
		)
		(layer "In1.Cu")
	)
	(gr_line
		(start 396.430246 -12.412472)
		(end 395.363446 -12.412472)
		(stroke
			(width 0.2032)
			(type default)
		)
		(layer "In1.Cu")
	)
	(gr_line
		(start 396.430246 -9.947148)
		(end 396.430246 -12.512548)
		(stroke
			(width 0.2032)
			(type default)
		)
		(layer "In1.Cu")
	)
	(gr_line
		(start 396.430246 -9.847072)
		(end 396.430246 -12.412472)
		(stroke
			(width 0.2032)
			(type default)
		)
		(layer "In1.Cu")
	)
	(gr_line
		(start 396.430246 -8.312404)
		(end 395.363446 -8.312404)
		(stroke
			(width 0.2032)
			(type default)
		)
		(layer "In1.Cu")
	)
	(gr_line
		(start 396.430246 -8.212328)
		(end 395.363446 -8.212328)
		(stroke
			(width 0.2032)
			(type default)
		)
		(layer "In1.Cu")
	)
	(gr_line
		(start 396.430246 -5.747004)
		(end 396.430246 -8.312404)
		(stroke
			(width 0.2032)
			(type default)
		)
		(layer "In1.Cu")
	)
	(gr_line
		(start 396.430246 -5.646928)
		(end 396.430246 -8.212328)
		(stroke
			(width 0.2032)
			(type default)
		)
		(layer "In1.Cu")
	)
	(gr_line
		(start 396.430246 -4.11226)
		(end 395.363446 -4.11226)
		(stroke
			(width 0.2032)
			(type default)
		)
		(layer "In1.Cu")
	)
	(gr_line
		(start 396.430246 -4.012184)
		(end 395.363446 -4.012184)
		(stroke
			(width 0.2032)
			(type default)
		)
		(layer "In1.Cu")
	)
	(gr_line
		(start 396.430246 -1.54686)
		(end 396.430246 -4.11226)
		(stroke
			(width 0.2032)
			(type default)
		)
		(layer "In1.Cu")
	)
	(gr_line
		(start 396.430246 -1.446784)
		(end 396.430246 -4.012184)
		(stroke
			(width 0.2032)
			(type default)
		)
		(layer "In1.Cu")
	)
	(gr_line
		(start 396.455646 -12.512548)
		(end 395.338046 -12.512548)
		(stroke
			(width 0.1016)
			(type default)
		)
		(layer "In1.Cu")
	)
	(gr_line
		(start 396.455646 -12.412472)
		(end 395.338046 -12.412472)
		(stroke
			(width 0.1016)
			(type default)
		)
		(layer "In1.Cu")
	)
	(gr_line
		(start 396.455646 -9.921748)
		(end 396.455646 -12.512548)
		(stroke
			(width 0.1016)
			(type default)
		)
		(layer "In1.Cu")
	)
	(gr_line
		(start 396.455646 -9.821672)
		(end 396.455646 -12.412472)
		(stroke
			(width 0.1016)
			(type default)
		)
		(layer "In1.Cu")
	)
	(gr_line
		(start 396.455646 -8.312404)
		(end 395.338046 -8.312404)
		(stroke
			(width 0.1016)
			(type default)
		)
		(layer "In1.Cu")
	)
	(gr_line
		(start 396.455646 -8.212328)
		(end 395.338046 -8.212328)
		(stroke
			(width 0.1016)
			(type default)
		)
		(layer "In1.Cu")
	)
	(gr_line
		(start 396.455646 -5.721604)
		(end 396.455646 -8.312404)
		(stroke
			(width 0.1016)
			(type default)
		)
		(layer "In1.Cu")
	)
	(gr_line
		(start 396.455646 -5.621528)
		(end 396.455646 -8.212328)
		(stroke
			(width 0.1016)
			(type default)
		)
		(layer "In1.Cu")
	)
	(gr_line
		(start 396.455646 -4.11226)
		(end 395.338046 -4.11226)
		(stroke
			(width 0.1016)
			(type default)
		)
		(layer "In1.Cu")
	)
	(gr_line
		(start 396.455646 -4.012184)
		(end 395.338046 -4.012184)
		(stroke
			(width 0.1016)
			(type default)
		)
		(layer "In1.Cu")
	)
	(gr_line
		(start 396.455646 -1.52146)
		(end 396.455646 -4.11226)
		(stroke
			(width 0.1016)
			(type default)
		)
		(layer "In1.Cu")
	)
	(gr_line
		(start 396.455646 -1.421384)
		(end 396.455646 -4.012184)
		(stroke
			(width 0.1016)
			(type default)
		)
		(layer "In1.Cu")
	)
	(gr_line
		(start 396.481046 -12.563348)
		(end 396.074646 -12.563348)
		(stroke
			(width 0.1016)
			(type default)
		)
		(layer "In1.Cu")
	)
	(gr_line
		(start 396.481046 -12.563348)
		(end 396.481046 -9.896348)
		(stroke
			(width 0.1016)
			(type default)
		)
		(layer "In1.Cu")
	)
	(gr_line
		(start 396.481046 -12.463272)
		(end 396.074646 -12.463272)
		(stroke
			(width 0.1016)
			(type default)
		)
		(layer "In1.Cu")
	)
	(gr_line
		(start 396.481046 -12.463272)
		(end 396.481046 -9.796272)
		(stroke
			(width 0.1016)
			(type default)
		)
		(layer "In1.Cu")
	)
	(gr_line
		(start 396.481046 -9.896348)
		(end 395.287246 -9.896348)
		(stroke
			(width 0.1016)
			(type default)
		)
		(layer "In1.Cu")
	)
	(gr_line
		(start 396.481046 -9.896348)
		(end 396.481046 -12.563348)
		(stroke
			(width 0.1016)
			(type default)
		)
		(layer "In1.Cu")
	)
	(gr_line
		(start 396.481046 -9.796272)
		(end 395.287246 -9.796272)
		(stroke
			(width 0.1016)
			(type default)
		)
		(layer "In1.Cu")
	)
	(gr_line
		(start 396.481046 -9.796272)
		(end 396.481046 -12.463272)
		(stroke
			(width 0.1016)
			(type default)
		)
		(layer "In1.Cu")
	)
	(gr_line
		(start 396.481046 -8.363204)
		(end 396.074646 -8.363204)
		(stroke
			(width 0.1016)
			(type default)
		)
		(layer "In1.Cu")
	)
	(gr_line
		(start 396.481046 -8.363204)
		(end 396.481046 -5.696204)
		(stroke
			(width 0.1016)
			(type default)
		)
		(layer "In1.Cu")
	)
	(gr_line
		(start 396.481046 -8.263128)
		(end 396.074646 -8.263128)
		(stroke
			(width 0.1016)
			(type default)
		)
		(layer "In1.Cu")
	)
	(gr_line
		(start 396.481046 -8.263128)
		(end 396.481046 -5.596128)
		(stroke
			(width 0.1016)
			(type default)
		)
		(layer "In1.Cu")
	)
	(gr_line
		(start 396.481046 -5.696204)
		(end 395.287246 -5.696204)
		(stroke
			(width 0.1016)
			(type default)
		)
		(layer "In1.Cu")
	)
	(gr_line
		(start 396.481046 -5.696204)
		(end 396.481046 -8.363204)
		(stroke
			(width 0.1016)
			(type default)
		)
		(layer "In1.Cu")
	)
	(gr_line
		(start 396.481046 -5.596128)
		(end 395.287246 -5.596128)
		(stroke
			(width 0.1016)
			(type default)
		)
		(layer "In1.Cu")
	)
	(gr_line
		(start 396.481046 -5.596128)
		(end 396.481046 -8.263128)
		(stroke
			(width 0.1016)
			(type default)
		)
		(layer "In1.Cu")
	)
	(gr_line
		(start 396.481046 -4.16306)
		(end 396.074646 -4.16306)
		(stroke
			(width 0.1016)
			(type default)
		)
		(layer "In1.Cu")
	)
	(gr_line
		(start 396.481046 -4.16306)
		(end 396.481046 -1.49606)
		(stroke
			(width 0.1016)
			(type default)
		)
		(layer "In1.Cu")
	)
	(gr_line
		(start 396.481046 -4.062984)
		(end 396.074646 -4.062984)
		(stroke
			(width 0.1016)
			(type default)
		)
		(layer "In1.Cu")
	)
	(gr_line
		(start 396.481046 -4.062984)
		(end 396.481046 -1.395984)
		(stroke
			(width 0.1016)
			(type default)
		)
		(layer "In1.Cu")
	)
	(gr_line
		(start 396.481046 -1.49606)
		(end 395.287246 -1.49606)
		(stroke
			(width 0.1016)
			(type default)
		)
		(layer "In1.Cu")
	)
	(gr_line
		(start 396.481046 -1.49606)
		(end 396.481046 -4.16306)
		(stroke
			(width 0.1016)
			(type default)
		)
		(layer "In1.Cu")
	)
	(gr_line
		(start 396.481046 -1.395984)
		(end 395.287246 -1.395984)
		(stroke
			(width 0.1016)
			(type default)
		)
		(layer "In1.Cu")
	)
	(gr_line
		(start 396.481046 -1.395984)
		(end 396.481046 -4.062984)
		(stroke
			(width 0.1016)
			(type default)
		)
		(layer "In1.Cu")
	)
	(gr_line
		(start 396.500096 -29.1084)
		(end 396.500096 -27.7622)
		(stroke
			(width 0.508)
			(type default)
		)
		(layer "In1.Cu")
	)
	(gr_line
		(start 396.525496 -29.1084)
		(end 397.185896 -29.1084)
		(stroke
			(width 0.508)
			(type default)
		)
		(layer "In1.Cu")
	)
	(gr_line
		(start 396.525496 -29.083)
		(end 396.525496 -27.7368)
		(stroke
			(width 0.508)
			(type default)
		)
		(layer "In1.Cu")
	)
	(gr_line
		(start 396.525496 -27.7114)
		(end 397.160496 -27.7114)
		(stroke
			(width 0.508)
			(type default)
		)
		(layer "In1.Cu")
	)
	(gr_line
		(start 396.550896 -29.083)
		(end 396.550896 -27.7368)
		(stroke
			(width 0.508)
			(type default)
		)
		(layer "In1.Cu")
	)
	(gr_line
		(start 396.576296 -29.083)
		(end 396.576296 -27.7368)
		(stroke
			(width 0.508)
			(type default)
		)
		(layer "In1.Cu")
	)
	(gr_line
		(start 396.627096 -29.1084)
		(end 396.627096 -27.7622)
		(stroke
			(width 0.508)
			(type default)
		)
		(layer "In1.Cu")
	)
	(gr_line
		(start 396.627096 -29.083)
		(end 396.627096 -27.7368)
		(stroke
			(width 0.508)
			(type default)
		)
		(layer "In1.Cu")
	)
	(gr_line
		(start 396.677896 -29.083)
		(end 396.677896 -27.7368)
		(stroke
			(width 0.508)
			(type default)
		)
		(layer "In1.Cu")
	)
	(gr_line
		(start 396.696946 -26.826972)
		(end 397.535146 -26.826972)
		(stroke
			(width 0.1016)
			(type default)
		)
		(layer "In1.Cu")
	)
	(gr_line
		(start 396.696946 -24.972772)
		(end 396.696946 -26.826972)
		(stroke
			(width 0.1016)
			(type default)
		)
		(layer "In1.Cu")
	)
	(gr_line
		(start 396.703296 -29.0576)
		(end 396.703296 -27.7114)
		(stroke
			(width 0.508)
			(type default)
		)
		(layer "In1.Cu")
	)
	(gr_line
		(start 396.728696 -29.083)
		(end 396.728696 -27.7368)
		(stroke
			(width 0.508)
			(type default)
		)
		(layer "In1.Cu")
	)
	(gr_line
		(start 396.747746 -26.725372)
		(end 396.747746 -25.048972)
		(stroke
			(width 0.2032)
			(type default)
		)
		(layer "In1.Cu")
	)
	(gr_line
		(start 396.747746 -25.048972)
		(end 397.814546 -25.048972)
		(stroke
			(width 0.2032)
			(type default)
		)
		(layer "In1.Cu")
	)
	(gr_line
		(start 396.754096 -29.083)
		(end 396.754096 -27.7368)
		(stroke
			(width 0.508)
			(type default)
		)
		(layer "In1.Cu")
	)
	(gr_line
		(start 396.773146 -26.750772)
		(end 397.763746 -26.750772)
		(stroke
			(width 0.2032)
			(type default)
		)
		(layer "In1.Cu")
	)
	(gr_line
		(start 396.773146 -26.725372)
		(end 396.773146 -26.750772)
		(stroke
			(width 0.2032)
			(type default)
		)
		(layer "In1.Cu")
	)
	(gr_line
		(start 396.779496 -29.083)
		(end 396.779496 -27.7368)
		(stroke
			(width 0.508)
			(type default)
		)
		(layer "In1.Cu")
	)
	(gr_line
		(start 396.823946 -26.674572)
		(end 397.763746 -26.674572)
		(stroke
			(width 0.2032)
			(type default)
		)
		(layer "In1.Cu")
	)
	(gr_line
		(start 396.823946 -25.099772)
		(end 396.823946 -26.674572)
		(stroke
			(width 0.2032)
			(type default)
		)
		(layer "In1.Cu")
	)
	(gr_line
		(start 396.830296 -29.083)
		(end 396.830296 -27.7368)
		(stroke
			(width 0.508)
			(type default)
		)
		(layer "In1.Cu")
	)
	(gr_line
		(start 396.855696 -29.083)
		(end 396.855696 -27.7368)
		(stroke
			(width 0.508)
			(type default)
		)
		(layer "In1.Cu")
	)
	(gr_line
		(start 396.881096 -29.083)
		(end 396.881096 -27.7368)
		(stroke
			(width 0.508)
			(type default)
		)
		(layer "In1.Cu")
	)
	(gr_line
		(start 396.900146 -26.598372)
		(end 396.900146 -25.252172)
		(stroke
			(width 0.508)
			(type default)
		)
		(layer "In1.Cu")
	)
	(gr_line
		(start 396.906496 -29.083)
		(end 396.906496 -27.7368)
		(stroke
			(width 0.508)
			(type default)
		)
		(layer "In1.Cu")
	)
	(gr_line
		(start 396.925546 -26.598372)
		(end 397.585946 -26.598372)
		(stroke
			(width 0.508)
			(type default)
		)
		(layer "In1.Cu")
	)
	(gr_line
		(start 396.925546 -26.572972)
		(end 396.925546 -25.226772)
		(stroke
			(width 0.508)
			(type default)
		)
		(layer "In1.Cu")
	)
	(gr_line
		(start 396.925546 -25.201372)
		(end 397.560546 -25.201372)
		(stroke
			(width 0.508)
			(type default)
		)
		(layer "In1.Cu")
	)
	(gr_line
		(start 396.931896 -29.1084)
		(end 396.931896 -27.7622)
		(stroke
			(width 0.508)
			(type default)
		)
		(layer "In1.Cu")
	)
	(gr_line
		(start 396.950946 -26.572972)
		(end 396.950946 -25.226772)
		(stroke
			(width 0.508)
			(type default)
		)
		(layer "In1.Cu")
	)
	(gr_line
		(start 396.957296 -29.1084)
		(end 396.957296 -27.7622)
		(stroke
			(width 0.508)
			(type default)
		)
		(layer "In1.Cu")
	)
	(gr_line
		(start 396.957296 -29.083)
		(end 396.957296 -27.7368)
		(stroke
			(width 0.508)
			(type default)
		)
		(layer "In1.Cu")
	)
	(gr_line
		(start 396.976346 -26.572972)
		(end 396.976346 -25.226772)
		(stroke
			(width 0.508)
			(type default)
		)
		(layer "In1.Cu")
	)
	(gr_line
		(start 396.982696 -29.083)
		(end 396.982696 -27.7368)
		(stroke
			(width 0.508)
			(type default)
		)
		(layer "In1.Cu")
	)
	(gr_line
		(start 397.008096 -29.083)
		(end 397.008096 -27.7368)
		(stroke
			(width 0.508)
			(type default)
		)
		(layer "In1.Cu")
	)
	(gr_line
		(start 397.027146 -26.598372)
		(end 397.027146 -25.252172)
		(stroke
			(width 0.508)
			(type default)
		)
		(layer "In1.Cu")
	)
	(gr_line
		(start 397.027146 -26.572972)
		(end 397.027146 -25.226772)
		(stroke
			(width 0.508)
			(type default)
		)
		(layer "In1.Cu")
	)
	(gr_line
		(start 397.033496 -29.083)
		(end 397.033496 -27.7368)
		(stroke
			(width 0.508)
			(type default)
		)
		(layer "In1.Cu")
	)
	(gr_line
		(start 397.058896 -29.1084)
		(end 397.058896 -27.7622)
		(stroke
			(width 0.508)
			(type default)
		)
		(layer "In1.Cu")
	)
	(gr_line
		(start 397.058896 -29.083)
		(end 397.058896 -27.7368)
		(stroke
			(width 0.508)
			(type default)
		)
		(layer "In1.Cu")
	)
	(gr_line
		(start 397.077946 -26.572972)
		(end 397.077946 -25.226772)
		(stroke
			(width 0.508)
			(type default)
		)
		(layer "In1.Cu")
	)
	(gr_line
		(start 397.084296 -29.1084)
		(end 397.084296 -27.7622)
		(stroke
			(width 0.508)
			(type default)
		)
		(layer "In1.Cu")
	)
	(gr_line
		(start 397.084296 -29.083)
		(end 397.084296 -27.7368)
		(stroke
			(width 0.508)
			(type default)
		)
		(layer "In1.Cu")
	)
	(gr_line
		(start 397.103346 -26.547572)
		(end 397.103346 -25.201372)
		(stroke
			(width 0.508)
			(type default)
		)
		(layer "In1.Cu")
	)
	(gr_line
		(start 397.109696 -29.1084)
		(end 397.109696 -27.7622)
		(stroke
			(width 0.508)
			(type default)
		)
		(layer "In1.Cu")
	)
	(gr_line
		(start 397.128746 -26.572972)
		(end 397.128746 -25.226772)
		(stroke
			(width 0.508)
			(type default)
		)
		(layer "In1.Cu")
	)
	(gr_line
		(start 397.135096 -29.337)
		(end 397.465296 -29.337)
		(stroke
			(width 0.1016)
			(type default)
		)
		(layer "In1.Cu")
	)
	(gr_line
		(start 397.135096 -29.083)
		(end 397.135096 -27.7368)
		(stroke
			(width 0.508)
			(type default)
		)
		(layer "In1.Cu")
	)
	(gr_line
		(start 397.154146 -26.572972)
		(end 397.154146 -25.226772)
		(stroke
			(width 0.508)
			(type default)
		)
		(layer "In1.Cu")
	)
	(gr_line
		(start 397.160496 -29.1084)
		(end 397.160496 -27.7622)
		(stroke
			(width 0.508)
			(type default)
		)
		(layer "In1.Cu")
	)
	(gr_line
		(start 397.160496 -29.083)
		(end 397.160496 -27.7368)
		(stroke
			(width 0.508)
			(type default)
		)
		(layer "In1.Cu")
	)
	(gr_line
		(start 397.179546 -26.572972)
		(end 397.179546 -25.226772)
		(stroke
			(width 0.508)
			(type default)
		)
		(layer "In1.Cu")
	)
	(gr_line
		(start 397.185896 -29.1084)
		(end 397.185896 -27.7622)
		(stroke
			(width 0.508)
			(type default)
		)
		(layer "In1.Cu")
	)
	(gr_line
		(start 397.230346 -26.572972)
		(end 397.230346 -25.226772)
		(stroke
			(width 0.508)
			(type default)
		)
		(layer "In1.Cu")
	)
	(gr_line
		(start 397.255746 -26.572972)
		(end 397.255746 -25.226772)
		(stroke
			(width 0.508)
			(type default)
		)
		(layer "In1.Cu")
	)
	(gr_line
		(start 397.262096 -29.1084)
		(end 397.262096 -27.7622)
		(stroke
			(width 0.508)
			(type default)
		)
		(layer "In1.Cu")
	)
	(gr_line
		(start 397.281146 -26.572972)
		(end 397.281146 -25.226772)
		(stroke
			(width 0.508)
			(type default)
		)
		(layer "In1.Cu")
	)
	(gr_line
		(start 397.306546 -26.572972)
		(end 397.306546 -25.226772)
		(stroke
			(width 0.508)
			(type default)
		)
		(layer "In1.Cu")
	)
	(gr_line
		(start 397.331946 -26.598372)
		(end 397.331946 -25.252172)
		(stroke
			(width 0.508)
			(type default)
		)
		(layer "In1.Cu")
	)
	(gr_line
		(start 397.357346 -26.598372)
		(end 397.357346 -25.252172)
		(stroke
			(width 0.508)
			(type default)
		)
		(layer "In1.Cu")
	)
	(gr_line
		(start 397.357346 -26.572972)
		(end 397.357346 -25.226772)
		(stroke
			(width 0.508)
			(type default)
		)
		(layer "In1.Cu")
	)
	(gr_line
		(start 397.363696 -29.2608)
		(end 397.363696 -27.6098)
		(stroke
			(width 0.2032)
			(type default)
		)
		(layer "In1.Cu")
	)
	(gr_line
		(start 397.363696 -29.2354)
		(end 396.347696 -29.2354)
		(stroke
			(width 0.2032)
			(type default)
		)
		(layer "In1.Cu")
	)
	(gr_line
		(start 397.363696 -29.1846)
		(end 397.363696 -29.2354)
		(stroke
			(width 0.2032)
			(type default)
		)
		(layer "In1.Cu")
	)
	(gr_line
		(start 397.363696 -27.6098)
		(end 396.423896 -27.6098)
		(stroke
			(width 0.2032)
			(type default)
		)
		(layer "In1.Cu")
	)
	(gr_line
		(start 397.382746 -26.572972)
		(end 397.382746 -25.226772)
		(stroke
			(width 0.508)
			(type default)
		)
		(layer "In1.Cu")
	)
	(gr_line
		(start 397.408146 -26.572972)
		(end 397.408146 -25.226772)
		(stroke
			(width 0.508)
			(type default)
		)
		(layer "In1.Cu")
	)
	(gr_line
		(start 397.414496 -29.2354)
		(end 396.373096 -29.2354)
		(stroke
			(width 0.2032)
			(type default)
		)
		(layer "In1.Cu")
	)
	(gr_line
		(start 397.414496 -27.559)
		(end 397.414496 -29.2354)
		(stroke
			(width 0.2032)
			(type default)
		)
		(layer "In1.Cu")
	)
	(gr_line
		(start 397.433546 -26.572972)
		(end 397.433546 -25.226772)
		(stroke
			(width 0.508)
			(type default)
		)
		(layer "In1.Cu")
	)
	(gr_line
		(start 397.458946 -26.598372)
		(end 397.458946 -25.252172)
		(stroke
			(width 0.508)
			(type default)
		)
		(layer "In1.Cu")
	)
	(gr_line
		(start 397.458946 -26.572972)
		(end 397.458946 -25.226772)
		(stroke
			(width 0.508)
			(type default)
		)
		(layer "In1.Cu")
	)
	(gr_line
		(start 397.465296 -29.337)
		(end 397.465296 -27.4828)
		(stroke
			(width 0.1016)
			(type default)
		)
		(layer "In1.Cu")
	)
	(gr_line
		(start 397.465296 -27.4828)
		(end 396.296896 -27.4828)
		(stroke
			(width 0.1016)
			(type default)
		)
		(layer "In1.Cu")
	)
	(gr_line
		(start 397.484346 -26.598372)
		(end 397.484346 -25.252172)
		(stroke
			(width 0.508)
			(type default)
		)
		(layer "In1.Cu")
	)
	(gr_line
		(start 397.484346 -26.572972)
		(end 397.484346 -25.226772)
		(stroke
			(width 0.508)
			(type default)
		)
		(layer "In1.Cu")
	)
	(gr_line
		(start 397.509746 -26.598372)
		(end 397.509746 -25.252172)
		(stroke
			(width 0.508)
			(type default)
		)
		(layer "In1.Cu")
	)
	(gr_line
		(start 397.519906 -30.99562)
		(end 396.249906 -30.99562)
		(stroke
			(width 0.7874)
			(type default)
		)
		(layer "In1.Cu")
	)
	(gr_line
		(start 397.535146 -26.826972)
		(end 397.865346 -26.826972)
		(stroke
			(width 0.1016)
			(type default)
		)
		(layer "In1.Cu")
	)
	(gr_line
		(start 397.535146 -26.572972)
		(end 397.535146 -25.226772)
		(stroke
			(width 0.508)
			(type default)
		)
		(layer "In1.Cu")
	)
	(gr_line
		(start 397.560546 -26.598372)
		(end 397.560546 -25.252172)
		(stroke
			(width 0.508)
			(type default)
		)
		(layer "In1.Cu")
	)
	(gr_line
		(start 397.560546 -26.572972)
		(end 397.560546 -25.226772)
		(stroke
			(width 0.508)
			(type default)
		)
		(layer "In1.Cu")
	)
	(gr_line
		(start 397.585946 -26.598372)
		(end 397.585946 -25.252172)
		(stroke
			(width 0.508)
			(type default)
		)
		(layer "In1.Cu")
	)
	(gr_line
		(start 397.662146 -26.598372)
		(end 397.662146 -25.252172)
		(stroke
			(width 0.508)
			(type default)
		)
		(layer "In1.Cu")
	)
	(gr_line
		(start 397.763746 -26.750772)
		(end 397.763746 -25.099772)
		(stroke
			(width 0.2032)
			(type default)
		)
		(layer "In1.Cu")
	)
	(gr_line
		(start 397.763746 -26.725372)
		(end 396.747746 -26.725372)
		(stroke
			(width 0.2032)
			(type default)
		)
		(layer "In1.Cu")
	)
	(gr_line
		(start 397.763746 -26.674572)
		(end 397.763746 -26.725372)
		(stroke
			(width 0.2032)
			(type default)
		)
		(layer "In1.Cu")
	)
	(gr_line
		(start 397.763746 -25.099772)
		(end 396.823946 -25.099772)
		(stroke
			(width 0.2032)
			(type default)
		)
		(layer "In1.Cu")
	)
	(gr_line
		(start 397.814546 -26.725372)
		(end 396.773146 -26.725372)
		(stroke
			(width 0.2032)
			(type default)
		)
		(layer "In1.Cu")
	)
	(gr_line
		(start 397.814546 -25.048972)
		(end 397.814546 -26.725372)
		(stroke
			(width 0.2032)
			(type default)
		)
		(layer "In1.Cu")
	)
	(gr_line
		(start 397.865346 -26.826972)
		(end 397.865346 -24.972772)
		(stroke
			(width 0.1016)
			(type default)
		)
		(layer "In1.Cu")
	)
	(gr_line
		(start 397.865346 -24.972772)
		(end 396.696946 -24.972772)
		(stroke
			(width 0.1016)
			(type default)
		)
		(layer "In1.Cu")
	)
	(gr_line
		(start 399.224246 -24.6634)
		(end 399.224246 -23.3934)
		(stroke
			(width 0.7874)
			(type default)
		)
		(layer "In1.Cu")
	)
	(gr_line
		(start 404.997412 -26.8224)
		(end 406.267412 -26.8224)
		(stroke
			(width 0.7874)
			(type default)
		)
		(layer "In1.Cu")
	)
	(gr_line
		(start 405.228552 -29.30906)
		(end 406.498552 -29.30906)
		(stroke
			(width 0.7874)
			(type default)
		)
		(layer "In1.Cu")
	)
	(gr_line
		(start 408.107134 -29.337)
		(end 408.945334 -29.337)
		(stroke
			(width 0.1016)
			(type default)
		)
		(layer "In1.Cu")
	)
	(gr_line
		(start 408.107134 -27.4828)
		(end 408.107134 -29.337)
		(stroke
			(width 0.1016)
			(type default)
		)
		(layer "In1.Cu")
	)
	(gr_line
		(start 408.157934 -29.2354)
		(end 408.157934 -27.559)
		(stroke
			(width 0.2032)
			(type default)
		)
		(layer "In1.Cu")
	)
	(gr_line
		(start 408.157934 -27.559)
		(end 409.224734 -27.559)
		(stroke
			(width 0.2032)
			(type default)
		)
		(layer "In1.Cu")
	)
	(gr_line
		(start 408.183334 -29.2608)
		(end 409.173934 -29.2608)
		(stroke
			(width 0.2032)
			(type default)
		)
		(layer "In1.Cu")
	)
	(gr_line
		(start 408.183334 -29.2354)
		(end 408.183334 -29.2608)
		(stroke
			(width 0.2032)
			(type default)
		)
		(layer "In1.Cu")
	)
	(gr_line
		(start 408.234134 -29.1846)
		(end 409.173934 -29.1846)
		(stroke
			(width 0.2032)
			(type default)
		)
		(layer "In1.Cu")
	)
	(gr_line
		(start 408.234134 -27.6098)
		(end 408.234134 -29.1846)
		(stroke
			(width 0.2032)
			(type default)
		)
		(layer "In1.Cu")
	)
	(gr_line
		(start 408.310334 -29.1084)
		(end 408.310334 -27.7622)
		(stroke
			(width 0.508)
			(type default)
		)
		(layer "In1.Cu")
	)
	(gr_line
		(start 408.335734 -29.1084)
		(end 408.996134 -29.1084)
		(stroke
			(width 0.508)
			(type default)
		)
		(layer "In1.Cu")
	)
	(gr_line
		(start 408.335734 -29.083)
		(end 408.335734 -27.7368)
		(stroke
			(width 0.508)
			(type default)
		)
		(layer "In1.Cu")
	)
	(gr_line
		(start 408.335734 -27.7114)
		(end 408.970734 -27.7114)
		(stroke
			(width 0.508)
			(type default)
		)
		(layer "In1.Cu")
	)
	(gr_line
		(start 408.361134 -29.083)
		(end 408.361134 -27.7368)
		(stroke
			(width 0.508)
			(type default)
		)
		(layer "In1.Cu")
	)
	(gr_line
		(start 408.386534 -29.083)
		(end 408.386534 -27.7368)
		(stroke
			(width 0.508)
			(type default)
		)
		(layer "In1.Cu")
	)
	(gr_line
		(start 408.437334 -29.1084)
		(end 408.437334 -27.7622)
		(stroke
			(width 0.508)
			(type default)
		)
		(layer "In1.Cu")
	)
	(gr_line
		(start 408.437334 -29.083)
		(end 408.437334 -27.7368)
		(stroke
			(width 0.508)
			(type default)
		)
		(layer "In1.Cu")
	)
	(gr_line
		(start 408.488134 -29.083)
		(end 408.488134 -27.7368)
		(stroke
			(width 0.508)
			(type default)
		)
		(layer "In1.Cu")
	)
	(gr_line
		(start 408.507184 -26.826972)
		(end 409.345384 -26.826972)
		(stroke
			(width 0.1016)
			(type default)
		)
		(layer "In1.Cu")
	)
	(gr_line
		(start 408.507184 -24.972772)
		(end 408.507184 -26.826972)
		(stroke
			(width 0.1016)
			(type default)
		)
		(layer "In1.Cu")
	)
	(gr_line
		(start 408.513534 -29.0576)
		(end 408.513534 -27.7114)
		(stroke
			(width 0.508)
			(type default)
		)
		(layer "In1.Cu")
	)
	(gr_line
		(start 408.538934 -29.083)
		(end 408.538934 -27.7368)
		(stroke
			(width 0.508)
			(type default)
		)
		(layer "In1.Cu")
	)
	(gr_line
		(start 408.557984 -26.725372)
		(end 408.557984 -25.048972)
		(stroke
			(width 0.2032)
			(type default)
		)
		(layer "In1.Cu")
	)
	(gr_line
		(start 408.557984 -25.048972)
		(end 409.624784 -25.048972)
		(stroke
			(width 0.2032)
			(type default)
		)
		(layer "In1.Cu")
	)
	(gr_line
		(start 408.564334 -29.083)
		(end 408.564334 -27.7368)
		(stroke
			(width 0.508)
			(type default)
		)
		(layer "In1.Cu")
	)
	(gr_line
		(start 408.583384 -26.750772)
		(end 409.573984 -26.750772)
		(stroke
			(width 0.2032)
			(type default)
		)
		(layer "In1.Cu")
	)
	(gr_line
		(start 408.583384 -26.725372)
		(end 408.583384 -26.750772)
		(stroke
			(width 0.2032)
			(type default)
		)
		(layer "In1.Cu")
	)
	(gr_line
		(start 408.589734 -29.083)
		(end 408.589734 -27.7368)
		(stroke
			(width 0.508)
			(type default)
		)
		(layer "In1.Cu")
	)
	(gr_line
		(start 408.634184 -26.674572)
		(end 409.573984 -26.674572)
		(stroke
			(width 0.2032)
			(type default)
		)
		(layer "In1.Cu")
	)
	(gr_line
		(start 408.634184 -25.099772)
		(end 408.634184 -26.674572)
		(stroke
			(width 0.2032)
			(type default)
		)
		(layer "In1.Cu")
	)
	(gr_line
		(start 408.640534 -29.083)
		(end 408.640534 -27.7368)
		(stroke
			(width 0.508)
			(type default)
		)
		(layer "In1.Cu")
	)
	(gr_line
		(start 408.665934 -29.083)
		(end 408.665934 -27.7368)
		(stroke
			(width 0.508)
			(type default)
		)
		(layer "In1.Cu")
	)
	(gr_line
		(start 408.691334 -29.083)
		(end 408.691334 -27.7368)
		(stroke
			(width 0.508)
			(type default)
		)
		(layer "In1.Cu")
	)
	(gr_line
		(start 408.710384 -26.598372)
		(end 408.710384 -25.252172)
		(stroke
			(width 0.508)
			(type default)
		)
		(layer "In1.Cu")
	)
	(gr_line
		(start 408.716734 -29.083)
		(end 408.716734 -27.7368)
		(stroke
			(width 0.508)
			(type default)
		)
		(layer "In1.Cu")
	)
	(gr_line
		(start 408.735784 -26.598372)
		(end 409.396184 -26.598372)
		(stroke
			(width 0.508)
			(type default)
		)
		(layer "In1.Cu")
	)
	(gr_line
		(start 408.735784 -26.572972)
		(end 408.735784 -25.226772)
		(stroke
			(width 0.508)
			(type default)
		)
		(layer "In1.Cu")
	)
	(gr_line
		(start 408.735784 -25.201372)
		(end 409.370784 -25.201372)
		(stroke
			(width 0.508)
			(type default)
		)
		(layer "In1.Cu")
	)
	(gr_line
		(start 408.742134 -29.1084)
		(end 408.742134 -27.7622)
		(stroke
			(width 0.508)
			(type default)
		)
		(layer "In1.Cu")
	)
	(gr_line
		(start 408.761184 -26.572972)
		(end 408.761184 -25.226772)
		(stroke
			(width 0.508)
			(type default)
		)
		(layer "In1.Cu")
	)
	(gr_line
		(start 408.767534 -29.1084)
		(end 408.767534 -27.7622)
		(stroke
			(width 0.508)
			(type default)
		)
		(layer "In1.Cu")
	)
	(gr_line
		(start 408.767534 -29.083)
		(end 408.767534 -27.7368)
		(stroke
			(width 0.508)
			(type default)
		)
		(layer "In1.Cu")
	)
	(gr_line
		(start 408.786584 -26.572972)
		(end 408.786584 -25.226772)
		(stroke
			(width 0.508)
			(type default)
		)
		(layer "In1.Cu")
	)
	(gr_line
		(start 408.792934 -29.083)
		(end 408.792934 -27.7368)
		(stroke
			(width 0.508)
			(type default)
		)
		(layer "In1.Cu")
	)
	(gr_line
		(start 408.818334 -29.083)
		(end 408.818334 -27.7368)
		(stroke
			(width 0.508)
			(type default)
		)
		(layer "In1.Cu")
	)
	(gr_line
		(start 408.837384 -26.598372)
		(end 408.837384 -25.252172)
		(stroke
			(width 0.508)
			(type default)
		)
		(layer "In1.Cu")
	)
	(gr_line
		(start 408.837384 -26.572972)
		(end 408.837384 -25.226772)
		(stroke
			(width 0.508)
			(type default)
		)
		(layer "In1.Cu")
	)
	(gr_line
		(start 408.843734 -29.083)
		(end 408.843734 -27.7368)
		(stroke
			(width 0.508)
			(type default)
		)
		(layer "In1.Cu")
	)
	(gr_line
		(start 408.869134 -29.1084)
		(end 408.869134 -27.7622)
		(stroke
			(width 0.508)
			(type default)
		)
		(layer "In1.Cu")
	)
	(gr_line
		(start 408.869134 -29.083)
		(end 408.869134 -27.7368)
		(stroke
			(width 0.508)
			(type default)
		)
		(layer "In1.Cu")
	)
	(gr_line
		(start 408.888184 -26.572972)
		(end 408.888184 -25.226772)
		(stroke
			(width 0.508)
			(type default)
		)
		(layer "In1.Cu")
	)
	(gr_line
		(start 408.894534 -29.1084)
		(end 408.894534 -27.7622)
		(stroke
			(width 0.508)
			(type default)
		)
		(layer "In1.Cu")
	)
	(gr_line
		(start 408.894534 -29.083)
		(end 408.894534 -27.7368)
		(stroke
			(width 0.508)
			(type default)
		)
		(layer "In1.Cu")
	)
	(gr_line
		(start 408.913584 -26.547572)
		(end 408.913584 -25.201372)
		(stroke
			(width 0.508)
			(type default)
		)
		(layer "In1.Cu")
	)
	(gr_line
		(start 408.919934 -29.1084)
		(end 408.919934 -27.7622)
		(stroke
			(width 0.508)
			(type default)
		)
		(layer "In1.Cu")
	)
	(gr_line
		(start 408.938984 -26.572972)
		(end 408.938984 -25.226772)
		(stroke
			(width 0.508)
			(type default)
		)
		(layer "In1.Cu")
	)
	(gr_line
		(start 408.945334 -29.337)
		(end 409.275534 -29.337)
		(stroke
			(width 0.1016)
			(type default)
		)
		(layer "In1.Cu")
	)
	(gr_line
		(start 408.945334 -29.083)
		(end 408.945334 -27.7368)
		(stroke
			(width 0.508)
			(type default)
		)
		(layer "In1.Cu")
	)
	(gr_line
		(start 408.964384 -26.572972)
		(end 408.964384 -25.226772)
		(stroke
			(width 0.508)
			(type default)
		)
		(layer "In1.Cu")
	)
	(gr_line
		(start 408.970734 -29.1084)
		(end 408.970734 -27.7622)
		(stroke
			(width 0.508)
			(type default)
		)
		(layer "In1.Cu")
	)
	(gr_line
		(start 408.970734 -29.083)
		(end 408.970734 -27.7368)
		(stroke
			(width 0.508)
			(type default)
		)
		(layer "In1.Cu")
	)
	(gr_line
		(start 408.989784 -26.572972)
		(end 408.989784 -25.226772)
		(stroke
			(width 0.508)
			(type default)
		)
		(layer "In1.Cu")
	)
	(gr_line
		(start 408.996134 -29.1084)
		(end 408.996134 -27.7622)
		(stroke
			(width 0.508)
			(type default)
		)
		(layer "In1.Cu")
	)
	(gr_line
		(start 409.040584 -26.572972)
		(end 409.040584 -25.226772)
		(stroke
			(width 0.508)
			(type default)
		)
		(layer "In1.Cu")
	)
	(gr_line
		(start 409.065984 -26.572972)
		(end 409.065984 -25.226772)
		(stroke
			(width 0.508)
			(type default)
		)
		(layer "In1.Cu")
	)
	(gr_line
		(start 409.072334 -29.1084)
		(end 409.072334 -27.7622)
		(stroke
			(width 0.508)
			(type default)
		)
		(layer "In1.Cu")
	)
	(gr_line
		(start 409.091384 -26.572972)
		(end 409.091384 -25.226772)
		(stroke
			(width 0.508)
			(type default)
		)
		(layer "In1.Cu")
	)
	(gr_line
		(start 409.116784 -26.572972)
		(end 409.116784 -25.226772)
		(stroke
			(width 0.508)
			(type default)
		)
		(layer "In1.Cu")
	)
	(gr_line
		(start 409.142184 -26.598372)
		(end 409.142184 -25.252172)
		(stroke
			(width 0.508)
			(type default)
		)
		(layer "In1.Cu")
	)
	(gr_line
		(start 409.167584 -26.598372)
		(end 409.167584 -25.252172)
		(stroke
			(width 0.508)
			(type default)
		)
		(layer "In1.Cu")
	)
	(gr_line
		(start 409.167584 -26.572972)
		(end 409.167584 -25.226772)
		(stroke
			(width 0.508)
			(type default)
		)
		(layer "In1.Cu")
	)
	(gr_line
		(start 409.173934 -29.2608)
		(end 409.173934 -27.6098)
		(stroke
			(width 0.2032)
			(type default)
		)
		(layer "In1.Cu")
	)
	(gr_line
		(start 409.173934 -29.2354)
		(end 408.157934 -29.2354)
		(stroke
			(width 0.2032)
			(type default)
		)
		(layer "In1.Cu")
	)
	(gr_line
		(start 409.173934 -29.1846)
		(end 409.173934 -29.2354)
		(stroke
			(width 0.2032)
			(type default)
		)
		(layer "In1.Cu")
	)
	(gr_line
		(start 409.173934 -27.6098)
		(end 408.234134 -27.6098)
		(stroke
			(width 0.2032)
			(type default)
		)
		(layer "In1.Cu")
	)
	(gr_line
		(start 409.192984 -26.572972)
		(end 409.192984 -25.226772)
		(stroke
			(width 0.508)
			(type default)
		)
		(layer "In1.Cu")
	)
	(gr_line
		(start 409.218384 -26.572972)
		(end 409.218384 -25.226772)
		(stroke
			(width 0.508)
			(type default)
		)
		(layer "In1.Cu")
	)
	(gr_line
		(start 409.224734 -29.2354)
		(end 408.183334 -29.2354)
		(stroke
			(width 0.2032)
			(type default)
		)
		(layer "In1.Cu")
	)
	(gr_line
		(start 409.224734 -27.559)
		(end 409.224734 -29.2354)
		(stroke
			(width 0.2032)
			(type default)
		)
		(layer "In1.Cu")
	)
	(gr_line
		(start 409.243784 -26.572972)
		(end 409.243784 -25.226772)
		(stroke
			(width 0.508)
			(type default)
		)
		(layer "In1.Cu")
	)
	(gr_line
		(start 409.269184 -26.598372)
		(end 409.269184 -25.252172)
		(stroke
			(width 0.508)
			(type default)
		)
		(layer "In1.Cu")
	)
	(gr_line
		(start 409.269184 -26.572972)
		(end 409.269184 -25.226772)
		(stroke
			(width 0.508)
			(type default)
		)
		(layer "In1.Cu")
	)
	(gr_line
		(start 409.275534 -29.337)
		(end 409.275534 -27.4828)
		(stroke
			(width 0.1016)
			(type default)
		)
		(layer "In1.Cu")
	)
	(gr_line
		(start 409.275534 -27.4828)
		(end 408.107134 -27.4828)
		(stroke
			(width 0.1016)
			(type default)
		)
		(layer "In1.Cu")
	)
	(gr_line
		(start 409.294584 -26.598372)
		(end 409.294584 -25.252172)
		(stroke
			(width 0.508)
			(type default)
		)
		(layer "In1.Cu")
	)
	(gr_line
		(start 409.294584 -26.572972)
		(end 409.294584 -25.226772)
		(stroke
			(width 0.508)
			(type default)
		)
		(layer "In1.Cu")
	)
	(gr_line
		(start 409.319984 -26.598372)
		(end 409.319984 -25.252172)
		(stroke
			(width 0.508)
			(type default)
		)
		(layer "In1.Cu")
	)
	(gr_line
		(start 409.345384 -26.826972)
		(end 409.675584 -26.826972)
		(stroke
			(width 0.1016)
			(type default)
		)
		(layer "In1.Cu")
	)
	(gr_line
		(start 409.345384 -26.572972)
		(end 409.345384 -25.226772)
		(stroke
			(width 0.508)
			(type default)
		)
		(layer "In1.Cu")
	)
	(gr_line
		(start 409.370784 -26.598372)
		(end 409.370784 -25.252172)
		(stroke
			(width 0.508)
			(type default)
		)
		(layer "In1.Cu")
	)
	(gr_line
		(start 409.370784 -26.572972)
		(end 409.370784 -25.226772)
		(stroke
			(width 0.508)
			(type default)
		)
		(layer "In1.Cu")
	)
	(gr_line
		(start 409.396184 -26.598372)
		(end 409.396184 -25.252172)
		(stroke
			(width 0.508)
			(type default)
		)
		(layer "In1.Cu")
	)
	(gr_line
		(start 409.472384 -26.598372)
		(end 409.472384 -25.252172)
		(stroke
			(width 0.508)
			(type default)
		)
		(layer "In1.Cu")
	)
	(gr_line
		(start 409.573984 -26.750772)
		(end 409.573984 -25.099772)
		(stroke
			(width 0.2032)
			(type default)
		)
		(layer "In1.Cu")
	)
	(gr_line
		(start 409.573984 -26.725372)
		(end 408.557984 -26.725372)
		(stroke
			(width 0.2032)
			(type default)
		)
		(layer "In1.Cu")
	)
	(gr_line
		(start 409.573984 -26.674572)
		(end 409.573984 -26.725372)
		(stroke
			(width 0.2032)
			(type default)
		)
		(layer "In1.Cu")
	)
	(gr_line
		(start 409.573984 -25.099772)
		(end 408.634184 -25.099772)
		(stroke
			(width 0.2032)
			(type default)
		)
		(layer "In1.Cu")
	)
	(gr_line
		(start 409.624784 -26.725372)
		(end 408.583384 -26.725372)
		(stroke
			(width 0.2032)
			(type default)
		)
		(layer "In1.Cu")
	)
	(gr_line
		(start 409.624784 -25.048972)
		(end 409.624784 -26.725372)
		(stroke
			(width 0.2032)
			(type default)
		)
		(layer "In1.Cu")
	)
	(gr_line
		(start 409.675584 -26.826972)
		(end 409.675584 -24.972772)
		(stroke
			(width 0.1016)
			(type default)
		)
		(layer "In1.Cu")
	)
	(gr_line
		(start 409.675584 -24.972772)
		(end 408.507184 -24.972772)
		(stroke
			(width 0.1016)
			(type default)
		)
		(layer "In1.Cu")
	)
	(gr_line
		(start 410.459682 -30.594808)
		(end 411.729682 -30.594808)
		(stroke
			(width 0.7874)
			(type default)
		)
		(layer "In1.Cu")
	)
	(gr_line
		(start 410.50718 -29.337)
		(end 411.34538 -29.337)
		(stroke
			(width 0.1016)
			(type default)
		)
		(layer "In1.Cu")
	)
	(gr_line
		(start 410.50718 -27.4828)
		(end 410.50718 -29.337)
		(stroke
			(width 0.1016)
			(type default)
		)
		(layer "In1.Cu")
	)
	(gr_line
		(start 410.55798 -29.2354)
		(end 410.55798 -27.559)
		(stroke
			(width 0.2032)
			(type default)
		)
		(layer "In1.Cu")
	)
	(gr_line
		(start 410.55798 -27.559)
		(end 411.62478 -27.559)
		(stroke
			(width 0.2032)
			(type default)
		)
		(layer "In1.Cu")
	)
	(gr_line
		(start 410.58338 -29.2608)
		(end 411.57398 -29.2608)
		(stroke
			(width 0.2032)
			(type default)
		)
		(layer "In1.Cu")
	)
	(gr_line
		(start 410.58338 -29.2354)
		(end 410.58338 -29.2608)
		(stroke
			(width 0.2032)
			(type default)
		)
		(layer "In1.Cu")
	)
	(gr_line
		(start 410.63418 -29.1846)
		(end 411.57398 -29.1846)
		(stroke
			(width 0.2032)
			(type default)
		)
		(layer "In1.Cu")
	)
	(gr_line
		(start 410.63418 -27.6098)
		(end 410.63418 -29.1846)
		(stroke
			(width 0.2032)
			(type default)
		)
		(layer "In1.Cu")
	)
	(gr_line
		(start 410.71038 -29.1084)
		(end 410.71038 -27.7622)
		(stroke
			(width 0.508)
			(type default)
		)
		(layer "In1.Cu")
	)
	(gr_line
		(start 410.73578 -29.1084)
		(end 411.39618 -29.1084)
		(stroke
			(width 0.508)
			(type default)
		)
		(layer "In1.Cu")
	)
	(gr_line
		(start 410.73578 -29.083)
		(end 410.73578 -27.7368)
		(stroke
			(width 0.508)
			(type default)
		)
		(layer "In1.Cu")
	)
	(gr_line
		(start 410.73578 -27.7114)
		(end 411.37078 -27.7114)
		(stroke
			(width 0.508)
			(type default)
		)
		(layer "In1.Cu")
	)
	(gr_line
		(start 410.76118 -29.083)
		(end 410.76118 -27.7368)
		(stroke
			(width 0.508)
			(type default)
		)
		(layer "In1.Cu")
	)
	(gr_line
		(start 410.78658 -29.083)
		(end 410.78658 -27.7368)
		(stroke
			(width 0.508)
			(type default)
		)
		(layer "In1.Cu")
	)
	(gr_line
		(start 410.83738 -29.1084)
		(end 410.83738 -27.7622)
		(stroke
			(width 0.508)
			(type default)
		)
		(layer "In1.Cu")
	)
	(gr_line
		(start 410.83738 -29.083)
		(end 410.83738 -27.7368)
		(stroke
			(width 0.508)
			(type default)
		)
		(layer "In1.Cu")
	)
	(gr_line
		(start 410.859986 -23.57882)
		(end 412.129986 -23.57882)
		(stroke
			(width 0.7874)
			(type default)
		)
		(layer "In1.Cu")
	)
	(gr_line
		(start 410.88818 -29.083)
		(end 410.88818 -27.7368)
		(stroke
			(width 0.508)
			(type default)
		)
		(layer "In1.Cu")
	)
	(gr_line
		(start 410.90723 -26.826972)
		(end 411.74543 -26.826972)
		(stroke
			(width 0.1016)
			(type default)
		)
		(layer "In1.Cu")
	)
	(gr_line
		(start 410.90723 -24.972772)
		(end 410.90723 -26.826972)
		(stroke
			(width 0.1016)
			(type default)
		)
		(layer "In1.Cu")
	)
	(gr_line
		(start 410.91358 -29.0576)
		(end 410.91358 -27.7114)
		(stroke
			(width 0.508)
			(type default)
		)
		(layer "In1.Cu")
	)
	(gr_line
		(start 410.93898 -29.083)
		(end 410.93898 -27.7368)
		(stroke
			(width 0.508)
			(type default)
		)
		(layer "In1.Cu")
	)
	(gr_line
		(start 410.95803 -26.725372)
		(end 410.95803 -25.048972)
		(stroke
			(width 0.2032)
			(type default)
		)
		(layer "In1.Cu")
	)
	(gr_line
		(start 410.95803 -25.048972)
		(end 412.02483 -25.048972)
		(stroke
			(width 0.2032)
			(type default)
		)
		(layer "In1.Cu")
	)
	(gr_line
		(start 410.96438 -29.083)
		(end 410.96438 -27.7368)
		(stroke
			(width 0.508)
			(type default)
		)
		(layer "In1.Cu")
	)
	(gr_line
		(start 410.98343 -26.750772)
		(end 411.97403 -26.750772)
		(stroke
			(width 0.2032)
			(type default)
		)
		(layer "In1.Cu")
	)
	(gr_line
		(start 410.98343 -26.725372)
		(end 410.98343 -26.750772)
		(stroke
			(width 0.2032)
			(type default)
		)
		(layer "In1.Cu")
	)
	(gr_line
		(start 410.98978 -29.083)
		(end 410.98978 -27.7368)
		(stroke
			(width 0.508)
			(type default)
		)
		(layer "In1.Cu")
	)
	(gr_line
		(start 411.03423 -26.674572)
		(end 411.97403 -26.674572)
		(stroke
			(width 0.2032)
			(type default)
		)
		(layer "In1.Cu")
	)
	(gr_line
		(start 411.03423 -25.099772)
		(end 411.03423 -26.674572)
		(stroke
			(width 0.2032)
			(type default)
		)
		(layer "In1.Cu")
	)
	(gr_line
		(start 411.04058 -29.083)
		(end 411.04058 -27.7368)
		(stroke
			(width 0.508)
			(type default)
		)
		(layer "In1.Cu")
	)
	(gr_line
		(start 411.06598 -29.083)
		(end 411.06598 -27.7368)
		(stroke
			(width 0.508)
			(type default)
		)
		(layer "In1.Cu")
	)
	(gr_line
		(start 411.09138 -29.083)
		(end 411.09138 -27.7368)
		(stroke
			(width 0.508)
			(type default)
		)
		(layer "In1.Cu")
	)
	(gr_line
		(start 411.11043 -26.598372)
		(end 411.11043 -25.252172)
		(stroke
			(width 0.508)
			(type default)
		)
		(layer "In1.Cu")
	)
	(gr_line
		(start 411.11678 -29.083)
		(end 411.11678 -27.7368)
		(stroke
			(width 0.508)
			(type default)
		)
		(layer "In1.Cu")
	)
	(gr_line
		(start 411.13583 -26.598372)
		(end 411.79623 -26.598372)
		(stroke
			(width 0.508)
			(type default)
		)
		(layer "In1.Cu")
	)
	(gr_line
		(start 411.13583 -26.572972)
		(end 411.13583 -25.226772)
		(stroke
			(width 0.508)
			(type default)
		)
		(layer "In1.Cu")
	)
	(gr_line
		(start 411.13583 -25.201372)
		(end 411.77083 -25.201372)
		(stroke
			(width 0.508)
			(type default)
		)
		(layer "In1.Cu")
	)
	(gr_line
		(start 411.14218 -29.1084)
		(end 411.14218 -27.7622)
		(stroke
			(width 0.508)
			(type default)
		)
		(layer "In1.Cu")
	)
	(gr_line
		(start 411.16123 -26.572972)
		(end 411.16123 -25.226772)
		(stroke
			(width 0.508)
			(type default)
		)
		(layer "In1.Cu")
	)
	(gr_line
		(start 411.16758 -29.1084)
		(end 411.16758 -27.7622)
		(stroke
			(width 0.508)
			(type default)
		)
		(layer "In1.Cu")
	)
	(gr_line
		(start 411.16758 -29.083)
		(end 411.16758 -27.7368)
		(stroke
			(width 0.508)
			(type default)
		)
		(layer "In1.Cu")
	)
	(gr_line
		(start 411.18663 -26.572972)
		(end 411.18663 -25.226772)
		(stroke
			(width 0.508)
			(type default)
		)
		(layer "In1.Cu")
	)
	(gr_line
		(start 411.19298 -29.083)
		(end 411.19298 -27.7368)
		(stroke
			(width 0.508)
			(type default)
		)
		(layer "In1.Cu")
	)
	(gr_line
		(start 411.21838 -29.083)
		(end 411.21838 -27.7368)
		(stroke
			(width 0.508)
			(type default)
		)
		(layer "In1.Cu")
	)
	(gr_line
		(start 411.23743 -26.598372)
		(end 411.23743 -25.252172)
		(stroke
			(width 0.508)
			(type default)
		)
		(layer "In1.Cu")
	)
	(gr_line
		(start 411.23743 -26.572972)
		(end 411.23743 -25.226772)
		(stroke
			(width 0.508)
			(type default)
		)
		(layer "In1.Cu")
	)
	(gr_line
		(start 411.24378 -29.083)
		(end 411.24378 -27.7368)
		(stroke
			(width 0.508)
			(type default)
		)
		(layer "In1.Cu")
	)
	(gr_line
		(start 411.26918 -29.1084)
		(end 411.26918 -27.7622)
		(stroke
			(width 0.508)
			(type default)
		)
		(layer "In1.Cu")
	)
	(gr_line
		(start 411.26918 -29.083)
		(end 411.26918 -27.7368)
		(stroke
			(width 0.508)
			(type default)
		)
		(layer "In1.Cu")
	)
	(gr_line
		(start 411.28823 -26.572972)
		(end 411.28823 -25.226772)
		(stroke
			(width 0.508)
			(type default)
		)
		(layer "In1.Cu")
	)
	(gr_line
		(start 411.29458 -29.1084)
		(end 411.29458 -27.7622)
		(stroke
			(width 0.508)
			(type default)
		)
		(layer "In1.Cu")
	)
	(gr_line
		(start 411.29458 -29.083)
		(end 411.29458 -27.7368)
		(stroke
			(width 0.508)
			(type default)
		)
		(layer "In1.Cu")
	)
	(gr_line
		(start 411.31363 -26.547572)
		(end 411.31363 -25.201372)
		(stroke
			(width 0.508)
			(type default)
		)
		(layer "In1.Cu")
	)
	(gr_line
		(start 411.31998 -29.1084)
		(end 411.31998 -27.7622)
		(stroke
			(width 0.508)
			(type default)
		)
		(layer "In1.Cu")
	)
	(gr_line
		(start 411.33903 -26.572972)
		(end 411.33903 -25.226772)
		(stroke
			(width 0.508)
			(type default)
		)
		(layer "In1.Cu")
	)
	(gr_line
		(start 411.34538 -29.337)
		(end 411.67558 -29.337)
		(stroke
			(width 0.1016)
			(type default)
		)
		(layer "In1.Cu")
	)
	(gr_line
		(start 411.34538 -29.083)
		(end 411.34538 -27.7368)
		(stroke
			(width 0.508)
			(type default)
		)
		(layer "In1.Cu")
	)
	(gr_line
		(start 411.36443 -26.572972)
		(end 411.36443 -25.226772)
		(stroke
			(width 0.508)
			(type default)
		)
		(layer "In1.Cu")
	)
	(gr_line
		(start 411.37078 -29.1084)
		(end 411.37078 -27.7622)
		(stroke
			(width 0.508)
			(type default)
		)
		(layer "In1.Cu")
	)
	(gr_line
		(start 411.37078 -29.083)
		(end 411.37078 -27.7368)
		(stroke
			(width 0.508)
			(type default)
		)
		(layer "In1.Cu")
	)
	(gr_line
		(start 411.38983 -26.572972)
		(end 411.38983 -25.226772)
		(stroke
			(width 0.508)
			(type default)
		)
		(layer "In1.Cu")
	)
	(gr_line
		(start 411.39618 -29.1084)
		(end 411.39618 -27.7622)
		(stroke
			(width 0.508)
			(type default)
		)
		(layer "In1.Cu")
	)
	(gr_line
		(start 411.44063 -26.572972)
		(end 411.44063 -25.226772)
		(stroke
			(width 0.508)
			(type default)
		)
		(layer "In1.Cu")
	)
	(gr_line
		(start 411.46603 -26.572972)
		(end 411.46603 -25.226772)
		(stroke
			(width 0.508)
			(type default)
		)
		(layer "In1.Cu")
	)
	(gr_line
		(start 411.47238 -29.1084)
		(end 411.47238 -27.7622)
		(stroke
			(width 0.508)
			(type default)
		)
		(layer "In1.Cu")
	)
	(gr_line
		(start 411.49143 -26.572972)
		(end 411.49143 -25.226772)
		(stroke
			(width 0.508)
			(type default)
		)
		(layer "In1.Cu")
	)
	(gr_line
		(start 411.51683 -26.572972)
		(end 411.51683 -25.226772)
		(stroke
			(width 0.508)
			(type default)
		)
		(layer "In1.Cu")
	)
	(gr_line
		(start 411.54223 -26.598372)
		(end 411.54223 -25.252172)
		(stroke
			(width 0.508)
			(type default)
		)
		(layer "In1.Cu")
	)
	(gr_line
		(start 411.56763 -26.598372)
		(end 411.56763 -25.252172)
		(stroke
			(width 0.508)
			(type default)
		)
		(layer "In1.Cu")
	)
	(gr_line
		(start 411.56763 -26.572972)
		(end 411.56763 -25.226772)
		(stroke
			(width 0.508)
			(type default)
		)
		(layer "In1.Cu")
	)
	(gr_line
		(start 411.57398 -29.2608)
		(end 411.57398 -27.6098)
		(stroke
			(width 0.2032)
			(type default)
		)
		(layer "In1.Cu")
	)
	(gr_line
		(start 411.57398 -29.2354)
		(end 410.55798 -29.2354)
		(stroke
			(width 0.2032)
			(type default)
		)
		(layer "In1.Cu")
	)
	(gr_line
		(start 411.57398 -29.1846)
		(end 411.57398 -29.2354)
		(stroke
			(width 0.2032)
			(type default)
		)
		(layer "In1.Cu")
	)
	(gr_line
		(start 411.57398 -27.6098)
		(end 410.63418 -27.6098)
		(stroke
			(width 0.2032)
			(type default)
		)
		(layer "In1.Cu")
	)
	(gr_line
		(start 411.59303 -26.572972)
		(end 411.59303 -25.226772)
		(stroke
			(width 0.508)
			(type default)
		)
		(layer "In1.Cu")
	)
	(gr_line
		(start 411.61843 -26.572972)
		(end 411.61843 -25.226772)
		(stroke
			(width 0.508)
			(type default)
		)
		(layer "In1.Cu")
	)
	(gr_line
		(start 411.62478 -29.2354)
		(end 410.58338 -29.2354)
		(stroke
			(width 0.2032)
			(type default)
		)
		(layer "In1.Cu")
	)
	(gr_line
		(start 411.62478 -27.559)
		(end 411.62478 -29.2354)
		(stroke
			(width 0.2032)
			(type default)
		)
		(layer "In1.Cu")
	)
	(gr_line
		(start 411.64383 -26.572972)
		(end 411.64383 -25.226772)
		(stroke
			(width 0.508)
			(type default)
		)
		(layer "In1.Cu")
	)
	(gr_line
		(start 411.66923 -26.598372)
		(end 411.66923 -25.252172)
		(stroke
			(width 0.508)
			(type default)
		)
		(layer "In1.Cu")
	)
	(gr_line
		(start 411.66923 -26.572972)
		(end 411.66923 -25.226772)
		(stroke
			(width 0.508)
			(type default)
		)
		(layer "In1.Cu")
	)
	(gr_line
		(start 411.67558 -29.337)
		(end 411.67558 -27.4828)
		(stroke
			(width 0.1016)
			(type default)
		)
		(layer "In1.Cu")
	)
	(gr_line
		(start 411.67558 -27.4828)
		(end 410.50718 -27.4828)
		(stroke
			(width 0.1016)
			(type default)
		)
		(layer "In1.Cu")
	)
	(gr_line
		(start 411.69463 -26.598372)
		(end 411.69463 -25.252172)
		(stroke
			(width 0.508)
			(type default)
		)
		(layer "In1.Cu")
	)
	(gr_line
		(start 411.69463 -26.572972)
		(end 411.69463 -25.226772)
		(stroke
			(width 0.508)
			(type default)
		)
		(layer "In1.Cu")
	)
	(gr_line
		(start 411.72003 -26.598372)
		(end 411.72003 -25.252172)
		(stroke
			(width 0.508)
			(type default)
		)
		(layer "In1.Cu")
	)
	(gr_line
		(start 411.74543 -26.826972)
		(end 412.07563 -26.826972)
		(stroke
			(width 0.1016)
			(type default)
		)
		(layer "In1.Cu")
	)
	(gr_line
		(start 411.74543 -26.572972)
		(end 411.74543 -25.226772)
		(stroke
			(width 0.508)
			(type default)
		)
		(layer "In1.Cu")
	)
	(gr_line
		(start 411.77083 -26.598372)
		(end 411.77083 -25.252172)
		(stroke
			(width 0.508)
			(type default)
		)
		(layer "In1.Cu")
	)
	(gr_line
		(start 411.77083 -26.572972)
		(end 411.77083 -25.226772)
		(stroke
			(width 0.508)
			(type default)
		)
		(layer "In1.Cu")
	)
	(gr_line
		(start 411.79623 -26.598372)
		(end 411.79623 -25.252172)
		(stroke
			(width 0.508)
			(type default)
		)
		(layer "In1.Cu")
	)
	(gr_line
		(start 411.87243 -26.598372)
		(end 411.87243 -25.252172)
		(stroke
			(width 0.508)
			(type default)
		)
		(layer "In1.Cu")
	)
	(gr_line
		(start 411.97403 -26.750772)
		(end 411.97403 -25.099772)
		(stroke
			(width 0.2032)
			(type default)
		)
		(layer "In1.Cu")
	)
	(gr_line
		(start 411.97403 -26.725372)
		(end 410.95803 -26.725372)
		(stroke
			(width 0.2032)
			(type default)
		)
		(layer "In1.Cu")
	)
	(gr_line
		(start 411.97403 -26.674572)
		(end 411.97403 -26.725372)
		(stroke
			(width 0.2032)
			(type default)
		)
		(layer "In1.Cu")
	)
	(gr_line
		(start 411.97403 -25.099772)
		(end 411.03423 -25.099772)
		(stroke
			(width 0.2032)
			(type default)
		)
		(layer "In1.Cu")
	)
	(gr_line
		(start 412.02483 -26.725372)
		(end 410.98343 -26.725372)
		(stroke
			(width 0.2032)
			(type default)
		)
		(layer "In1.Cu")
	)
	(gr_line
		(start 412.02483 -25.048972)
		(end 412.02483 -26.725372)
		(stroke
			(width 0.2032)
			(type default)
		)
		(layer "In1.Cu")
	)
	(gr_line
		(start 412.07563 -26.826972)
		(end 412.07563 -24.972772)
		(stroke
			(width 0.1016)
			(type default)
		)
		(layer "In1.Cu")
	)
	(gr_line
		(start 412.07563 -24.972772)
		(end 410.90723 -24.972772)
		(stroke
			(width 0.1016)
			(type default)
		)
		(layer "In1.Cu")
	)
	(gr_line
		(start 412.873952 -31.68142)
		(end 414.143952 -31.68142)
		(stroke
			(width 0.7874)
			(type default)
		)
		(layer "In1.Cu")
	)
	(gr_line
		(start 412.906972 -29.337)
		(end 413.745172 -29.337)
		(stroke
			(width 0.1016)
			(type default)
		)
		(layer "In1.Cu")
	)
	(gr_line
		(start 412.906972 -27.4828)
		(end 412.906972 -29.337)
		(stroke
			(width 0.1016)
			(type default)
		)
		(layer "In1.Cu")
	)
	(gr_line
		(start 412.957772 -29.2354)
		(end 412.957772 -27.559)
		(stroke
			(width 0.2032)
			(type default)
		)
		(layer "In1.Cu")
	)
	(gr_line
		(start 412.957772 -27.559)
		(end 414.024572 -27.559)
		(stroke
			(width 0.2032)
			(type default)
		)
		(layer "In1.Cu")
	)
	(gr_line
		(start 412.983172 -29.2608)
		(end 413.973772 -29.2608)
		(stroke
			(width 0.2032)
			(type default)
		)
		(layer "In1.Cu")
	)
	(gr_line
		(start 412.983172 -29.2354)
		(end 412.983172 -29.2608)
		(stroke
			(width 0.2032)
			(type default)
		)
		(layer "In1.Cu")
	)
	(gr_line
		(start 413.033972 -29.1846)
		(end 413.973772 -29.1846)
		(stroke
			(width 0.2032)
			(type default)
		)
		(layer "In1.Cu")
	)
	(gr_line
		(start 413.033972 -27.6098)
		(end 413.033972 -29.1846)
		(stroke
			(width 0.2032)
			(type default)
		)
		(layer "In1.Cu")
	)
	(gr_line
		(start 413.110172 -29.1084)
		(end 413.110172 -27.7622)
		(stroke
			(width 0.508)
			(type default)
		)
		(layer "In1.Cu")
	)
	(gr_line
		(start 413.135572 -29.1084)
		(end 413.795972 -29.1084)
		(stroke
			(width 0.508)
			(type default)
		)
		(layer "In1.Cu")
	)
	(gr_line
		(start 413.135572 -29.083)
		(end 413.135572 -27.7368)
		(stroke
			(width 0.508)
			(type default)
		)
		(layer "In1.Cu")
	)
	(gr_line
		(start 413.135572 -27.7114)
		(end 413.770572 -27.7114)
		(stroke
			(width 0.508)
			(type default)
		)
		(layer "In1.Cu")
	)
	(gr_line
		(start 413.160972 -29.083)
		(end 413.160972 -27.7368)
		(stroke
			(width 0.508)
			(type default)
		)
		(layer "In1.Cu")
	)
	(gr_line
		(start 413.186372 -29.083)
		(end 413.186372 -27.7368)
		(stroke
			(width 0.508)
			(type default)
		)
		(layer "In1.Cu")
	)
	(gr_line
		(start 413.237172 -29.1084)
		(end 413.237172 -27.7622)
		(stroke
			(width 0.508)
			(type default)
		)
		(layer "In1.Cu")
	)
	(gr_line
		(start 413.237172 -29.083)
		(end 413.237172 -27.7368)
		(stroke
			(width 0.508)
			(type default)
		)
		(layer "In1.Cu")
	)
	(gr_line
		(start 413.260032 -18.5166)
		(end 414.530032 -18.5166)
		(stroke
			(width 0.7874)
			(type default)
		)
		(layer "In1.Cu")
	)
	(gr_line
		(start 413.287972 -29.083)
		(end 413.287972 -27.7368)
		(stroke
			(width 0.508)
			(type default)
		)
		(layer "In1.Cu")
	)
	(gr_line
		(start 413.307022 -26.826972)
		(end 414.145222 -26.826972)
		(stroke
			(width 0.1016)
			(type default)
		)
		(layer "In1.Cu")
	)
	(gr_line
		(start 413.307022 -24.972772)
		(end 413.307022 -26.826972)
		(stroke
			(width 0.1016)
			(type default)
		)
		(layer "In1.Cu")
	)
	(gr_line
		(start 413.313372 -29.0576)
		(end 413.313372 -27.7114)
		(stroke
			(width 0.508)
			(type default)
		)
		(layer "In1.Cu")
	)
	(gr_line
		(start 413.338772 -29.083)
		(end 413.338772 -27.7368)
		(stroke
			(width 0.508)
			(type default)
		)
		(layer "In1.Cu")
	)
	(gr_line
		(start 413.357822 -26.725372)
		(end 413.357822 -25.048972)
		(stroke
			(width 0.2032)
			(type default)
		)
		(layer "In1.Cu")
	)
	(gr_line
		(start 413.357822 -25.048972)
		(end 414.424622 -25.048972)
		(stroke
			(width 0.2032)
			(type default)
		)
		(layer "In1.Cu")
	)
	(gr_line
		(start 413.364172 -29.083)
		(end 413.364172 -27.7368)
		(stroke
			(width 0.508)
			(type default)
		)
		(layer "In1.Cu")
	)
	(gr_line
		(start 413.383222 -26.750772)
		(end 414.373822 -26.750772)
		(stroke
			(width 0.2032)
			(type default)
		)
		(layer "In1.Cu")
	)
	(gr_line
		(start 413.383222 -26.725372)
		(end 413.383222 -26.750772)
		(stroke
			(width 0.2032)
			(type default)
		)
		(layer "In1.Cu")
	)
	(gr_line
		(start 413.389572 -29.083)
		(end 413.389572 -27.7368)
		(stroke
			(width 0.508)
			(type default)
		)
		(layer "In1.Cu")
	)
	(gr_line
		(start 413.434022 -26.674572)
		(end 414.373822 -26.674572)
		(stroke
			(width 0.2032)
			(type default)
		)
		(layer "In1.Cu")
	)
	(gr_line
		(start 413.434022 -25.099772)
		(end 413.434022 -26.674572)
		(stroke
			(width 0.2032)
			(type default)
		)
		(layer "In1.Cu")
	)
	(gr_line
		(start 413.440372 -29.083)
		(end 413.440372 -27.7368)
		(stroke
			(width 0.508)
			(type default)
		)
		(layer "In1.Cu")
	)
	(gr_line
		(start 413.465772 -29.083)
		(end 413.465772 -27.7368)
		(stroke
			(width 0.508)
			(type default)
		)
		(layer "In1.Cu")
	)
	(gr_line
		(start 413.491172 -29.083)
		(end 413.491172 -27.7368)
		(stroke
			(width 0.508)
			(type default)
		)
		(layer "In1.Cu")
	)
	(gr_line
		(start 413.510222 -26.598372)
		(end 413.510222 -25.252172)
		(stroke
			(width 0.508)
			(type default)
		)
		(layer "In1.Cu")
	)
	(gr_line
		(start 413.516572 -29.083)
		(end 413.516572 -27.7368)
		(stroke
			(width 0.508)
			(type default)
		)
		(layer "In1.Cu")
	)
	(gr_line
		(start 413.535622 -26.598372)
		(end 414.196022 -26.598372)
		(stroke
			(width 0.508)
			(type default)
		)
		(layer "In1.Cu")
	)
	(gr_line
		(start 413.535622 -26.572972)
		(end 413.535622 -25.226772)
		(stroke
			(width 0.508)
			(type default)
		)
		(layer "In1.Cu")
	)
	(gr_line
		(start 413.535622 -25.201372)
		(end 414.170622 -25.201372)
		(stroke
			(width 0.508)
			(type default)
		)
		(layer "In1.Cu")
	)
	(gr_line
		(start 413.541972 -29.1084)
		(end 413.541972 -27.7622)
		(stroke
			(width 0.508)
			(type default)
		)
		(layer "In1.Cu")
	)
	(gr_line
		(start 413.561022 -26.572972)
		(end 413.561022 -25.226772)
		(stroke
			(width 0.508)
			(type default)
		)
		(layer "In1.Cu")
	)
	(gr_line
		(start 413.567372 -29.1084)
		(end 413.567372 -27.7622)
		(stroke
			(width 0.508)
			(type default)
		)
		(layer "In1.Cu")
	)
	(gr_line
		(start 413.567372 -29.083)
		(end 413.567372 -27.7368)
		(stroke
			(width 0.508)
			(type default)
		)
		(layer "In1.Cu")
	)
	(gr_line
		(start 413.586422 -26.572972)
		(end 413.586422 -25.226772)
		(stroke
			(width 0.508)
			(type default)
		)
		(layer "In1.Cu")
	)
	(gr_line
		(start 413.592772 -29.083)
		(end 413.592772 -27.7368)
		(stroke
			(width 0.508)
			(type default)
		)
		(layer "In1.Cu")
	)
	(gr_line
		(start 413.618172 -29.083)
		(end 413.618172 -27.7368)
		(stroke
			(width 0.508)
			(type default)
		)
		(layer "In1.Cu")
	)
	(gr_line
		(start 413.637222 -26.598372)
		(end 413.637222 -25.252172)
		(stroke
			(width 0.508)
			(type default)
		)
		(layer "In1.Cu")
	)
	(gr_line
		(start 413.637222 -26.572972)
		(end 413.637222 -25.226772)
		(stroke
			(width 0.508)
			(type default)
		)
		(layer "In1.Cu")
	)
	(gr_line
		(start 413.643572 -29.083)
		(end 413.643572 -27.7368)
		(stroke
			(width 0.508)
			(type default)
		)
		(layer "In1.Cu")
	)
	(gr_line
		(start 413.668972 -29.1084)
		(end 413.668972 -27.7622)
		(stroke
			(width 0.508)
			(type default)
		)
		(layer "In1.Cu")
	)
	(gr_line
		(start 413.668972 -29.083)
		(end 413.668972 -27.7368)
		(stroke
			(width 0.508)
			(type default)
		)
		(layer "In1.Cu")
	)
	(gr_line
		(start 413.688022 -26.572972)
		(end 413.688022 -25.226772)
		(stroke
			(width 0.508)
			(type default)
		)
		(layer "In1.Cu")
	)
	(gr_line
		(start 413.694372 -29.1084)
		(end 413.694372 -27.7622)
		(stroke
			(width 0.508)
			(type default)
		)
		(layer "In1.Cu")
	)
	(gr_line
		(start 413.694372 -29.083)
		(end 413.694372 -27.7368)
		(stroke
			(width 0.508)
			(type default)
		)
		(layer "In1.Cu")
	)
	(gr_line
		(start 413.713422 -26.547572)
		(end 413.713422 -25.201372)
		(stroke
			(width 0.508)
			(type default)
		)
		(layer "In1.Cu")
	)
	(gr_line
		(start 413.719772 -29.1084)
		(end 413.719772 -27.7622)
		(stroke
			(width 0.508)
			(type default)
		)
		(layer "In1.Cu")
	)
	(gr_line
		(start 413.738822 -26.572972)
		(end 413.738822 -25.226772)
		(stroke
			(width 0.508)
			(type default)
		)
		(layer "In1.Cu")
	)
	(gr_line
		(start 413.745172 -29.337)
		(end 414.075372 -29.337)
		(stroke
			(width 0.1016)
			(type default)
		)
		(layer "In1.Cu")
	)
	(gr_line
		(start 413.745172 -29.083)
		(end 413.745172 -27.7368)
		(stroke
			(width 0.508)
			(type default)
		)
		(layer "In1.Cu")
	)
	(gr_line
		(start 413.764222 -26.572972)
		(end 413.764222 -25.226772)
		(stroke
			(width 0.508)
			(type default)
		)
		(layer "In1.Cu")
	)
	(gr_line
		(start 413.770572 -29.1084)
		(end 413.770572 -27.7622)
		(stroke
			(width 0.508)
			(type default)
		)
		(layer "In1.Cu")
	)
	(gr_line
		(start 413.770572 -29.083)
		(end 413.770572 -27.7368)
		(stroke
			(width 0.508)
			(type default)
		)
		(layer "In1.Cu")
	)
	(gr_line
		(start 413.789622 -26.572972)
		(end 413.789622 -25.226772)
		(stroke
			(width 0.508)
			(type default)
		)
		(layer "In1.Cu")
	)
	(gr_line
		(start 413.795972 -29.1084)
		(end 413.795972 -27.7622)
		(stroke
			(width 0.508)
			(type default)
		)
		(layer "In1.Cu")
	)
	(gr_line
		(start 413.840422 -26.572972)
		(end 413.840422 -25.226772)
		(stroke
			(width 0.508)
			(type default)
		)
		(layer "In1.Cu")
	)
	(gr_line
		(start 413.865822 -26.572972)
		(end 413.865822 -25.226772)
		(stroke
			(width 0.508)
			(type default)
		)
		(layer "In1.Cu")
	)
	(gr_line
		(start 413.872172 -29.1084)
		(end 413.872172 -27.7622)
		(stroke
			(width 0.508)
			(type default)
		)
		(layer "In1.Cu")
	)
	(gr_line
		(start 413.891222 -26.572972)
		(end 413.891222 -25.226772)
		(stroke
			(width 0.508)
			(type default)
		)
		(layer "In1.Cu")
	)
	(gr_line
		(start 413.916622 -26.572972)
		(end 413.916622 -25.226772)
		(stroke
			(width 0.508)
			(type default)
		)
		(layer "In1.Cu")
	)
	(gr_line
		(start 413.942022 -26.598372)
		(end 413.942022 -25.252172)
		(stroke
			(width 0.508)
			(type default)
		)
		(layer "In1.Cu")
	)
	(gr_line
		(start 413.967422 -26.598372)
		(end 413.967422 -25.252172)
		(stroke
			(width 0.508)
			(type default)
		)
		(layer "In1.Cu")
	)
	(gr_line
		(start 413.967422 -26.572972)
		(end 413.967422 -25.226772)
		(stroke
			(width 0.508)
			(type default)
		)
		(layer "In1.Cu")
	)
	(gr_line
		(start 413.973772 -29.2608)
		(end 413.973772 -27.6098)
		(stroke
			(width 0.2032)
			(type default)
		)
		(layer "In1.Cu")
	)
	(gr_line
		(start 413.973772 -29.2354)
		(end 412.957772 -29.2354)
		(stroke
			(width 0.2032)
			(type default)
		)
		(layer "In1.Cu")
	)
	(gr_line
		(start 413.973772 -29.1846)
		(end 413.973772 -29.2354)
		(stroke
			(width 0.2032)
			(type default)
		)
		(layer "In1.Cu")
	)
	(gr_line
		(start 413.973772 -27.6098)
		(end 413.033972 -27.6098)
		(stroke
			(width 0.2032)
			(type default)
		)
		(layer "In1.Cu")
	)
	(gr_line
		(start 413.992822 -26.572972)
		(end 413.992822 -25.226772)
		(stroke
			(width 0.508)
			(type default)
		)
		(layer "In1.Cu")
	)
	(gr_line
		(start 414.018222 -26.572972)
		(end 414.018222 -25.226772)
		(stroke
			(width 0.508)
			(type default)
		)
		(layer "In1.Cu")
	)
	(gr_line
		(start 414.024572 -29.2354)
		(end 412.983172 -29.2354)
		(stroke
			(width 0.2032)
			(type default)
		)
		(layer "In1.Cu")
	)
	(gr_line
		(start 414.024572 -27.559)
		(end 414.024572 -29.2354)
		(stroke
			(width 0.2032)
			(type default)
		)
		(layer "In1.Cu")
	)
	(gr_line
		(start 414.043622 -26.572972)
		(end 414.043622 -25.226772)
		(stroke
			(width 0.508)
			(type default)
		)
		(layer "In1.Cu")
	)
	(gr_line
		(start 414.069022 -26.598372)
		(end 414.069022 -25.252172)
		(stroke
			(width 0.508)
			(type default)
		)
		(layer "In1.Cu")
	)
	(gr_line
		(start 414.069022 -26.572972)
		(end 414.069022 -25.226772)
		(stroke
			(width 0.508)
			(type default)
		)
		(layer "In1.Cu")
	)
	(gr_line
		(start 414.075372 -29.337)
		(end 414.075372 -27.4828)
		(stroke
			(width 0.1016)
			(type default)
		)
		(layer "In1.Cu")
	)
	(gr_line
		(start 414.075372 -27.4828)
		(end 412.906972 -27.4828)
		(stroke
			(width 0.1016)
			(type default)
		)
		(layer "In1.Cu")
	)
	(gr_line
		(start 414.094422 -26.598372)
		(end 414.094422 -25.252172)
		(stroke
			(width 0.508)
			(type default)
		)
		(layer "In1.Cu")
	)
	(gr_line
		(start 414.094422 -26.572972)
		(end 414.094422 -25.226772)
		(stroke
			(width 0.508)
			(type default)
		)
		(layer "In1.Cu")
	)
	(gr_line
		(start 414.119822 -26.598372)
		(end 414.119822 -25.252172)
		(stroke
			(width 0.508)
			(type default)
		)
		(layer "In1.Cu")
	)
	(gr_line
		(start 414.145222 -26.826972)
		(end 414.475422 -26.826972)
		(stroke
			(width 0.1016)
			(type default)
		)
		(layer "In1.Cu")
	)
	(gr_line
		(start 414.145222 -26.572972)
		(end 414.145222 -25.226772)
		(stroke
			(width 0.508)
			(type default)
		)
		(layer "In1.Cu")
	)
	(gr_line
		(start 414.170622 -26.598372)
		(end 414.170622 -25.252172)
		(stroke
			(width 0.508)
			(type default)
		)
		(layer "In1.Cu")
	)
	(gr_line
		(start 414.170622 -26.572972)
		(end 414.170622 -25.226772)
		(stroke
			(width 0.508)
			(type default)
		)
		(layer "In1.Cu")
	)
	(gr_line
		(start 414.196022 -26.598372)
		(end 414.196022 -25.252172)
		(stroke
			(width 0.508)
			(type default)
		)
		(layer "In1.Cu")
	)
	(gr_line
		(start 414.272222 -26.598372)
		(end 414.272222 -25.252172)
		(stroke
			(width 0.508)
			(type default)
		)
		(layer "In1.Cu")
	)
	(gr_line
		(start 414.373822 -26.750772)
		(end 414.373822 -25.099772)
		(stroke
			(width 0.2032)
			(type default)
		)
		(layer "In1.Cu")
	)
	(gr_line
		(start 414.373822 -26.725372)
		(end 413.357822 -26.725372)
		(stroke
			(width 0.2032)
			(type default)
		)
		(layer "In1.Cu")
	)
	(gr_line
		(start 414.373822 -26.674572)
		(end 414.373822 -26.725372)
		(stroke
			(width 0.2032)
			(type default)
		)
		(layer "In1.Cu")
	)
	(gr_line
		(start 414.373822 -25.099772)
		(end 413.434022 -25.099772)
		(stroke
			(width 0.2032)
			(type default)
		)
		(layer "In1.Cu")
	)
	(gr_line
		(start 414.424622 -26.725372)
		(end 413.383222 -26.725372)
		(stroke
			(width 0.2032)
			(type default)
		)
		(layer "In1.Cu")
	)
	(gr_line
		(start 414.424622 -25.048972)
		(end 414.424622 -26.725372)
		(stroke
			(width 0.2032)
			(type default)
		)
		(layer "In1.Cu")
	)
	(gr_line
		(start 414.475422 -26.826972)
		(end 414.475422 -24.972772)
		(stroke
			(width 0.1016)
			(type default)
		)
		(layer "In1.Cu")
	)
	(gr_line
		(start 414.475422 -24.972772)
		(end 413.307022 -24.972772)
		(stroke
			(width 0.1016)
			(type default)
		)
		(layer "In1.Cu")
	)
	(gr_line
		(start 415.259774 -30.56382)
		(end 416.529774 -30.56382)
		(stroke
			(width 0.7874)
			(type default)
		)
		(layer "In1.Cu")
	)
	(gr_line
		(start 415.307018 -29.337)
		(end 416.145218 -29.337)
		(stroke
			(width 0.1016)
			(type default)
		)
		(layer "In1.Cu")
	)
	(gr_line
		(start 415.307018 -27.4828)
		(end 415.307018 -29.337)
		(stroke
			(width 0.1016)
			(type default)
		)
		(layer "In1.Cu")
	)
	(gr_line
		(start 415.357818 -29.2354)
		(end 415.357818 -27.559)
		(stroke
			(width 0.2032)
			(type default)
		)
		(layer "In1.Cu")
	)
	(gr_line
		(start 415.357818 -27.559)
		(end 416.424618 -27.559)
		(stroke
			(width 0.2032)
			(type default)
		)
		(layer "In1.Cu")
	)
	(gr_line
		(start 415.383218 -29.2608)
		(end 416.373818 -29.2608)
		(stroke
			(width 0.2032)
			(type default)
		)
		(layer "In1.Cu")
	)
	(gr_line
		(start 415.383218 -29.2354)
		(end 415.383218 -29.2608)
		(stroke
			(width 0.2032)
			(type default)
		)
		(layer "In1.Cu")
	)
	(gr_line
		(start 415.434018 -29.1846)
		(end 416.373818 -29.1846)
		(stroke
			(width 0.2032)
			(type default)
		)
		(layer "In1.Cu")
	)
	(gr_line
		(start 415.434018 -27.6098)
		(end 415.434018 -29.1846)
		(stroke
			(width 0.2032)
			(type default)
		)
		(layer "In1.Cu")
	)
	(gr_line
		(start 415.510218 -29.1084)
		(end 415.510218 -27.7622)
		(stroke
			(width 0.508)
			(type default)
		)
		(layer "In1.Cu")
	)
	(gr_line
		(start 415.535618 -29.1084)
		(end 416.196018 -29.1084)
		(stroke
			(width 0.508)
			(type default)
		)
		(layer "In1.Cu")
	)
	(gr_line
		(start 415.535618 -29.083)
		(end 415.535618 -27.7368)
		(stroke
			(width 0.508)
			(type default)
		)
		(layer "In1.Cu")
	)
	(gr_line
		(start 415.535618 -27.7114)
		(end 416.170618 -27.7114)
		(stroke
			(width 0.508)
			(type default)
		)
		(layer "In1.Cu")
	)
	(gr_line
		(start 415.561018 -29.083)
		(end 415.561018 -27.7368)
		(stroke
			(width 0.508)
			(type default)
		)
		(layer "In1.Cu")
	)
	(gr_line
		(start 415.586418 -29.083)
		(end 415.586418 -27.7368)
		(stroke
			(width 0.508)
			(type default)
		)
		(layer "In1.Cu")
	)
	(gr_line
		(start 415.637218 -29.1084)
		(end 415.637218 -27.7622)
		(stroke
			(width 0.508)
			(type default)
		)
		(layer "In1.Cu")
	)
	(gr_line
		(start 415.637218 -29.083)
		(end 415.637218 -27.7368)
		(stroke
			(width 0.508)
			(type default)
		)
		(layer "In1.Cu")
	)
	(gr_line
		(start 415.688018 -29.083)
		(end 415.688018 -27.7368)
		(stroke
			(width 0.508)
			(type default)
		)
		(layer "In1.Cu")
	)
	(gr_line
		(start 415.707068 -26.826972)
		(end 416.545268 -26.826972)
		(stroke
			(width 0.1016)
			(type default)
		)
		(layer "In1.Cu")
	)
	(gr_line
		(start 415.707068 -24.972772)
		(end 415.707068 -26.826972)
		(stroke
			(width 0.1016)
			(type default)
		)
		(layer "In1.Cu")
	)
	(gr_line
		(start 415.713418 -29.0576)
		(end 415.713418 -27.7114)
		(stroke
			(width 0.508)
			(type default)
		)
		(layer "In1.Cu")
	)
	(gr_line
		(start 415.738818 -29.083)
		(end 415.738818 -27.7368)
		(stroke
			(width 0.508)
			(type default)
		)
		(layer "In1.Cu")
	)
	(gr_line
		(start 415.757868 -26.725372)
		(end 415.757868 -25.048972)
		(stroke
			(width 0.2032)
			(type default)
		)
		(layer "In1.Cu")
	)
	(gr_line
		(start 415.757868 -25.048972)
		(end 416.824668 -25.048972)
		(stroke
			(width 0.2032)
			(type default)
		)
		(layer "In1.Cu")
	)
	(gr_line
		(start 415.764218 -29.083)
		(end 415.764218 -27.7368)
		(stroke
			(width 0.508)
			(type default)
		)
		(layer "In1.Cu")
	)
	(gr_line
		(start 415.783268 -26.750772)
		(end 416.773868 -26.750772)
		(stroke
			(width 0.2032)
			(type default)
		)
		(layer "In1.Cu")
	)
	(gr_line
		(start 415.783268 -26.725372)
		(end 415.783268 -26.750772)
		(stroke
			(width 0.2032)
			(type default)
		)
		(layer "In1.Cu")
	)
	(gr_line
		(start 415.789618 -29.083)
		(end 415.789618 -27.7368)
		(stroke
			(width 0.508)
			(type default)
		)
		(layer "In1.Cu")
	)
	(gr_line
		(start 415.834068 -26.674572)
		(end 416.773868 -26.674572)
		(stroke
			(width 0.2032)
			(type default)
		)
		(layer "In1.Cu")
	)
	(gr_line
		(start 415.834068 -25.099772)
		(end 415.834068 -26.674572)
		(stroke
			(width 0.2032)
			(type default)
		)
		(layer "In1.Cu")
	)
	(gr_line
		(start 415.840418 -29.083)
		(end 415.840418 -27.7368)
		(stroke
			(width 0.508)
			(type default)
		)
		(layer "In1.Cu")
	)
	(gr_line
		(start 415.865818 -29.083)
		(end 415.865818 -27.7368)
		(stroke
			(width 0.508)
			(type default)
		)
		(layer "In1.Cu")
	)
	(gr_line
		(start 415.891218 -29.083)
		(end 415.891218 -27.7368)
		(stroke
			(width 0.508)
			(type default)
		)
		(layer "In1.Cu")
	)
	(gr_line
		(start 415.910268 -26.598372)
		(end 415.910268 -25.252172)
		(stroke
			(width 0.508)
			(type default)
		)
		(layer "In1.Cu")
	)
	(gr_line
		(start 415.916618 -29.083)
		(end 415.916618 -27.7368)
		(stroke
			(width 0.508)
			(type default)
		)
		(layer "In1.Cu")
	)
	(gr_line
		(start 415.935668 -26.598372)
		(end 416.596068 -26.598372)
		(stroke
			(width 0.508)
			(type default)
		)
		(layer "In1.Cu")
	)
	(gr_line
		(start 415.935668 -26.572972)
		(end 415.935668 -25.226772)
		(stroke
			(width 0.508)
			(type default)
		)
		(layer "In1.Cu")
	)
	(gr_line
		(start 415.935668 -25.201372)
		(end 416.570668 -25.201372)
		(stroke
			(width 0.508)
			(type default)
		)
		(layer "In1.Cu")
	)
	(gr_line
		(start 415.942018 -29.1084)
		(end 415.942018 -27.7622)
		(stroke
			(width 0.508)
			(type default)
		)
		(layer "In1.Cu")
	)
	(gr_line
		(start 415.961068 -26.572972)
		(end 415.961068 -25.226772)
		(stroke
			(width 0.508)
			(type default)
		)
		(layer "In1.Cu")
	)
	(gr_line
		(start 415.967418 -29.1084)
		(end 415.967418 -27.7622)
		(stroke
			(width 0.508)
			(type default)
		)
		(layer "In1.Cu")
	)
	(gr_line
		(start 415.967418 -29.083)
		(end 415.967418 -27.7368)
		(stroke
			(width 0.508)
			(type default)
		)
		(layer "In1.Cu")
	)
	(gr_line
		(start 415.986468 -26.572972)
		(end 415.986468 -25.226772)
		(stroke
			(width 0.508)
			(type default)
		)
		(layer "In1.Cu")
	)
	(gr_line
		(start 415.992818 -29.083)
		(end 415.992818 -27.7368)
		(stroke
			(width 0.508)
			(type default)
		)
		(layer "In1.Cu")
	)
	(gr_line
		(start 416.018218 -29.083)
		(end 416.018218 -27.7368)
		(stroke
			(width 0.508)
			(type default)
		)
		(layer "In1.Cu")
	)
	(gr_line
		(start 416.037268 -26.598372)
		(end 416.037268 -25.252172)
		(stroke
			(width 0.508)
			(type default)
		)
		(layer "In1.Cu")
	)
	(gr_line
		(start 416.037268 -26.572972)
		(end 416.037268 -25.226772)
		(stroke
			(width 0.508)
			(type default)
		)
		(layer "In1.Cu")
	)
	(gr_line
		(start 416.043618 -29.083)
		(end 416.043618 -27.7368)
		(stroke
			(width 0.508)
			(type default)
		)
		(layer "In1.Cu")
	)
	(gr_line
		(start 416.069018 -29.1084)
		(end 416.069018 -27.7622)
		(stroke
			(width 0.508)
			(type default)
		)
		(layer "In1.Cu")
	)
	(gr_line
		(start 416.069018 -29.083)
		(end 416.069018 -27.7368)
		(stroke
			(width 0.508)
			(type default)
		)
		(layer "In1.Cu")
	)
	(gr_line
		(start 416.088068 -26.572972)
		(end 416.088068 -25.226772)
		(stroke
			(width 0.508)
			(type default)
		)
		(layer "In1.Cu")
	)
	(gr_line
		(start 416.094418 -29.1084)
		(end 416.094418 -27.7622)
		(stroke
			(width 0.508)
			(type default)
		)
		(layer "In1.Cu")
	)
	(gr_line
		(start 416.094418 -29.083)
		(end 416.094418 -27.7368)
		(stroke
			(width 0.508)
			(type default)
		)
		(layer "In1.Cu")
	)
	(gr_line
		(start 416.113468 -26.547572)
		(end 416.113468 -25.201372)
		(stroke
			(width 0.508)
			(type default)
		)
		(layer "In1.Cu")
	)
	(gr_line
		(start 416.119818 -29.1084)
		(end 416.119818 -27.7622)
		(stroke
			(width 0.508)
			(type default)
		)
		(layer "In1.Cu")
	)
	(gr_line
		(start 416.138868 -26.572972)
		(end 416.138868 -25.226772)
		(stroke
			(width 0.508)
			(type default)
		)
		(layer "In1.Cu")
	)
	(gr_line
		(start 416.145218 -29.337)
		(end 416.475418 -29.337)
		(stroke
			(width 0.1016)
			(type default)
		)
		(layer "In1.Cu")
	)
	(gr_line
		(start 416.145218 -29.083)
		(end 416.145218 -27.7368)
		(stroke
			(width 0.508)
			(type default)
		)
		(layer "In1.Cu")
	)
	(gr_line
		(start 416.164268 -26.572972)
		(end 416.164268 -25.226772)
		(stroke
			(width 0.508)
			(type default)
		)
		(layer "In1.Cu")
	)
	(gr_line
		(start 416.170618 -29.1084)
		(end 416.170618 -27.7622)
		(stroke
			(width 0.508)
			(type default)
		)
		(layer "In1.Cu")
	)
	(gr_line
		(start 416.170618 -29.083)
		(end 416.170618 -27.7368)
		(stroke
			(width 0.508)
			(type default)
		)
		(layer "In1.Cu")
	)
	(gr_line
		(start 416.189668 -26.572972)
		(end 416.189668 -25.226772)
		(stroke
			(width 0.508)
			(type default)
		)
		(layer "In1.Cu")
	)
	(gr_line
		(start 416.196018 -29.1084)
		(end 416.196018 -27.7622)
		(stroke
			(width 0.508)
			(type default)
		)
		(layer "In1.Cu")
	)
	(gr_line
		(start 416.240468 -26.572972)
		(end 416.240468 -25.226772)
		(stroke
			(width 0.508)
			(type default)
		)
		(layer "In1.Cu")
	)
	(gr_line
		(start 416.265868 -26.572972)
		(end 416.265868 -25.226772)
		(stroke
			(width 0.508)
			(type default)
		)
		(layer "In1.Cu")
	)
	(gr_line
		(start 416.272218 -29.1084)
		(end 416.272218 -27.7622)
		(stroke
			(width 0.508)
			(type default)
		)
		(layer "In1.Cu")
	)
	(gr_line
		(start 416.291268 -26.572972)
		(end 416.291268 -25.226772)
		(stroke
			(width 0.508)
			(type default)
		)
		(layer "In1.Cu")
	)
	(gr_line
		(start 416.316668 -26.572972)
		(end 416.316668 -25.226772)
		(stroke
			(width 0.508)
			(type default)
		)
		(layer "In1.Cu")
	)
	(gr_line
		(start 416.342068 -26.598372)
		(end 416.342068 -25.252172)
		(stroke
			(width 0.508)
			(type default)
		)
		(layer "In1.Cu")
	)
	(gr_line
		(start 416.367468 -26.598372)
		(end 416.367468 -25.252172)
		(stroke
			(width 0.508)
			(type default)
		)
		(layer "In1.Cu")
	)
	(gr_line
		(start 416.367468 -26.572972)
		(end 416.367468 -25.226772)
		(stroke
			(width 0.508)
			(type default)
		)
		(layer "In1.Cu")
	)
	(gr_line
		(start 416.373818 -29.2608)
		(end 416.373818 -27.6098)
		(stroke
			(width 0.2032)
			(type default)
		)
		(layer "In1.Cu")
	)
	(gr_line
		(start 416.373818 -29.2354)
		(end 415.357818 -29.2354)
		(stroke
			(width 0.2032)
			(type default)
		)
		(layer "In1.Cu")
	)
	(gr_line
		(start 416.373818 -29.1846)
		(end 416.373818 -29.2354)
		(stroke
			(width 0.2032)
			(type default)
		)
		(layer "In1.Cu")
	)
	(gr_line
		(start 416.373818 -27.6098)
		(end 415.434018 -27.6098)
		(stroke
			(width 0.2032)
			(type default)
		)
		(layer "In1.Cu")
	)
	(gr_line
		(start 416.392868 -26.572972)
		(end 416.392868 -25.226772)
		(stroke
			(width 0.508)
			(type default)
		)
		(layer "In1.Cu")
	)
	(gr_line
		(start 416.418268 -26.572972)
		(end 416.418268 -25.226772)
		(stroke
			(width 0.508)
			(type default)
		)
		(layer "In1.Cu")
	)
	(gr_line
		(start 416.424618 -29.2354)
		(end 415.383218 -29.2354)
		(stroke
			(width 0.2032)
			(type default)
		)
		(layer "In1.Cu")
	)
	(gr_line
		(start 416.424618 -27.559)
		(end 416.424618 -29.2354)
		(stroke
			(width 0.2032)
			(type default)
		)
		(layer "In1.Cu")
	)
	(gr_line
		(start 416.443668 -26.572972)
		(end 416.443668 -25.226772)
		(stroke
			(width 0.508)
			(type default)
		)
		(layer "In1.Cu")
	)
	(gr_line
		(start 416.469068 -26.598372)
		(end 416.469068 -25.252172)
		(stroke
			(width 0.508)
			(type default)
		)
		(layer "In1.Cu")
	)
	(gr_line
		(start 416.469068 -26.572972)
		(end 416.469068 -25.226772)
		(stroke
			(width 0.508)
			(type default)
		)
		(layer "In1.Cu")
	)
	(gr_line
		(start 416.475418 -29.337)
		(end 416.475418 -27.4828)
		(stroke
			(width 0.1016)
			(type default)
		)
		(layer "In1.Cu")
	)
	(gr_line
		(start 416.475418 -27.4828)
		(end 415.307018 -27.4828)
		(stroke
			(width 0.1016)
			(type default)
		)
		(layer "In1.Cu")
	)
	(gr_line
		(start 416.494468 -26.598372)
		(end 416.494468 -25.252172)
		(stroke
			(width 0.508)
			(type default)
		)
		(layer "In1.Cu")
	)
	(gr_line
		(start 416.494468 -26.572972)
		(end 416.494468 -25.226772)
		(stroke
			(width 0.508)
			(type default)
		)
		(layer "In1.Cu")
	)
	(gr_line
		(start 416.519868 -26.598372)
		(end 416.519868 -25.252172)
		(stroke
			(width 0.508)
			(type default)
		)
		(layer "In1.Cu")
	)
	(gr_line
		(start 416.545268 -26.826972)
		(end 416.875468 -26.826972)
		(stroke
			(width 0.1016)
			(type default)
		)
		(layer "In1.Cu")
	)
	(gr_line
		(start 416.545268 -26.572972)
		(end 416.545268 -25.226772)
		(stroke
			(width 0.508)
			(type default)
		)
		(layer "In1.Cu")
	)
	(gr_line
		(start 416.570668 -26.598372)
		(end 416.570668 -25.252172)
		(stroke
			(width 0.508)
			(type default)
		)
		(layer "In1.Cu")
	)
	(gr_line
		(start 416.570668 -26.572972)
		(end 416.570668 -25.226772)
		(stroke
			(width 0.508)
			(type default)
		)
		(layer "In1.Cu")
	)
	(gr_line
		(start 416.596068 -26.598372)
		(end 416.596068 -25.252172)
		(stroke
			(width 0.508)
			(type default)
		)
		(layer "In1.Cu")
	)
	(gr_line
		(start 416.672268 -26.598372)
		(end 416.672268 -25.252172)
		(stroke
			(width 0.508)
			(type default)
		)
		(layer "In1.Cu")
	)
	(gr_line
		(start 416.773868 -26.750772)
		(end 416.773868 -25.099772)
		(stroke
			(width 0.2032)
			(type default)
		)
		(layer "In1.Cu")
	)
	(gr_line
		(start 416.773868 -26.725372)
		(end 415.757868 -26.725372)
		(stroke
			(width 0.2032)
			(type default)
		)
		(layer "In1.Cu")
	)
	(gr_line
		(start 416.773868 -26.674572)
		(end 416.773868 -26.725372)
		(stroke
			(width 0.2032)
			(type default)
		)
		(layer "In1.Cu")
	)
	(gr_line
		(start 416.773868 -25.099772)
		(end 415.834068 -25.099772)
		(stroke
			(width 0.2032)
			(type default)
		)
		(layer "In1.Cu")
	)
	(gr_line
		(start 416.824668 -26.725372)
		(end 415.783268 -26.725372)
		(stroke
			(width 0.2032)
			(type default)
		)
		(layer "In1.Cu")
	)
	(gr_line
		(start 416.824668 -25.048972)
		(end 416.824668 -26.725372)
		(stroke
			(width 0.2032)
			(type default)
		)
		(layer "In1.Cu")
	)
	(gr_line
		(start 416.875468 -26.826972)
		(end 416.875468 -24.972772)
		(stroke
			(width 0.1016)
			(type default)
		)
		(layer "In1.Cu")
	)
	(gr_line
		(start 416.875468 -24.972772)
		(end 415.707068 -24.972772)
		(stroke
			(width 0.1016)
			(type default)
		)
		(layer "In1.Cu")
	)
	(gr_line
		(start 418.662866 -24.67102)
		(end 418.662866 -23.40102)
		(stroke
			(width 0.7874)
			(type default)
		)
		(layer "In1.Cu")
	)
	(gr_arc
		(start 425.010072 -41.000172)
		(mid 425.156481 -41.353635)
		(end 425.509944 -41.500044)
		(stroke
			(width 1.016)
			(type default)
		)
		(layer "In1.Cu")
	)
	(gr_line
		(start 425.010072 -31.999936)
		(end 425.010072 -41.000172)
		(stroke
			(width 1.016)
			(type default)
		)
		(layer "In1.Cu")
	)
	(gr_line
		(start 425.509944 -41.500044)
		(end 427.110144 -41.500044)
		(stroke
			(width 1.016)
			(type default)
		)
		(layer "In1.Cu")
	)
	(gr_arc
		(start 425.509944 -31.500064)
		(mid 425.156481 -31.646473)
		(end 425.010072 -31.999936)
		(stroke
			(width 1.016)
			(type default)
		)
		(layer "In1.Cu")
	)
	(gr_line
		(start 425.61002 -50.390044)
		(end 381.990092 -50.390044)
		(stroke
			(width 1.016)
			(type default)
		)
		(layer "In1.Cu")
	)
	(gr_arc
		(start 425.61002 -50.390044)
		(mid 427.024235 -49.804255)
		(end 427.610016 -48.390048)
		(stroke
			(width 1.016)
			(type default)
		)
		(layer "In1.Cu")
	)
	(gr_line
		(start 427.10989 -31.500064)
		(end 425.509944 -31.500064)
		(stroke
			(width 1.016)
			(type default)
		)
		(layer "In1.Cu")
	)
	(gr_arc
		(start 427.10989 -31.500064)
		(mid 427.463552 -31.353586)
		(end 427.610016 -30.999938)
		(stroke
			(width 1.016)
			(type default)
		)
		(layer "In1.Cu")
	)
	(gr_arc
		(start 427.610016 -41.999916)
		(mid 427.463615 -41.646427)
		(end 427.110144 -41.500044)
		(stroke
			(width 1.016)
			(type default)
		)
		(layer "In1.Cu")
	)
	(gr_line
		(start 427.610016 -41.999916)
		(end 427.610016 -48.390048)
		(stroke
			(width 1.016)
			(type default)
		)
		(layer "In1.Cu")
	)
	(gr_line
		(start 427.610016 -10.999978)
		(end 427.610016 -30.999938)
		(stroke
			(width 1.016)
			(type default)
		)
		(layer "In1.Cu")
	)
	(gr_arc
		(start 428.109888 -10.500106)
		(mid 427.756425 -10.646515)
		(end 427.610016 -10.999978)
		(stroke
			(width 1.016)
			(type default)
		)
		(layer "In1.Cu")
	)
	(gr_line
		(start 428.309786 -10.500106)
		(end 428.109888 -10.500106)
		(stroke
			(width 1.016)
			(type default)
		)
		(layer "In1.Cu")
	)
	(gr_arc
		(start 428.309786 -10.500106)
		(mid 428.66343 -10.353626)
		(end 428.809912 -9.99998)
		(stroke
			(width 1.016)
			(type default)
		)
		(layer "In1.Cu")
	)
	(gr_arc
		(start 428.809912 -1.999996)
		(mid 428.224126 -0.585782)
		(end 426.809916 0)
		(stroke
			(width 1.016)
			(type default)
		)
		(layer "In1.Cu")
	)
	(gr_line
		(start 428.809912 -1.999996)
		(end 428.809912 -9.99998)
		(stroke
			(width 1.016)
			(type default)
		)
		(layer "In1.Cu")
	)
	(gr_poly
		(pts
			(xy 334.429862 -33.031938) (xy 334.44464 -32.975899) (xy 334.481027 -32.865853) (xy 334.525041 -32.758629)
			(xy 334.576464 -32.654755) (xy 334.635044 -32.554742) (xy 334.700492 -32.459083) (xy 334.772486 -32.368249)
			(xy 334.850672 -32.282685) (xy 334.934665 -32.202814) (xy 335.024052 -32.12903) (xy 335.118391 -32.061694)
			(xy 335.21722 -32.001138) (xy 335.320052 -31.947661) (xy 335.42638 -31.901525) (xy 335.535681 -31.862959)
			(xy 335.591404 -31.847028) (xy 335.623662 -31.838138) (xy 337.865212 -29.596588) (xy 337.865212 -27.263344)
			(xy 339.8774 -25.251156) (xy 339.8774 -22.6314) (xy 338.686648 -21.440648) (xy 338.642198 -21.435822)
			(xy 338.613728 -21.432193) (xy 338.558252 -21.417488) (xy 338.505605 -21.394638) (xy 338.456975 -21.36416)
			(xy 338.413459 -21.326741) (xy 338.37604 -21.283225) (xy 338.345562 -21.234595) (xy 338.322712 -21.181948)
			(xy 338.308007 -21.126472) (xy 338.304378 -21.098002) (xy 338.299552 -21.053552) (xy 338.2518 -21.0058)
			(xy 338.235441 -20.990142) (xy 338.198256 -20.964304) (xy 338.157082 -20.945466) (xy 338.113221 -20.934221)
			(xy 338.068061 -20.930927) (xy 338.023032 -20.935688) (xy 337.97956 -20.948353) (xy 337.93902 -20.968521)
			(xy 337.920584 -20.98167) (xy 337.898263 -20.997666) (xy 337.849949 -21.023769) (xy 337.798391 -21.042674)
			(xy 337.744656 -21.053991) (xy 337.689853 -21.057487) (xy 337.635115 -21.053089) (xy 337.581574 -21.040888)
			(xy 337.530335 -21.021135) (xy 337.482457 -20.994241) (xy 337.438931 -20.960759) (xy 337.400655 -20.921382)
			(xy 337.36842 -20.876924) (xy 337.342893 -20.828304) (xy 337.324601 -20.776526) (xy 337.313922 -20.72266)
			(xy 337.311077 -20.667819) (xy 337.316125 -20.613138) (xy 337.328961 -20.559745) (xy 337.34932 -20.508744)
			(xy 337.376781 -20.461189) (xy 337.410777 -20.418063) (xy 337.450605 -20.380257) (xy 337.495442 -20.348552)
			(xy 337.544362 -20.323604) (xy 337.596354 -20.305928) (xy 337.650343 -20.295889) (xy 337.67776 -20.294346)
			(xy 337.69934 -20.293047) (xy 337.74162 -20.284034) (xy 337.781765 -20.267995) (xy 337.818616 -20.245394)
			(xy 337.851112 -20.216883) (xy 337.878314 -20.183284) (xy 337.899438 -20.145567) (xy 337.913874 -20.104818)
			(xy 337.921206 -20.062215) (xy 337.9216 -20.0406) (xy 337.9216 -5.1816) (xy 334.9498 -2.2098) (xy 331.47 -2.2098)
			(xy 330.9366 -2.7432) (xy 330.9366 -7.634478) (xy 330.96346 -7.662514) (xy 331.012212 -7.722947)
			(xy 331.054884 -7.787817) (xy 331.091076 -7.856513) (xy 331.120446 -7.92839) (xy 331.14272 -8.002774)
			(xy 331.157687 -8.078964) (xy 331.165208 -8.156245) (xy 331.165211 -8.233892) (xy 331.157696 -8.311174)
			(xy 331.142735 -8.387365) (xy 331.120467 -8.46175) (xy 331.091102 -8.53363) (xy 331.054916 -8.602329)
			(xy 331.012249 -8.667202) (xy 330.963501 -8.727639) (xy 330.9366 -8.755634) (xy 330.9366 -9.6774)
			(xy 330.896048 -9.717952) (xy 333.851439 -9.717952) (xy 333.853195 -9.663212) (xy 333.86276 -9.609286)
			(xy 333.879936 -9.557281) (xy 333.904372 -9.508267) (xy 333.935565 -9.463249) (xy 333.972874 -9.423155)
			(xy 334.015532 -9.388807) (xy 334.062664 -9.360911) (xy 334.113299 -9.34004) (xy 334.166399 -9.326624)
			(xy 334.220871 -9.320937) (xy 334.248252 -9.321546) (xy 334.265298 -9.321673) (xy 334.298472 -9.313873)
			(xy 334.328404 -9.297582) (xy 334.352966 -9.273959) (xy 334.370409 -9.244683) (xy 334.379495 -9.211838)
			(xy 334.380078 -9.1948) (xy 334.380229 -9.18052) (xy 334.38239 -9.152043) (xy 334.384396 -9.137904)
			(xy 334.385666 -9.128506) (xy 334.385666 -9.119108) (xy 334.385198 -9.102451) (xy 334.376576 -9.070271)
			(xy 334.359917 -9.041421) (xy 334.336358 -9.017867) (xy 334.307504 -9.001214) (xy 334.275323 -8.992599)
			(xy 334.258666 -8.992108) (xy 334.231163 -8.991683) (xy 334.176725 -8.983791) (xy 334.123985 -8.968163)
			(xy 334.074037 -8.945121) (xy 334.027916 -8.915143) (xy 333.98658 -8.878853) (xy 333.950885 -8.837001)
			(xy 333.921571 -8.790456) (xy 333.899246 -8.740183) (xy 333.884375 -8.687225) (xy 333.877263 -8.632679)
			(xy 333.878061 -8.577678) (xy 333.886749 -8.523362) (xy 333.90315 -8.470857) (xy 333.926922 -8.421253)
			(xy 333.957572 -8.375577) (xy 333.994465 -8.334777) (xy 334.036836 -8.299699) (xy 334.083806 -8.271071)
			(xy 334.134401 -8.249486) (xy 334.187572 -8.235393) (xy 334.242215 -8.229082) (xy 334.297199 -8.230686)
			(xy 334.351381 -8.24017) (xy 334.40364 -8.257339) (xy 334.452891 -8.281836) (xy 334.498113 -8.313153)
			(xy 334.538367 -8.35064) (xy 334.57282 -8.393521) (xy 334.600756 -8.440906) (xy 334.621596 -8.491812)
			(xy 334.634909 -8.545183) (xy 334.638142 -8.5725) (xy 334.643222 -8.621268) (xy 334.715612 -8.6868)
			(xy 336.112866 -8.6868) (xy 336.128999 -8.686359) (xy 336.160236 -8.678279) (xy 336.18845 -8.662627)
			(xy 336.21184 -8.640401) (xy 336.228911 -8.613022) (xy 336.238573 -8.582238) (xy 336.239866 -8.56615)
			(xy 336.241725 -8.538567) (xy 336.252425 -8.48433) (xy 336.270841 -8.432206) (xy 336.296587 -8.383285)
			(xy 336.329125 -8.338592) (xy 336.367772 -8.299063) (xy 336.411719 -8.265525) (xy 336.460047 -8.238682)
			(xy 336.511743 -8.219094) (xy 336.565725 -8.207173) (xy 336.620862 -8.203168) (xy 336.676 -8.207162)
			(xy 336.729984 -8.219073) (xy 336.781684 -8.23865) (xy 336.830017 -8.265484) (xy 336.873971 -8.299012)
			(xy 336.912626 -8.338533) (xy 336.945172 -8.38322) (xy 336.970928 -8.432136) (xy 336.989355 -8.484257)
			(xy 337.000066 -8.538492) (xy 337.002837 -8.593705) (xy 336.997611 -8.648739) (xy 336.984497 -8.702444)
			(xy 336.963768 -8.753693) (xy 336.93586 -8.801414) (xy 336.901357 -8.844607) (xy 336.860982 -8.882369)
			(xy 336.815578 -8.913908) (xy 336.766099 -8.938564) (xy 336.739992 -8.947658) (xy 336.718396 -8.955313)
			(xy 336.678164 -8.977227) (xy 336.642509 -9.005995) (xy 336.612585 -9.040687) (xy 336.589362 -9.080178)
			(xy 336.57359 -9.123191) (xy 336.56578 -9.168334) (xy 336.565494 -9.191244) (xy 336.565494 -9.198356)
			(xy 336.565801 -9.221269) (xy 336.573584 -9.266421) (xy 336.589339 -9.309445) (xy 336.612556 -9.348945)
			(xy 336.64248 -9.383642) (xy 336.678142 -9.412408) (xy 336.718386 -9.434312) (xy 336.739992 -9.441942)
			(xy 336.765795 -9.450914) (xy 336.814728 -9.475199) (xy 336.859696 -9.506218) (xy 336.899778 -9.543334)
			(xy 336.934156 -9.585789) (xy 336.962125 -9.632714) (xy 336.983114 -9.683149) (xy 336.996693 -9.736063)
			(xy 337.002584 -9.790372) (xy 337.000667 -9.844967) (xy 336.99098 -9.898729) (xy 336.973724 -9.95056)
			(xy 336.949249 -9.999399) (xy 336.918057 -10.044246) (xy 336.880786 -10.084185) (xy 336.838199 -10.118398)
			(xy 336.791166 -10.146186) (xy 336.74065 -10.166979) (xy 336.687684 -10.180354) (xy 336.633352 -10.186035)
			(xy 336.578766 -10.183906) (xy 336.525041 -10.174013) (xy 336.473277 -10.156555) (xy 336.424533 -10.131892)
			(xy 336.379807 -10.100527) (xy 336.340012 -10.063102) (xy 336.305964 -10.020383) (xy 336.278358 -9.973243)
			(xy 336.25776 -9.922647) (xy 336.244591 -9.86963) (xy 336.24139 -9.8425) (xy 336.23631 -9.793732)
			(xy 336.16392 -9.7282) (xy 334.718406 -9.7282) (xy 334.702299 -9.728671) (xy 334.671113 -9.73674)
			(xy 334.642943 -9.752365) (xy 334.619586 -9.774549) (xy 334.602531 -9.801877) (xy 334.597248 -9.8171)
			(xy 334.588577 -9.84308) (xy 334.564868 -9.89245) (xy 334.534344 -9.937923) (xy 334.497632 -9.978565)
			(xy 334.455487 -10.013541) (xy 334.408773 -10.04213) (xy 334.358452 -10.063747) (xy 334.305556 -10.077947)
			(xy 334.251174 -10.084438) (xy 334.196423 -10.083087) (xy 334.142427 -10.073922) (xy 334.090297 -10.05713)
			(xy 334.041103 -10.033057) (xy 333.995857 -10.002198) (xy 333.955487 -9.965186) (xy 333.920824 -9.922783)
			(xy 333.892581 -9.875859) (xy 333.871336 -9.825379) (xy 333.857528 -9.772381) (xy 333.851439 -9.717952)
			(xy 330.896048 -9.717952) (xy 330.3524 -10.2616) (xy 330.3524 -11.4808) (xy 330.2508 -11.5824) (xy 330.2254 -11.5824)
			(xy 329.7174 -12.0904) (xy 329.7174 -12.7508) (xy 329.67295 -12.79525) (xy 331.893936 -12.79525)
			(xy 331.897917 -12.715486) (xy 331.90982 -12.636514) (xy 331.929527 -12.55912) (xy 331.956842 -12.484073)
			(xy 331.991493 -12.412118) (xy 332.033137 -12.343971) (xy 332.081359 -12.280309) (xy 332.13568 -12.221765)
			(xy 332.195561 -12.16892) (xy 332.260405 -12.1223) (xy 332.329569 -12.082368) (xy 332.402365 -12.049521)
			(xy 332.47807 -12.024086) (xy 332.555931 -12.006315) (xy 332.635175 -11.996384) (xy 332.715014 -11.994393)
			(xy 332.794654 -12.000361) (xy 332.873305 -12.014229) (xy 332.950184 -12.03586) (xy 333.024527 -12.065037)
			(xy 333.095595 -12.101472) (xy 333.162683 -12.144802) (xy 333.225122 -12.194596) (xy 333.282294 -12.25036)
			(xy 333.33363 -12.311539) (xy 333.378618 -12.377525) (xy 333.416814 -12.447663) (xy 333.447835 -12.521256)
			(xy 333.471376 -12.597571) (xy 333.4872 -12.675851) (xy 333.495152 -12.755318) (xy 333.49565 -12.79525)
			(xy 333.495152 -12.835182) (xy 333.4872 -12.914649) (xy 333.471376 -12.992929) (xy 333.447835 -13.069244)
			(xy 333.416814 -13.142837) (xy 333.378618 -13.212975) (xy 333.33363 -13.278961) (xy 333.282294 -13.34014)
			(xy 333.225122 -13.395904) (xy 333.162683 -13.445698) (xy 333.095595 -13.489028) (xy 333.024527 -13.525463)
			(xy 332.950184 -13.55464) (xy 332.873305 -13.576271) (xy 332.794654 -13.590139) (xy 332.715014 -13.596107)
			(xy 332.635175 -13.594116) (xy 332.555931 -13.584185) (xy 332.47807 -13.566414) (xy 332.402365 -13.540979)
			(xy 332.329569 -13.508132) (xy 332.260405 -13.4682) (xy 332.195561 -13.42158) (xy 332.13568 -13.368735)
			(xy 332.081359 -13.310191) (xy 332.033137 -13.246529) (xy 331.991493 -13.178382) (xy 331.956842 -13.106427)
			(xy 331.929527 -13.03138) (xy 331.90982 -12.953986) (xy 331.897917 -12.875014) (xy 331.893936 -12.79525)
			(xy 329.67295 -12.79525) (xy 329.311 -13.1572) (xy 329.311 -13.4366) (xy 329.0062 -13.7414) (xy 327.5838 -13.7414)
			(xy 327.567152 -13.741943) (xy 327.534989 -13.750561) (xy 327.506154 -13.767209) (xy 327.482609 -13.790754)
			(xy 327.465961 -13.819589) (xy 327.457343 -13.851752) (xy 327.4568 -13.8684) (xy 327.4568 -14.059916)
			(xy 329.480926 -14.059916) (xy 329.481436 -14.017565) (xy 329.489498 -13.933249) (xy 329.505539 -13.85008)
			(xy 329.529411 -13.768812) (xy 329.5609 -13.690182) (xy 329.59972 -13.6149) (xy 329.645519 -13.543649)
			(xy 329.697884 -13.477073) (xy 329.756339 -13.415776) (xy 329.820356 -13.360313) (xy 329.889354 -13.311185)
			(xy 329.96271 -13.268838) (xy 330.039758 -13.233655) (xy 330.119802 -13.205954) (xy 330.202116 -13.185987)
			(xy 330.285956 -13.173933) (xy 330.370561 -13.169903) (xy 330.455166 -13.173933) (xy 330.539006 -13.185987)
			(xy 330.62132 -13.205954) (xy 330.701364 -13.233655) (xy 330.778412 -13.268838) (xy 330.851768 -13.311185)
			(xy 330.920766 -13.360313) (xy 330.984783 -13.415776) (xy 331.043238 -13.477073) (xy 331.095603 -13.543649)
			(xy 331.141402 -13.6149) (xy 331.180222 -13.690182) (xy 331.211711 -13.768812) (xy 331.235583 -13.85008)
			(xy 331.251624 -13.933249) (xy 331.259686 -14.017565) (xy 331.260196 -14.059916) (xy 331.260196 -14.694916)
			(xy 331.259735 -14.737193) (xy 331.251932 -14.821386) (xy 331.236394 -14.904499) (xy 331.213253 -14.985825)
			(xy 331.182708 -15.064668) (xy 331.145018 -15.140357) (xy 331.100505 -15.212245) (xy 331.049549 -15.279719)
			(xy 331.03551 -15.295118) (xy 331.944737 -15.295118) (xy 331.948713 -15.217971) (xy 331.960601 -15.141641)
			(xy 331.980274 -15.066939) (xy 332.007524 -14.994655) (xy 332.042062 -14.925556) (xy 332.083522 -14.860375)
			(xy 332.131464 -14.799802) (xy 332.185379 -14.74448) (xy 332.244698 -14.694994) (xy 332.30879 -14.65187)
			(xy 332.376977 -14.615565) (xy 332.448535 -14.586463) (xy 332.522706 -14.564872) (xy 332.598704 -14.551023)
			(xy 332.675723 -14.545061) (xy 332.752947 -14.54705) (xy 332.829557 -14.556969) (xy 332.904742 -14.574712)
			(xy 332.977703 -14.600092) (xy 333.047668 -14.632839) (xy 333.113895 -14.672607) (xy 333.175683 -14.718973)
			(xy 333.232375 -14.771447) (xy 333.283371 -14.829471) (xy 333.328131 -14.892432) (xy 333.366181 -14.959661)
			(xy 333.397115 -15.030446) (xy 333.420608 -15.104037) (xy 333.43641 -15.179653) (xy 333.444353 -15.256493)
			(xy 333.44485 -15.295118) (xy 333.444353 -15.333743) (xy 333.43641 -15.410583) (xy 333.420608 -15.486199)
			(xy 333.397115 -15.55979) (xy 333.366181 -15.630575) (xy 333.328131 -15.697804) (xy 333.283371 -15.760765)
			(xy 333.232375 -15.818789) (xy 333.175683 -15.871263) (xy 333.113895 -15.917629) (xy 333.047668 -15.957397)
			(xy 332.977703 -15.990144) (xy 332.904742 -16.015524) (xy 332.829557 -16.033267) (xy 332.752947 -16.043186)
			(xy 332.675723 -16.045175) (xy 332.598704 -16.039213) (xy 332.522706 -16.025364) (xy 332.448535 -16.003773)
			(xy 332.376977 -15.974671) (xy 332.30879 -15.938366) (xy 332.244698 -15.895242) (xy 332.185379 -15.845756)
			(xy 332.131464 -15.790434) (xy 332.083522 -15.729861) (xy 332.042062 -15.66468) (xy 332.007524 -15.595581)
			(xy 331.980274 -15.523297) (xy 331.960601 -15.448595) (xy 331.948713 -15.372265) (xy 331.944737 -15.295118)
			(xy 331.03551 -15.295118) (xy 330.992584 -15.342204) (xy 330.930098 -15.399167) (xy 330.862622 -15.450121)
			(xy 330.790732 -15.494631) (xy 330.715042 -15.532319) (xy 330.636198 -15.562862) (xy 330.554872 -15.586)
			(xy 330.471758 -15.601536) (xy 330.387565 -15.609336) (xy 330.345288 -15.609824) (xy 330.302863 -15.609299)
			(xy 330.218422 -15.600981) (xy 330.135202 -15.584427) (xy 330.054006 -15.559796) (xy 329.975615 -15.527324)
			(xy 329.900784 -15.487326) (xy 329.830233 -15.440186) (xy 329.764643 -15.386357) (xy 329.704645 -15.32636)
			(xy 329.650817 -15.26077) (xy 329.603676 -15.19022) (xy 329.563677 -15.115389) (xy 329.531206 -15.036998)
			(xy 329.506574 -14.955802) (xy 329.490019 -14.872582) (xy 329.481701 -14.788141) (xy 329.48118 -14.745716)
			(xy 329.480926 -14.059916) (xy 327.4568 -14.059916) (xy 327.4568 -17.79524) (xy 331.893936 -17.79524)
			(xy 331.897917 -17.715476) (xy 331.90982 -17.636504) (xy 331.929527 -17.55911) (xy 331.956842 -17.484063)
			(xy 331.991493 -17.412108) (xy 332.033137 -17.343961) (xy 332.081359 -17.280299) (xy 332.13568 -17.221755)
			(xy 332.195561 -17.16891) (xy 332.260405 -17.12229) (xy 332.329569 -17.082358) (xy 332.402365 -17.049511)
			(xy 332.47807 -17.024076) (xy 332.555931 -17.006305) (xy 332.635175 -16.996374) (xy 332.715014 -16.994383)
			(xy 332.794654 -17.000351) (xy 332.873305 -17.014219) (xy 332.950184 -17.03585) (xy 333.024527 -17.065027)
			(xy 333.095595 -17.101462) (xy 333.162683 -17.144792) (xy 333.225122 -17.194586) (xy 333.282294 -17.25035)
			(xy 333.33363 -17.311529) (xy 333.378618 -17.377515) (xy 333.416814 -17.447653) (xy 333.447835 -17.521246)
			(xy 333.471376 -17.597561) (xy 333.4872 -17.675841) (xy 333.495152 -17.755308) (xy 333.49565 -17.79524)
			(xy 333.495152 -17.835172) (xy 333.4872 -17.914639) (xy 333.471376 -17.992919) (xy 333.447835 -18.069234)
			(xy 333.416814 -18.142827) (xy 333.378618 -18.212965) (xy 333.33363 -18.278951) (xy 333.282294 -18.34013)
			(xy 333.225122 -18.395894) (xy 333.162683 -18.445688) (xy 333.095595 -18.489018) (xy 333.024527 -18.525453)
			(xy 332.950184 -18.55463) (xy 332.873305 -18.576261) (xy 332.794654 -18.590129) (xy 332.715014 -18.596097)
			(xy 332.635175 -18.594106) (xy 332.555931 -18.584175) (xy 332.47807 -18.566404) (xy 332.402365 -18.540969)
			(xy 332.329569 -18.508122) (xy 332.260405 -18.46819) (xy 332.195561 -18.42157) (xy 332.13568 -18.368725)
			(xy 332.081359 -18.310181) (xy 332.033137 -18.246519) (xy 331.991493 -18.178372) (xy 331.956842 -18.106417)
			(xy 331.929527 -18.03137) (xy 331.90982 -17.953976) (xy 331.897917 -17.875004) (xy 331.893936 -17.79524)
			(xy 327.4568 -17.79524) (xy 327.4568 -19.48942) (xy 327.496678 -19.55165) (xy 327.53046 -19.567398)
			(xy 327.556023 -19.579814) (xy 327.603482 -19.611073) (xy 327.645789 -19.649015) (xy 327.682012 -19.692803)
			(xy 327.711353 -19.741472) (xy 327.733163 -19.793948) (xy 327.740518 -19.821398) (xy 327.746491 -19.843477)
			(xy 327.765262 -19.885181) (xy 327.791195 -19.922852) (xy 327.823451 -19.955273) (xy 327.860989 -19.981398)
			(xy 327.902597 -20.000381) (xy 327.946931 -20.011611) (xy 327.992559 -20.014725) (xy 328.038008 -20.009621)
			(xy 328.06005 -20.003516) (xy 328.085753 -19.996243) (xy 328.138549 -19.988124) (xy 328.191961 -19.987445)
			(xy 328.244946 -19.99422) (xy 328.296469 -20.008316) (xy 328.321162 -20.018502) (xy 328.342496 -20.027162)
			(xy 328.387363 -20.037482) (xy 328.433355 -20.039544) (xy 328.478965 -20.033279) (xy 328.522699 -20.018895)
			(xy 328.563122 -19.996861) (xy 328.598911 -19.967901) (xy 328.628892 -19.932963) (xy 328.640948 -19.913346)
			(xy 328.655185 -19.889968) (xy 328.689313 -19.847173) (xy 328.729208 -19.809695) (xy 328.77405 -19.778306)
			(xy 328.822919 -19.753648) (xy 328.87481 -19.736229) (xy 328.928659 -19.726407) (xy 328.983358 -19.724382)
			(xy 329.037786 -19.730197) (xy 329.090823 -19.743732) (xy 329.14138 -19.764709) (xy 329.18842 -19.792698)
			(xy 329.230977 -19.827123) (xy 329.268175 -19.867278) (xy 329.299252 -19.912338) (xy 329.323568 -19.961377)
			(xy 329.340625 -20.013389) (xy 329.350073 -20.067304) (xy 329.351716 -20.122016) (xy 329.345523 -20.176402)
			(xy 329.331618 -20.229343) (xy 329.310289 -20.279754) (xy 329.281974 -20.326598) (xy 329.247253 -20.368913)
			(xy 329.20684 -20.405831) (xy 329.161565 -20.436593) (xy 329.112358 -20.460567) (xy 329.060229 -20.477262)
			(xy 329.006249 -20.486334) (xy 328.951526 -20.487596) (xy 328.897186 -20.481024) (xy 328.844342 -20.466751)
			(xy 328.819002 -20.456398) (xy 328.797666 -20.447731) (xy 328.752794 -20.4374) (xy 328.706794 -20.435329)
			(xy 328.661175 -20.441585) (xy 328.617431 -20.455964) (xy 328.576997 -20.477995) (xy 328.541198 -20.506955)
			(xy 328.511207 -20.541895) (xy 328.499216 -20.561554) (xy 328.485161 -20.584624) (xy 328.451556 -20.626919)
			(xy 328.412321 -20.66405) (xy 328.368238 -20.695273) (xy 328.320191 -20.719964) (xy 328.269141 -20.737628)
			(xy 328.216109 -20.747913) (xy 328.162157 -20.750612) (xy 328.108363 -20.745671) (xy 328.055805 -20.73319)
			(xy 328.005534 -20.713417) (xy 327.958555 -20.68675) (xy 327.915809 -20.65372) (xy 327.878152 -20.61499)
			(xy 327.846336 -20.571333) (xy 327.820998 -20.523625) (xy 327.802645 -20.472818) (xy 327.791644 -20.41993)
			(xy 327.788216 -20.366019) (xy 327.789794 -20.33905) (xy 327.790509 -20.323079) (xy 327.78494 -20.29161)
			(xy 327.771724 -20.262512) (xy 327.75169 -20.237613) (xy 327.726096 -20.218474) (xy 327.696549 -20.206297)
			(xy 327.664902 -20.201847) (xy 327.633142 -20.205402) (xy 327.603262 -20.216739) (xy 327.589896 -20.225512)
			(xy 327.575742 -20.235254) (xy 327.545979 -20.252427) (xy 327.53046 -20.259802) (xy 327.51749 -20.266229)
			(xy 327.49464 -20.283988) (xy 327.476389 -20.306448) (xy 327.463682 -20.332449) (xy 327.457174 -20.360648)
			(xy 327.4568 -20.375118) (xy 327.4568 -20.9804) (xy 335.278982 -20.9804) (xy 335.283053 -20.924778)
			(xy 335.295179 -20.870341) (xy 335.315102 -20.81825) (xy 335.342398 -20.769615) (xy 335.376484 -20.725472)
			(xy 335.416633 -20.686763) (xy 335.461991 -20.654312) (xy 335.511591 -20.628811) (xy 335.564375 -20.610804)
			(xy 335.619218 -20.600674) (xy 335.674952 -20.598637) (xy 335.730389 -20.604737) (xy 335.784346 -20.618843)
			(xy 335.835675 -20.640655) (xy 335.883281 -20.669709) (xy 335.926149 -20.705384) (xy 335.963366 -20.746921)
			(xy 335.994139 -20.793434) (xy 336.017811 -20.843931) (xy 336.033879 -20.897338) (xy 336.041999 -20.952514)
			(xy 336.042508 -20.9804) (xy 336.041999 -21.008286) (xy 336.033879 -21.063462) (xy 336.017811 -21.116869)
			(xy 335.994139 -21.167366) (xy 335.963366 -21.213879) (xy 335.926149 -21.255416) (xy 335.883281 -21.291091)
			(xy 335.835675 -21.320145) (xy 335.784346 -21.341957) (xy 335.730389 -21.356063) (xy 335.674952 -21.362163)
			(xy 335.619218 -21.360126) (xy 335.564375 -21.349996) (xy 335.511591 -21.331989) (xy 335.461991 -21.306488)
			(xy 335.416633 -21.274037) (xy 335.376484 -21.235328) (xy 335.342398 -21.191185) (xy 335.315102 -21.14255)
			(xy 335.295179 -21.090459) (xy 335.283053 -21.036022) (xy 335.278982 -20.9804) (xy 327.4568 -20.9804)
			(xy 327.4568 -22.3774) (xy 327.338944 -22.495256) (xy 331.893936 -22.495256) (xy 331.897917 -22.415492)
			(xy 331.90982 -22.33652) (xy 331.929527 -22.259126) (xy 331.956842 -22.184079) (xy 331.991493 -22.112124)
			(xy 332.033137 -22.043977) (xy 332.081359 -21.980315) (xy 332.13568 -21.921771) (xy 332.195561 -21.868926)
			(xy 332.260405 -21.822306) (xy 332.329569 -21.782374) (xy 332.402365 -21.749527) (xy 332.47807 -21.724092)
			(xy 332.555931 -21.706321) (xy 332.635175 -21.69639) (xy 332.715014 -21.694399) (xy 332.794654 -21.700367)
			(xy 332.873305 -21.714235) (xy 332.950184 -21.735866) (xy 333.024527 -21.765043) (xy 333.095595 -21.801478)
			(xy 333.162683 -21.844808) (xy 333.225122 -21.894602) (xy 333.282294 -21.950366) (xy 333.33363 -22.011545)
			(xy 333.378618 -22.077531) (xy 333.416814 -22.147669) (xy 333.447835 -22.221262) (xy 333.471376 -22.297577)
			(xy 333.472108 -22.3012) (xy 335.532982 -22.3012) (xy 335.537053 -22.245578) (xy 335.549179 -22.191141)
			(xy 335.569102 -22.13905) (xy 335.596398 -22.090415) (xy 335.630484 -22.046272) (xy 335.670633 -22.007563)
			(xy 335.715991 -21.975112) (xy 335.765591 -21.949611) (xy 335.818375 -21.931604) (xy 335.873218 -21.921474)
			(xy 335.928952 -21.919437) (xy 335.984389 -21.925537) (xy 336.038346 -21.939643) (xy 336.089675 -21.961455)
			(xy 336.137281 -21.990509) (xy 336.180149 -22.026184) (xy 336.217366 -22.067721) (xy 336.248139 -22.114234)
			(xy 336.271811 -22.164731) (xy 336.287879 -22.218138) (xy 336.295999 -22.273314) (xy 336.296508 -22.3012)
			(xy 336.295999 -22.329086) (xy 336.287879 -22.384262) (xy 336.271811 -22.437669) (xy 336.248139 -22.488166)
			(xy 336.217366 -22.534679) (xy 336.180149 -22.576216) (xy 336.137281 -22.611891) (xy 336.089675 -22.640945)
			(xy 336.038346 -22.662757) (xy 335.984389 -22.676863) (xy 335.928952 -22.682963) (xy 335.873218 -22.680926)
			(xy 335.818375 -22.670796) (xy 335.765591 -22.652789) (xy 335.715991 -22.627288) (xy 335.670633 -22.594837)
			(xy 335.630484 -22.556128) (xy 335.596398 -22.511985) (xy 335.569102 -22.46335) (xy 335.549179 -22.411259)
			(xy 335.537053 -22.356822) (xy 335.532982 -22.3012) (xy 333.472108 -22.3012) (xy 333.4872 -22.375857)
			(xy 333.495152 -22.455324) (xy 333.49565 -22.495256) (xy 333.495152 -22.535188) (xy 333.4872 -22.614655)
			(xy 333.471376 -22.692935) (xy 333.447835 -22.76925) (xy 333.416814 -22.842843) (xy 333.378618 -22.912981)
			(xy 333.33363 -22.978967) (xy 333.282294 -23.040146) (xy 333.225122 -23.09591) (xy 333.162683 -23.145704)
			(xy 333.095595 -23.189034) (xy 333.024527 -23.225469) (xy 332.950184 -23.254646) (xy 332.873305 -23.276277)
			(xy 332.794654 -23.290145) (xy 332.715014 -23.296113) (xy 332.635175 -23.294122) (xy 332.555931 -23.284191)
			(xy 332.47807 -23.26642) (xy 332.402365 -23.240985) (xy 332.329569 -23.208138) (xy 332.260405 -23.168206)
			(xy 332.195561 -23.121586) (xy 332.13568 -23.068741) (xy 332.081359 -23.010197) (xy 332.033137 -22.946535)
			(xy 331.991493 -22.878388) (xy 331.956842 -22.806433) (xy 331.929527 -22.731386) (xy 331.90982 -22.653992)
			(xy 331.897917 -22.57502) (xy 331.893936 -22.495256) (xy 327.338944 -22.495256) (xy 326.263 -23.5712)
			(xy 335.253582 -23.5712) (xy 335.257653 -23.515578) (xy 335.269779 -23.461141) (xy 335.289702 -23.40905)
			(xy 335.316998 -23.360415) (xy 335.351084 -23.316272) (xy 335.391233 -23.277563) (xy 335.436591 -23.245112)
			(xy 335.486191 -23.219611) (xy 335.538975 -23.201604) (xy 335.593818 -23.191474) (xy 335.649552 -23.189437)
			(xy 335.704989 -23.195537) (xy 335.758946 -23.209643) (xy 335.810275 -23.231455) (xy 335.857881 -23.260509)
			(xy 335.900749 -23.296184) (xy 335.937966 -23.337721) (xy 335.968739 -23.384234) (xy 335.992411 -23.434731)
			(xy 336.008479 -23.488138) (xy 336.016599 -23.543314) (xy 336.017108 -23.5712) (xy 336.016599 -23.599086)
			(xy 336.008479 -23.654262) (xy 335.992411 -23.707669) (xy 335.968739 -23.758166) (xy 335.937966 -23.804679)
			(xy 335.900749 -23.846216) (xy 335.857881 -23.881891) (xy 335.810275 -23.910945) (xy 335.758946 -23.932757)
			(xy 335.704989 -23.946863) (xy 335.649552 -23.952963) (xy 335.593818 -23.950926) (xy 335.538975 -23.940796)
			(xy 335.486191 -23.922789) (xy 335.436591 -23.897288) (xy 335.391233 -23.864837) (xy 335.351084 -23.826128)
			(xy 335.316998 -23.781985) (xy 335.289702 -23.73335) (xy 335.269779 -23.681259) (xy 335.257653 -23.626822)
			(xy 335.253582 -23.5712) (xy 326.263 -23.5712) (xy 324.539102 -25.295098) (xy 326.11239 -25.295098)
			(xy 326.116356 -25.210567) (xy 326.128221 -25.12678) (xy 326.147879 -25.044471) (xy 326.175159 -24.964365)
			(xy 326.20982 -24.887166) (xy 326.251558 -24.813551) (xy 326.300005 -24.744168) (xy 326.354737 -24.679627)
			(xy 326.415273 -24.620495) (xy 326.481079 -24.567291) (xy 326.551579 -24.520483) (xy 326.626151 -24.480482)
			(xy 326.704142 -24.44764) (xy 326.784866 -24.422246) (xy 326.867613 -24.404523) (xy 326.951655 -24.394625)
			(xy 327.036256 -24.392642) (xy 327.12067 -24.398589) (xy 327.204157 -24.412414) (xy 327.285982 -24.433997)
			(xy 327.365426 -24.463147) (xy 327.441792 -24.499608) (xy 327.514408 -24.54306) (xy 327.582636 -24.593121)
			(xy 327.645876 -24.649351) (xy 327.703573 -24.711256) (xy 327.75522 -24.778292) (xy 327.800362 -24.849869)
			(xy 327.838604 -24.925359) (xy 327.869608 -25.004098) (xy 327.893103 -25.085395) (xy 327.908882 -25.168534)
			(xy 327.916806 -25.252786) (xy 327.917302 -25.295098) (xy 331.792338 -25.295098) (xy 331.796304 -25.210567)
			(xy 331.808169 -25.12678) (xy 331.827827 -25.044471) (xy 331.855107 -24.964365) (xy 331.889768 -24.887166)
			(xy 331.931506 -24.813551) (xy 331.979953 -24.744168) (xy 332.034685 -24.679627) (xy 332.095221 -24.620495)
			(xy 332.161027 -24.567291) (xy 332.231527 -24.520483) (xy 332.306099 -24.480482) (xy 332.38409 -24.44764)
			(xy 332.464814 -24.422246) (xy 332.547561 -24.404523) (xy 332.631603 -24.394625) (xy 332.716204 -24.392642)
			(xy 332.800618 -24.398589) (xy 332.884105 -24.412414) (xy 332.96593 -24.433997) (xy 333.045374 -24.463147)
			(xy 333.12174 -24.499608) (xy 333.194356 -24.54306) (xy 333.262584 -24.593121) (xy 333.325824 -24.649351)
			(xy 333.383521 -24.711256) (xy 333.435168 -24.778292) (xy 333.48031 -24.849869) (xy 333.518552 -24.925359)
			(xy 333.549556 -25.004098) (xy 333.573051 -25.085395) (xy 333.58883 -25.168534) (xy 333.59242 -25.206706)
			(xy 335.659982 -25.206706) (xy 335.664053 -25.151084) (xy 335.676179 -25.096647) (xy 335.696102 -25.044556)
			(xy 335.723398 -24.995921) (xy 335.757484 -24.951778) (xy 335.797633 -24.913069) (xy 335.842991 -24.880618)
			(xy 335.892591 -24.855117) (xy 335.945375 -24.83711) (xy 336.000218 -24.82698) (xy 336.055952 -24.824943)
			(xy 336.111389 -24.831043) (xy 336.165346 -24.845149) (xy 336.216675 -24.866961) (xy 336.264281 -24.896015)
			(xy 336.307149 -24.93169) (xy 336.344366 -24.973227) (xy 336.375139 -25.01974) (xy 336.398811 -25.070237)
			(xy 336.414879 -25.123644) (xy 336.422999 -25.17882) (xy 336.423508 -25.206706) (xy 336.422999 -25.234592)
			(xy 336.414879 -25.289768) (xy 336.398811 -25.343175) (xy 336.375139 -25.393672) (xy 336.344366 -25.440185)
			(xy 336.307149 -25.481722) (xy 336.264281 -25.517397) (xy 336.216675 -25.546451) (xy 336.165346 -25.568263)
			(xy 336.111389 -25.582369) (xy 336.055952 -25.588469) (xy 336.000218 -25.586432) (xy 335.945375 -25.576302)
			(xy 335.892591 -25.558295) (xy 335.842991 -25.532794) (xy 335.797633 -25.500343) (xy 335.757484 -25.461634)
			(xy 335.723398 -25.417491) (xy 335.696102 -25.368856) (xy 335.676179 -25.316765) (xy 335.664053 -25.262328)
			(xy 335.659982 -25.206706) (xy 333.59242 -25.206706) (xy 333.596754 -25.252786) (xy 333.59725 -25.295098)
			(xy 333.596754 -25.33741) (xy 333.58883 -25.421662) (xy 333.573051 -25.504801) (xy 333.549556 -25.586098)
			(xy 333.518552 -25.664837) (xy 333.48031 -25.740327) (xy 333.435168 -25.811904) (xy 333.383521 -25.87894)
			(xy 333.325824 -25.940845) (xy 333.262584 -25.997075) (xy 333.194356 -26.047136) (xy 333.12174 -26.090588)
			(xy 333.045374 -26.127049) (xy 332.96593 -26.156199) (xy 332.884105 -26.177782) (xy 332.800618 -26.191607)
			(xy 332.716204 -26.197554) (xy 332.631603 -26.195571) (xy 332.547561 -26.185673) (xy 332.464814 -26.16795)
			(xy 332.38409 -26.142556) (xy 332.306099 -26.109714) (xy 332.231527 -26.069713) (xy 332.161027 -26.022905)
			(xy 332.095221 -25.969701) (xy 332.034685 -25.910569) (xy 331.979953 -25.846028) (xy 331.931506 -25.776645)
			(xy 331.889768 -25.70303) (xy 331.855107 -25.625831) (xy 331.827827 -25.545725) (xy 331.808169 -25.463416)
			(xy 331.796304 -25.379629) (xy 331.792338 -25.295098) (xy 327.917302 -25.295098) (xy 327.916806 -25.33741)
			(xy 327.908882 -25.421662) (xy 327.893103 -25.504801) (xy 327.869608 -25.586098) (xy 327.838604 -25.664837)
			(xy 327.800362 -25.740327) (xy 327.75522 -25.811904) (xy 327.703573 -25.87894) (xy 327.645876 -25.940845)
			(xy 327.582636 -25.997075) (xy 327.514408 -26.047136) (xy 327.441792 -26.090588) (xy 327.365426 -26.127049)
			(xy 327.285982 -26.156199) (xy 327.204157 -26.177782) (xy 327.12067 -26.191607) (xy 327.036256 -26.197554)
			(xy 326.951655 -26.195571) (xy 326.867613 -26.185673) (xy 326.784866 -26.16795) (xy 326.704142 -26.142556)
			(xy 326.626151 -26.109714) (xy 326.551579 -26.069713) (xy 326.481079 -26.022905) (xy 326.415273 -25.969701)
			(xy 326.354737 -25.910569) (xy 326.300005 -25.846028) (xy 326.251558 -25.776645) (xy 326.20982 -25.70303)
			(xy 326.175159 -25.625831) (xy 326.147879 -25.545725) (xy 326.128221 -25.463416) (xy 326.116356 -25.379629)
			(xy 326.11239 -25.295098) (xy 324.539102 -25.295098) (xy 323.5198 -26.3144) (xy 314.804806 -26.3144)
			(xy 313.563508 -27.555952) (xy 313.563508 -30.295088) (xy 317.54243 -30.295088) (xy 317.546396 -30.210557)
			(xy 317.558261 -30.12677) (xy 317.577919 -30.044461) (xy 317.605199 -29.964355) (xy 317.63986 -29.887156)
			(xy 317.681598 -29.813541) (xy 317.730045 -29.744158) (xy 317.784777 -29.679617) (xy 317.845313 -29.620485)
			(xy 317.911119 -29.567281) (xy 317.981619 -29.520473) (xy 318.056191 -29.480472) (xy 318.134182 -29.44763)
			(xy 318.214906 -29.422236) (xy 318.297653 -29.404513) (xy 318.381695 -29.394615) (xy 318.466296 -29.392632)
			(xy 318.55071 -29.398579) (xy 318.634197 -29.412404) (xy 318.716022 -29.433987) (xy 318.795466 -29.463137)
			(xy 318.871832 -29.499598) (xy 318.944448 -29.54305) (xy 319.012676 -29.593111) (xy 319.075916 -29.649341)
			(xy 319.133613 -29.711246) (xy 319.18526 -29.778282) (xy 319.230402 -29.849859) (xy 319.268644 -29.925349)
			(xy 319.299648 -30.004088) (xy 319.323143 -30.085385) (xy 319.338922 -30.168524) (xy 319.346846 -30.252776)
			(xy 319.347342 -30.295088) (xy 319.346846 -30.3374) (xy 319.338922 -30.421652) (xy 319.323143 -30.504791)
			(xy 319.299648 -30.586088) (xy 319.268644 -30.664827) (xy 319.230402 -30.740317) (xy 319.18526 -30.811894)
			(xy 319.133613 -30.87893) (xy 319.075916 -30.940835) (xy 319.012676 -30.997065) (xy 318.944448 -31.047126)
			(xy 318.871832 -31.090578) (xy 318.795466 -31.127039) (xy 318.716022 -31.156189) (xy 318.634197 -31.177772)
			(xy 318.55071 -31.191597) (xy 318.466296 -31.197544) (xy 318.381695 -31.195561) (xy 318.297653 -31.185663)
			(xy 318.214906 -31.16794) (xy 318.134182 -31.142546) (xy 318.056191 -31.109704) (xy 317.981619 -31.069703)
			(xy 317.911119 -31.022895) (xy 317.845313 -30.969691) (xy 317.784777 -30.910559) (xy 317.730045 -30.846018)
			(xy 317.681598 -30.776635) (xy 317.63986 -30.70302) (xy 317.605199 -30.625821) (xy 317.577919 -30.545715)
			(xy 317.558261 -30.463406) (xy 317.546396 -30.379619) (xy 317.54243 -30.295088) (xy 313.563508 -30.295088)
			(xy 313.563508 -31.060898) (xy 313.182 -31.442152) (xy 313.182 -32.1818) (xy 314.0456 -33.0454) (xy 334.4164 -33.0454)
		)
		(stroke
			(width 0)
			(type solid)
		)
		(fill yes)
		(layer "In2.Cu")
		(net "P3V3_BLAD2")
	)
	(gr_poly
		(pts
			(xy 113.393474 -33.213802) (xy 113.401094 -33.167828) (xy 113.411169 -33.110443) (xy 113.43836 -32.99714)
			(xy 113.47347 -32.886034) (xy 113.516323 -32.77768) (xy 113.566707 -32.672616) (xy 113.624371 -32.571364)
			(xy 113.689028 -32.474428) (xy 113.760356 -32.382291) (xy 113.838001 -32.29541) (xy 113.921577 -32.214218)
			(xy 114.010668 -32.139119) (xy 114.10483 -32.070485) (xy 114.203595 -32.008659) (xy 114.306472 -31.953948)
			(xy 114.41295 -31.906624) (xy 114.522499 -31.866923) (xy 114.634573 -31.835042) (xy 114.748615 -31.811139)
			(xy 114.864059 -31.795334) (xy 114.98033 -31.787705) (xy 115.096849 -31.78829) (xy 115.213037 -31.797086)
			(xy 115.328316 -31.81405) (xy 115.442113 -31.839096) (xy 115.498118 -31.855156) (xy 115.514626 -31.859424)
			(xy 115.548705 -31.860025) (xy 115.581734 -31.851609) (xy 115.61137 -31.834774) (xy 115.623848 -31.823152)
			(xy 116.864892 -30.582108) (xy 116.864892 -28.62961) (xy 118.795292 -26.69921) (xy 118.795292 -25.069292)
			(xy 117.5004 -23.7744) (xy 116.9924 -23.7744) (xy 116.8908 -23.6728) (xy 116.8908 -23.5204) (xy 117.5004 -22.9108)
			(xy 117.5004 -20.664678) (xy 117.499795 -20.646824) (xy 117.489899 -20.612515) (xy 117.470887 -20.582289)
			(xy 117.457982 -20.569936) (xy 117.438364 -20.551767) (xy 117.403901 -20.510885) (xy 117.375482 -20.465591)
			(xy 117.353667 -20.416774) (xy 117.338881 -20.365388) (xy 117.331414 -20.312442) (xy 117.331413 -20.258971)
			(xy 117.338878 -20.206025) (xy 117.353662 -20.154639) (xy 117.375476 -20.10582) (xy 117.403893 -20.060526)
			(xy 117.438355 -20.019643) (xy 117.457982 -20.001484) (xy 117.470895 -19.989141) (xy 117.489891 -19.958908)
			(xy 117.499767 -19.924595) (xy 117.5004 -19.906742) (xy 117.5004 -2.5908) (xy 116.6876 -1.778) (xy 106.61269 -1.778)
			(xy 106.597952 -1.778414) (xy 106.569263 -1.785177) (xy 106.542899 -1.798359) (xy 106.520277 -1.817254)
			(xy 106.502609 -1.840848) (xy 106.496358 -1.8542) (xy 106.484952 -1.879187) (xy 106.456022 -1.925876)
			(xy 106.420693 -1.967932) (xy 106.379697 -2.004485) (xy 106.333881 -2.034779) (xy 106.284194 -2.058188)
			(xy 106.231662 -2.074226) (xy 106.177373 -2.082563) (xy 106.122449 -2.083026) (xy 106.068027 -2.075606)
			(xy 106.015232 -2.060455) (xy 105.965157 -2.037887) (xy 105.918837 -2.00837) (xy 105.89768 -1.990852)
			(xy 105.879602 -1.975977) (xy 105.839145 -1.952428) (xy 105.79506 -1.936688) (xy 105.748838 -1.92929)
			(xy 105.702042 -1.930483) (xy 105.656257 -1.940228) (xy 105.613031 -1.958194) (xy 105.593134 -1.970532)
			(xy 105.570995 -1.984445) (xy 105.523701 -2.00675) (xy 105.473808 -2.022399) (xy 105.4481 -2.027174)
			(xy 105.407968 -2.034032) (xy 104.8004 -2.6416) (xy 104.8004 -3.509518) (xy 104.800861 -3.52484)
			(xy 104.808185 -3.554596) (xy 104.822404 -3.581742) (xy 104.842695 -3.604705) (xy 104.867884 -3.622158)
			(xy 104.896512 -3.633089) (xy 104.911652 -3.635502) (xy 104.942033 -3.639811) (xy 105.001452 -3.655131)
			(xy 105.058451 -3.677855) (xy 105.112112 -3.707618) (xy 105.161571 -3.743939) (xy 105.206029 -3.786233)
			(xy 105.244771 -3.833818) (xy 105.277172 -3.885929) (xy 105.290366 -3.913632) (xy 105.30586 -3.947668)
			(xy 105.368344 -3.9878) (xy 106.9848 -3.9878) (xy 110.236 -7.239) (xy 110.236 -9.757894) (xy 112.901822 -9.757894)
			(xy 112.90523 -9.702502) (xy 112.916626 -9.648189) (xy 112.935769 -9.596099) (xy 112.962256 -9.547331)
			(xy 112.995527 -9.502915) (xy 113.034882 -9.463787) (xy 113.079489 -9.430772) (xy 113.128409 -9.404567)
			(xy 113.180608 -9.385724) (xy 113.234987 -9.374642) (xy 113.262664 -9.3726) (xy 113.27973 -9.371033)
			(xy 113.312209 -9.360161) (xy 113.340616 -9.341028) (xy 113.3629 -9.315018) (xy 113.377448 -9.284011)
			(xy 113.383208 -9.250249) (xy 113.382044 -9.233154) (xy 113.38052 -9.21385) (xy 113.37886 -9.190805)
			(xy 113.36828 -9.145835) (xy 113.349749 -9.103516) (xy 113.323879 -9.065241) (xy 113.291518 -9.03227)
			(xy 113.253734 -9.005688) (xy 113.211769 -8.986369) (xy 113.189512 -8.98017) (xy 113.162779 -8.972744)
			(xy 113.111588 -8.951359) (xy 113.064035 -8.922783) (xy 113.021124 -8.887618) (xy 112.983761 -8.846607)
			(xy 112.952734 -8.800616) (xy 112.928699 -8.750614) (xy 112.912161 -8.697657) (xy 112.903471 -8.642864)
			(xy 112.902812 -8.587389) (xy 112.910198 -8.532404) (xy 112.925472 -8.479069) (xy 112.948312 -8.428511)
			(xy 112.978237 -8.381795) (xy 113.014615 -8.339907) (xy 113.056678 -8.303733) (xy 113.103538 -8.274034)
			(xy 113.154207 -8.251439) (xy 113.207615 -8.236423) (xy 113.262635 -8.229304) (xy 113.318106 -8.230232)
			(xy 113.372857 -8.239187) (xy 113.425733 -8.255981) (xy 113.475617 -8.280258) (xy 113.521458 -8.311507)
			(xy 113.562288 -8.349068) (xy 113.597244 -8.392149) (xy 113.62559 -8.439839) (xy 113.646727 -8.491134)
			(xy 113.660209 -8.544949) (xy 113.663476 -8.5725) (xy 113.668556 -8.621268) (xy 113.740946 -8.6868)
			(xy 115.168934 -8.6868) (xy 115.183973 -8.686322) (xy 115.213207 -8.679246) (xy 115.239971 -8.665521)
			(xy 115.262776 -8.645908) (xy 115.280353 -8.6215) (xy 115.291725 -8.593654) (xy 115.29441 -8.57885)
			(xy 115.29908 -8.551377) (xy 115.315355 -8.498082) (xy 115.33921 -8.447721) (xy 115.370138 -8.401367)
			(xy 115.40748 -8.360006) (xy 115.450443 -8.324517) (xy 115.498112 -8.295656) (xy 115.549472 -8.274038)
			(xy 115.603431 -8.260121) (xy 115.65884 -8.254203) (xy 115.714521 -8.256408) (xy 115.769289 -8.266691)
			(xy 115.821978 -8.284833) (xy 115.871467 -8.310446) (xy 115.916704 -8.342988) (xy 115.956724 -8.381764)
			(xy 115.990678 -8.425949) (xy 116.017842 -8.474605) (xy 116.037639 -8.526695) (xy 116.049647 -8.58111)
			(xy 116.05361 -8.636694) (xy 116.049445 -8.692263) (xy 116.037239 -8.746634) (xy 116.017254 -8.798652)
			(xy 115.989913 -8.847208) (xy 115.955799 -8.891271) (xy 115.915638 -8.929901) (xy 115.870283 -8.962278)
			(xy 115.820701 -8.987711) (xy 115.767947 -9.005661) (xy 115.713142 -9.015745) (xy 115.685316 -9.017254)
			(xy 115.668056 -9.018506) (xy 115.63512 -9.029078) (xy 115.606224 -9.048092) (xy 115.583483 -9.074157)
			(xy 115.568561 -9.105364) (xy 115.562553 -9.13943) (xy 115.56365 -9.1567) (xy 115.565428 -9.18972)
			(xy 115.566291 -9.213716) (xy 115.575968 -9.260743) (xy 115.594295 -9.305119) (xy 115.620621 -9.34527)
			(xy 115.654011 -9.37977) (xy 115.693279 -9.407394) (xy 115.737033 -9.427161) (xy 115.760246 -9.433306)
			(xy 115.786636 -9.440147) (xy 115.837317 -9.460233) (xy 115.884622 -9.487328) (xy 115.927588 -9.520881)
			(xy 115.965341 -9.560208) (xy 115.997111 -9.60451) (xy 116.02225 -9.652883) (xy 116.040248 -9.704341)
			(xy 116.050738 -9.757838) (xy 116.053505 -9.812283) (xy 116.048493 -9.866568) (xy 116.035805 -9.919586)
			(xy 116.015699 -9.970258) (xy 115.988585 -10.017552) (xy 115.955014 -10.060505) (xy 115.915671 -10.098241)
			(xy 115.871356 -10.129993) (xy 115.822973 -10.155113) (xy 115.771507 -10.173089) (xy 115.718006 -10.183557)
			(xy 115.66356 -10.186301) (xy 115.609278 -10.181268) (xy 115.556264 -10.168558) (xy 115.505601 -10.148431)
			(xy 115.458318 -10.121297) (xy 115.415379 -10.087709) (xy 115.377659 -10.04835) (xy 115.345925 -10.004023)
			(xy 115.320825 -9.955629) (xy 115.30287 -9.904156) (xy 115.292424 -9.850651) (xy 115.2906 -9.82345)
			(xy 115.28806 -9.77265) (xy 115.214654 -9.7028) (xy 113.786666 -9.7028) (xy 113.771627 -9.703278)
			(xy 113.742393 -9.710354) (xy 113.715629 -9.724079) (xy 113.692824 -9.743692) (xy 113.675247 -9.7681)
			(xy 113.663875 -9.795946) (xy 113.66119 -9.81075) (xy 113.656539 -9.83811) (xy 113.640367 -9.891198)
			(xy 113.616676 -9.941383) (xy 113.585964 -9.987606) (xy 113.548881 -10.028894) (xy 113.506209 -10.064374)
			(xy 113.458846 -10.093299) (xy 113.407794 -10.115058) (xy 113.354128 -10.129193) (xy 113.298981 -10.135404)
			(xy 113.243515 -10.133562) (xy 113.188901 -10.123704) (xy 113.136292 -10.10604) (xy 113.086796 -10.08094)
			(xy 113.041458 -10.048936) (xy 113.001234 -10.010702) (xy 112.966972 -9.967045) (xy 112.939396 -9.918885)
			(xy 112.919087 -9.867238) (xy 112.906474 -9.813194) (xy 112.901822 -9.757894) (xy 110.236 -9.757894)
			(xy 110.236 -10.9982) (xy 108.43895 -12.79525) (xy 110.89387 -12.79525) (xy 110.897851 -12.715486)
			(xy 110.909754 -12.636514) (xy 110.929461 -12.55912) (xy 110.956776 -12.484073) (xy 110.991427 -12.412118)
			(xy 111.033071 -12.343971) (xy 111.081293 -12.280309) (xy 111.135614 -12.221765) (xy 111.195495 -12.16892)
			(xy 111.260339 -12.1223) (xy 111.329503 -12.082368) (xy 111.402299 -12.049521) (xy 111.478004 -12.024086)
			(xy 111.555865 -12.006315) (xy 111.635109 -11.996384) (xy 111.714948 -11.994393) (xy 111.794588 -12.000361)
			(xy 111.873239 -12.014229) (xy 111.950118 -12.03586) (xy 112.024461 -12.065037) (xy 112.095529 -12.101472)
			(xy 112.162617 -12.144802) (xy 112.225056 -12.194596) (xy 112.282228 -12.25036) (xy 112.333564 -12.311539)
			(xy 112.378552 -12.377525) (xy 112.416748 -12.447663) (xy 112.447769 -12.521256) (xy 112.47131 -12.597571)
			(xy 112.487134 -12.675851) (xy 112.495086 -12.755318) (xy 112.495584 -12.79525) (xy 112.495086 -12.835182)
			(xy 112.487134 -12.914649) (xy 112.47131 -12.992929) (xy 112.447769 -13.069244) (xy 112.416748 -13.142837)
			(xy 112.378552 -13.212975) (xy 112.333564 -13.278961) (xy 112.282228 -13.34014) (xy 112.225056 -13.395904)
			(xy 112.162617 -13.445698) (xy 112.095529 -13.489028) (xy 112.024461 -13.525463) (xy 111.950118 -13.55464)
			(xy 111.873239 -13.576271) (xy 111.794588 -13.590139) (xy 111.714948 -13.596107) (xy 111.635109 -13.594116)
			(xy 111.555865 -13.584185) (xy 111.478004 -13.566414) (xy 111.402299 -13.540979) (xy 111.329503 -13.508132)
			(xy 111.260339 -13.4682) (xy 111.195495 -13.42158) (xy 111.135614 -13.368735) (xy 111.081293 -13.310191)
			(xy 111.033071 -13.246529) (xy 110.991427 -13.178382) (xy 110.956776 -13.106427) (xy 110.929461 -13.03138)
			(xy 110.909754 -12.953986) (xy 110.897851 -12.875014) (xy 110.89387 -12.79525) (xy 108.43895 -12.79525)
			(xy 108.0008 -13.2334) (xy 106.9594 -13.2334) (xy 106.942752 -13.233943) (xy 106.910589 -13.242561)
			(xy 106.881754 -13.259209) (xy 106.858209 -13.282754) (xy 106.841561 -13.311589) (xy 106.832943 -13.343752)
			(xy 106.8324 -13.3604) (xy 106.8324 -14.745462) (xy 108.48086 -14.745462) (xy 108.48086 -14.059662)
			(xy 108.481364 -14.017301) (xy 108.489417 -13.932964) (xy 108.505451 -13.849774) (xy 108.529319 -13.768484)
			(xy 108.560807 -13.689832) (xy 108.599629 -13.614529) (xy 108.645432 -13.543257) (xy 108.697803 -13.476661)
			(xy 108.756268 -13.415346) (xy 108.820296 -13.359865) (xy 108.889308 -13.310722) (xy 108.962678 -13.268362)
			(xy 109.039743 -13.233167) (xy 109.119805 -13.205458) (xy 109.202138 -13.185484) (xy 109.285997 -13.173427)
			(xy 109.370622 -13.169396) (xy 109.455247 -13.173427) (xy 109.539106 -13.185484) (xy 109.621439 -13.205458)
			(xy 109.701501 -13.233167) (xy 109.778566 -13.268362) (xy 109.851936 -13.310722) (xy 109.920948 -13.359865)
			(xy 109.984976 -13.415346) (xy 110.043441 -13.476661) (xy 110.095812 -13.543257) (xy 110.141615 -13.614529)
			(xy 110.180437 -13.689832) (xy 110.211925 -13.768484) (xy 110.235793 -13.849774) (xy 110.251827 -13.932964)
			(xy 110.25988 -14.017301) (xy 110.260384 -14.059662) (xy 110.260384 -14.694662) (xy 110.259852 -14.736949)
			(xy 110.252052 -14.821164) (xy 110.236515 -14.904299) (xy 110.213373 -14.985646) (xy 110.182824 -15.06451)
			(xy 110.145129 -15.14022) (xy 110.100608 -15.212128) (xy 110.049643 -15.279622) (xy 110.035518 -15.295118)
			(xy 110.944671 -15.295118) (xy 110.948647 -15.217971) (xy 110.960535 -15.141641) (xy 110.980208 -15.066939)
			(xy 111.007458 -14.994655) (xy 111.041996 -14.925556) (xy 111.083456 -14.860375) (xy 111.131398 -14.799802)
			(xy 111.185313 -14.74448) (xy 111.244632 -14.694994) (xy 111.308724 -14.65187) (xy 111.376911 -14.615565)
			(xy 111.448469 -14.586463) (xy 111.52264 -14.564872) (xy 111.598638 -14.551023) (xy 111.675657 -14.545061)
			(xy 111.752881 -14.54705) (xy 111.829491 -14.556969) (xy 111.904676 -14.574712) (xy 111.977637 -14.600092)
			(xy 112.047602 -14.632839) (xy 112.113829 -14.672607) (xy 112.175617 -14.718973) (xy 112.232309 -14.771447)
			(xy 112.283305 -14.829471) (xy 112.328065 -14.892432) (xy 112.366115 -14.959661) (xy 112.397049 -15.030446)
			(xy 112.420542 -15.104037) (xy 112.436344 -15.179653) (xy 112.444287 -15.256493) (xy 112.444784 -15.295118)
			(xy 112.444287 -15.333743) (xy 112.436344 -15.410583) (xy 112.420542 -15.486199) (xy 112.397049 -15.55979)
			(xy 112.366115 -15.630575) (xy 112.328065 -15.697804) (xy 112.283305 -15.760765) (xy 112.232309 -15.818789)
			(xy 112.175617 -15.871263) (xy 112.113829 -15.917629) (xy 112.047602 -15.957397) (xy 111.977637 -15.990144)
			(xy 111.904676 -16.015524) (xy 111.829491 -16.033267) (xy 111.752881 -16.043186) (xy 111.675657 -16.045175)
			(xy 111.598638 -16.039213) (xy 111.52264 -16.025364) (xy 111.448469 -16.003773) (xy 111.376911 -15.974671)
			(xy 111.308724 -15.938366) (xy 111.244632 -15.895242) (xy 111.185313 -15.845756) (xy 111.131398 -15.790434)
			(xy 111.083456 -15.729861) (xy 111.041996 -15.66468) (xy 111.007458 -15.595581) (xy 110.980208 -15.523297)
			(xy 110.960535 -15.448595) (xy 110.948647 -15.372265) (xy 110.944671 -15.295118) (xy 110.035518 -15.295118)
			(xy 109.992668 -15.342125) (xy 109.930168 -15.399105) (xy 109.862678 -15.450074) (xy 109.790772 -15.494599)
			(xy 109.715065 -15.5323) (xy 109.636203 -15.562854) (xy 109.554857 -15.586001) (xy 109.471723 -15.601544)
			(xy 109.387509 -15.609349) (xy 109.345222 -15.609824) (xy 109.302783 -15.609337) (xy 109.218312 -15.601019)
			(xy 109.135064 -15.584462) (xy 109.05384 -15.559824) (xy 108.975422 -15.527343) (xy 108.900565 -15.487331)
			(xy 108.829991 -15.440175) (xy 108.764379 -15.386328) (xy 108.704361 -15.326309) (xy 108.650515 -15.260696)
			(xy 108.60336 -15.190121) (xy 108.563351 -15.115264) (xy 108.530871 -15.036845) (xy 108.506234 -14.95562)
			(xy 108.489678 -14.872372) (xy 108.481362 -14.787901) (xy 108.48086 -14.745462) (xy 106.8324 -14.745462)
			(xy 106.8324 -17.79524) (xy 110.89387 -17.79524) (xy 110.897851 -17.715476) (xy 110.909754 -17.636504)
			(xy 110.929461 -17.55911) (xy 110.956776 -17.484063) (xy 110.991427 -17.412108) (xy 111.033071 -17.343961)
			(xy 111.081293 -17.280299) (xy 111.135614 -17.221755) (xy 111.195495 -17.16891) (xy 111.260339 -17.12229)
			(xy 111.329503 -17.082358) (xy 111.402299 -17.049511) (xy 111.478004 -17.024076) (xy 111.555865 -17.006305)
			(xy 111.635109 -16.996374) (xy 111.714948 -16.994383) (xy 111.794588 -17.000351) (xy 111.873239 -17.014219)
			(xy 111.950118 -17.03585) (xy 112.024461 -17.065027) (xy 112.095529 -17.101462) (xy 112.162617 -17.144792)
			(xy 112.225056 -17.194586) (xy 112.282228 -17.25035) (xy 112.333564 -17.311529) (xy 112.378552 -17.377515)
			(xy 112.416748 -17.447653) (xy 112.447769 -17.521246) (xy 112.47131 -17.597561) (xy 112.487134 -17.675841)
			(xy 112.495086 -17.755308) (xy 112.495584 -17.79524) (xy 112.495086 -17.835172) (xy 112.487134 -17.914639)
			(xy 112.47131 -17.992919) (xy 112.447769 -18.069234) (xy 112.416748 -18.142827) (xy 112.378552 -18.212965)
			(xy 112.333564 -18.278951) (xy 112.282228 -18.34013) (xy 112.225056 -18.395894) (xy 112.162617 -18.445688)
			(xy 112.095529 -18.489018) (xy 112.024461 -18.525453) (xy 111.950118 -18.55463) (xy 111.873239 -18.576261)
			(xy 111.794588 -18.590129) (xy 111.714948 -18.596097) (xy 111.635109 -18.594106) (xy 111.555865 -18.584175)
			(xy 111.478004 -18.566404) (xy 111.402299 -18.540969) (xy 111.329503 -18.508122) (xy 111.260339 -18.46819)
			(xy 111.195495 -18.42157) (xy 111.135614 -18.368725) (xy 111.081293 -18.310181) (xy 111.033071 -18.246519)
			(xy 110.991427 -18.178372) (xy 110.956776 -18.106417) (xy 110.929461 -18.03137) (xy 110.909754 -17.953976)
			(xy 110.897851 -17.875004) (xy 110.89387 -17.79524) (xy 106.8324 -17.79524) (xy 106.8324 -19.28368)
			(xy 106.832835 -19.305311) (xy 106.840162 -19.347948) (xy 106.854608 -19.388727) (xy 106.875755 -19.426468)
			(xy 106.902992 -19.46008) (xy 106.93553 -19.48859) (xy 106.972429 -19.511175) (xy 107.012621 -19.527181)
			(xy 107.054944 -19.536145) (xy 107.098174 -19.537808) (xy 107.119674 -19.535394) (xy 107.146586 -19.532291)
			(xy 107.200757 -19.532813) (xy 107.254309 -19.540992) (xy 107.306166 -19.556664) (xy 107.355285 -19.579513)
			(xy 107.400678 -19.60908) (xy 107.441432 -19.644771) (xy 107.476729 -19.685867) (xy 107.505857 -19.731543)
			(xy 107.528232 -19.780879) (xy 107.543403 -19.832885) (xy 107.544048 -19.8374) (xy 107.872782 -19.8374)
			(xy 107.876853 -19.781778) (xy 107.888979 -19.727341) (xy 107.908902 -19.67525) (xy 107.936198 -19.626615)
			(xy 107.970284 -19.582472) (xy 108.010433 -19.543763) (xy 108.055791 -19.511312) (xy 108.105391 -19.485811)
			(xy 108.158175 -19.467804) (xy 108.213018 -19.457674) (xy 108.268752 -19.455637) (xy 108.324189 -19.461737)
			(xy 108.378146 -19.475843) (xy 108.429475 -19.497655) (xy 108.477081 -19.526709) (xy 108.519949 -19.562384)
			(xy 108.557166 -19.603921) (xy 108.587939 -19.650434) (xy 108.611611 -19.700931) (xy 108.627679 -19.754338)
			(xy 108.635799 -19.809514) (xy 108.636308 -19.8374) (xy 108.635799 -19.865286) (xy 108.627679 -19.920462)
			(xy 108.611611 -19.973869) (xy 108.587939 -20.024366) (xy 108.557166 -20.070879) (xy 108.519949 -20.112416)
			(xy 108.477081 -20.148091) (xy 108.429475 -20.177145) (xy 108.378146 -20.198957) (xy 108.324189 -20.213063)
			(xy 108.268752 -20.219163) (xy 108.213018 -20.217126) (xy 108.158175 -20.206996) (xy 108.105391 -20.188989)
			(xy 108.055791 -20.163488) (xy 108.010433 -20.131037) (xy 107.970284 -20.092328) (xy 107.936198 -20.048185)
			(xy 107.908902 -19.99955) (xy 107.888979 -19.947459) (xy 107.876853 -19.893022) (xy 107.872782 -19.8374)
			(xy 107.544048 -19.8374) (xy 107.551066 -19.886513) (xy 107.551066 -19.940687) (xy 107.543403 -19.994315)
			(xy 107.528232 -20.046321) (xy 107.505857 -20.095657) (xy 107.476729 -20.141333) (xy 107.441432 -20.182429)
			(xy 107.400678 -20.21812) (xy 107.355285 -20.247687) (xy 107.306166 -20.270536) (xy 107.254309 -20.286208)
			(xy 107.200757 -20.294387) (xy 107.146586 -20.294909) (xy 107.119674 -20.291806) (xy 107.098173 -20.289405)
			(xy 107.054945 -20.291083) (xy 107.012626 -20.300057) (xy 106.972437 -20.316066) (xy 106.935539 -20.33865)
			(xy 106.902997 -20.367155) (xy 106.875752 -20.400758) (xy 106.854591 -20.43849) (xy 106.840124 -20.479259)
			(xy 106.832768 -20.52189) (xy 106.8324 -20.54352) (xy 106.8324 -20.6756) (xy 114.197382 -20.6756)
			(xy 114.201453 -20.619978) (xy 114.213579 -20.565541) (xy 114.233502 -20.51345) (xy 114.260798 -20.464815)
			(xy 114.294884 -20.420672) (xy 114.335033 -20.381963) (xy 114.380391 -20.349512) (xy 114.429991 -20.324011)
			(xy 114.482775 -20.306004) (xy 114.537618 -20.295874) (xy 114.593352 -20.293837) (xy 114.648789 -20.299937)
			(xy 114.702746 -20.314043) (xy 114.754075 -20.335855) (xy 114.801681 -20.364909) (xy 114.844549 -20.400584)
			(xy 114.881766 -20.442121) (xy 114.912539 -20.488634) (xy 114.936211 -20.539131) (xy 114.952279 -20.592538)
			(xy 114.960399 -20.647714) (xy 114.960908 -20.6756) (xy 114.960399 -20.703486) (xy 114.952279 -20.758662)
			(xy 114.936211 -20.812069) (xy 114.912539 -20.862566) (xy 114.881766 -20.909079) (xy 114.844549 -20.950616)
			(xy 114.801681 -20.986291) (xy 114.754075 -21.015345) (xy 114.702746 -21.037157) (xy 114.648789 -21.051263)
			(xy 114.593352 -21.057363) (xy 114.537618 -21.055326) (xy 114.482775 -21.045196) (xy 114.429991 -21.027189)
			(xy 114.380391 -21.001688) (xy 114.335033 -20.969237) (xy 114.294884 -20.930528) (xy 114.260798 -20.886385)
			(xy 114.233502 -20.83775) (xy 114.213579 -20.785659) (xy 114.201453 -20.731222) (xy 114.197382 -20.6756)
			(xy 106.8324 -20.6756) (xy 106.8324 -22.495256) (xy 110.89387 -22.495256) (xy 110.897851 -22.415492)
			(xy 110.909754 -22.33652) (xy 110.929461 -22.259126) (xy 110.956776 -22.184079) (xy 110.991427 -22.112124)
			(xy 111.033071 -22.043977) (xy 111.081293 -21.980315) (xy 111.135614 -21.921771) (xy 111.195495 -21.868926)
			(xy 111.260339 -21.822306) (xy 111.329503 -21.782374) (xy 111.402299 -21.749527) (xy 111.478004 -21.724092)
			(xy 111.555865 -21.706321) (xy 111.635109 -21.69639) (xy 111.714948 -21.694399) (xy 111.794588 -21.700367)
			(xy 111.873239 -21.714235) (xy 111.950118 -21.735866) (xy 112.024461 -21.765043) (xy 112.095529 -21.801478)
			(xy 112.162617 -21.844808) (xy 112.225056 -21.894602) (xy 112.282228 -21.950366) (xy 112.333564 -22.011545)
			(xy 112.357873 -22.0472) (xy 114.756182 -22.0472) (xy 114.760253 -21.991578) (xy 114.772379 -21.937141)
			(xy 114.792302 -21.88505) (xy 114.819598 -21.836415) (xy 114.853684 -21.792272) (xy 114.893833 -21.753563)
			(xy 114.939191 -21.721112) (xy 114.988791 -21.695611) (xy 115.041575 -21.677604) (xy 115.096418 -21.667474)
			(xy 115.152152 -21.665437) (xy 115.207589 -21.671537) (xy 115.261546 -21.685643) (xy 115.312875 -21.707455)
			(xy 115.360481 -21.736509) (xy 115.403349 -21.772184) (xy 115.440566 -21.813721) (xy 115.471339 -21.860234)
			(xy 115.495011 -21.910731) (xy 115.511079 -21.964138) (xy 115.519199 -22.019314) (xy 115.519708 -22.0472)
			(xy 115.519199 -22.075086) (xy 115.511079 -22.130262) (xy 115.495011 -22.183669) (xy 115.471339 -22.234166)
			(xy 115.440566 -22.280679) (xy 115.403349 -22.322216) (xy 115.360481 -22.357891) (xy 115.312875 -22.386945)
			(xy 115.261546 -22.408757) (xy 115.207589 -22.422863) (xy 115.152152 -22.428963) (xy 115.096418 -22.426926)
			(xy 115.041575 -22.416796) (xy 114.988791 -22.398789) (xy 114.939191 -22.373288) (xy 114.893833 -22.340837)
			(xy 114.853684 -22.302128) (xy 114.819598 -22.257985) (xy 114.792302 -22.20935) (xy 114.772379 -22.157259)
			(xy 114.760253 -22.102822) (xy 114.756182 -22.0472) (xy 112.357873 -22.0472) (xy 112.378552 -22.077531)
			(xy 112.416748 -22.147669) (xy 112.447769 -22.221262) (xy 112.47131 -22.297577) (xy 112.487134 -22.375857)
			(xy 112.495086 -22.455324) (xy 112.495584 -22.495256) (xy 112.495086 -22.535188) (xy 112.487134 -22.614655)
			(xy 112.47131 -22.692935) (xy 112.447769 -22.76925) (xy 112.416748 -22.842843) (xy 112.378552 -22.912981)
			(xy 112.333564 -22.978967) (xy 112.282228 -23.040146) (xy 112.225056 -23.09591) (xy 112.162617 -23.145704)
			(xy 112.095529 -23.189034) (xy 112.024461 -23.225469) (xy 111.950118 -23.254646) (xy 111.873239 -23.276277)
			(xy 111.794588 -23.290145) (xy 111.714948 -23.296113) (xy 111.635109 -23.294122) (xy 111.555865 -23.284191)
			(xy 111.478004 -23.26642) (xy 111.402299 -23.240985) (xy 111.329503 -23.208138) (xy 111.260339 -23.168206)
			(xy 111.195495 -23.121586) (xy 111.135614 -23.068741) (xy 111.081293 -23.010197) (xy 111.033071 -22.946535)
			(xy 110.991427 -22.878388) (xy 110.956776 -22.806433) (xy 110.929461 -22.731386) (xy 110.909754 -22.653992)
			(xy 110.897851 -22.57502) (xy 110.89387 -22.495256) (xy 106.8324 -22.495256) (xy 106.8324 -23.4442)
			(xy 114.908582 -23.4442) (xy 114.912653 -23.388578) (xy 114.924779 -23.334141) (xy 114.944702 -23.28205)
			(xy 114.971998 -23.233415) (xy 115.006084 -23.189272) (xy 115.046233 -23.150563) (xy 115.091591 -23.118112)
			(xy 115.141191 -23.092611) (xy 115.193975 -23.074604) (xy 115.248818 -23.064474) (xy 115.304552 -23.062437)
			(xy 115.359989 -23.068537) (xy 115.413946 -23.082643) (xy 115.465275 -23.104455) (xy 115.512881 -23.133509)
			(xy 115.555749 -23.169184) (xy 115.592966 -23.210721) (xy 115.623739 -23.257234) (xy 115.647411 -23.307731)
			(xy 115.663479 -23.361138) (xy 115.671599 -23.416314) (xy 115.672108 -23.4442) (xy 115.671599 -23.472086)
			(xy 115.663479 -23.527262) (xy 115.647411 -23.580669) (xy 115.623739 -23.631166) (xy 115.592966 -23.677679)
			(xy 115.555749 -23.719216) (xy 115.512881 -23.754891) (xy 115.465275 -23.783945) (xy 115.413946 -23.805757)
			(xy 115.359989 -23.819863) (xy 115.304552 -23.825963) (xy 115.248818 -23.823926) (xy 115.193975 -23.813796)
			(xy 115.141191 -23.795789) (xy 115.091591 -23.770288) (xy 115.046233 -23.737837) (xy 115.006084 -23.699128)
			(xy 114.971998 -23.654985) (xy 114.944702 -23.60635) (xy 114.924779 -23.554259) (xy 114.912653 -23.499822)
			(xy 114.908582 -23.4442) (xy 106.8324 -23.4442) (xy 106.8324 -23.9268) (xy 106.551476 -24.207724)
			(xy 106.53662 -24.223209) (xy 106.511805 -24.258214) (xy 106.493226 -24.296893) (xy 106.481414 -24.338144)
			(xy 106.476702 -24.380793) (xy 106.479226 -24.423627) (xy 106.488914 -24.465428) (xy 106.50549 -24.505006)
			(xy 106.528482 -24.541235) (xy 106.557236 -24.573084) (xy 106.573828 -24.586692) (xy 106.606759 -24.613282)
			(xy 106.668015 -24.671701) (xy 106.72353 -24.7356) (xy 106.772816 -24.804418) (xy 106.815441 -24.877549)
			(xy 106.851029 -24.954351) (xy 106.879267 -25.034148) (xy 106.899908 -25.11624) (xy 106.91277 -25.199903)
			(xy 106.91774 -25.284404) (xy 106.917365 -25.295098) (xy 110.792272 -25.295098) (xy 110.796238 -25.210567)
			(xy 110.808103 -25.12678) (xy 110.827761 -25.044471) (xy 110.855041 -24.964365) (xy 110.889702 -24.887166)
			(xy 110.93144 -24.813551) (xy 110.979887 -24.744168) (xy 111.034619 -24.679627) (xy 111.095155 -24.620495)
			(xy 111.160961 -24.567291) (xy 111.231461 -24.520483) (xy 111.306033 -24.480482) (xy 111.384024 -24.44764)
			(xy 111.464748 -24.422246) (xy 111.547495 -24.404523) (xy 111.631537 -24.394625) (xy 111.716138 -24.392642)
			(xy 111.800552 -24.398589) (xy 111.884039 -24.412414) (xy 111.965864 -24.433997) (xy 112.045308 -24.463147)
			(xy 112.121674 -24.499608) (xy 112.19429 -24.54306) (xy 112.262518 -24.593121) (xy 112.312992 -24.638)
			(xy 114.451382 -24.638) (xy 114.455453 -24.582378) (xy 114.467579 -24.527941) (xy 114.487502 -24.47585)
			(xy 114.514798 -24.427215) (xy 114.548884 -24.383072) (xy 114.589033 -24.344363) (xy 114.634391 -24.311912)
			(xy 114.683991 -24.286411) (xy 114.736775 -24.268404) (xy 114.791618 -24.258274) (xy 114.847352 -24.256237)
			(xy 114.902789 -24.262337) (xy 114.956746 -24.276443) (xy 115.008075 -24.298255) (xy 115.055681 -24.327309)
			(xy 115.098549 -24.362984) (xy 115.135766 -24.404521) (xy 115.166539 -24.451034) (xy 115.190211 -24.501531)
			(xy 115.206279 -24.554938) (xy 115.214399 -24.610114) (xy 115.214908 -24.638) (xy 115.214399 -24.665886)
			(xy 115.206279 -24.721062) (xy 115.190211 -24.774469) (xy 115.166539 -24.824966) (xy 115.135766 -24.871479)
			(xy 115.098549 -24.913016) (xy 115.055681 -24.948691) (xy 115.008075 -24.977745) (xy 114.956746 -24.999557)
			(xy 114.902789 -25.013663) (xy 114.847352 -25.019763) (xy 114.791618 -25.017726) (xy 114.736775 -25.007596)
			(xy 114.683991 -24.989589) (xy 114.634391 -24.964088) (xy 114.589033 -24.931637) (xy 114.548884 -24.892928)
			(xy 114.514798 -24.848785) (xy 114.487502 -24.80015) (xy 114.467579 -24.748059) (xy 114.455453 -24.693622)
			(xy 114.451382 -24.638) (xy 112.312992 -24.638) (xy 112.325758 -24.649351) (xy 112.383455 -24.711256)
			(xy 112.435102 -24.778292) (xy 112.480244 -24.849869) (xy 112.518486 -24.925359) (xy 112.54949 -25.004098)
			(xy 112.572985 -25.085395) (xy 112.588764 -25.168534) (xy 112.596688 -25.252786) (xy 112.597184 -25.295098)
			(xy 112.596688 -25.33741) (xy 112.588764 -25.421662) (xy 112.572985 -25.504801) (xy 112.54949 -25.586098)
			(xy 112.518486 -25.664837) (xy 112.480244 -25.740327) (xy 112.435102 -25.811904) (xy 112.383455 -25.87894)
			(xy 112.325758 -25.940845) (xy 112.305565 -25.9588) (xy 114.425982 -25.9588) (xy 114.430053 -25.903178)
			(xy 114.442179 -25.848741) (xy 114.462102 -25.79665) (xy 114.489398 -25.748015) (xy 114.523484 -25.703872)
			(xy 114.563633 -25.665163) (xy 114.608991 -25.632712) (xy 114.658591 -25.607211) (xy 114.711375 -25.589204)
			(xy 114.766218 -25.579074) (xy 114.821952 -25.577037) (xy 114.877389 -25.583137) (xy 114.931346 -25.597243)
			(xy 114.982675 -25.619055) (xy 115.030281 -25.648109) (xy 115.073149 -25.683784) (xy 115.110366 -25.725321)
			(xy 115.141139 -25.771834) (xy 115.164811 -25.822331) (xy 115.180879 -25.875738) (xy 115.188999 -25.930914)
			(xy 115.189508 -25.9588) (xy 115.188999 -25.986686) (xy 115.180879 -26.041862) (xy 115.164811 -26.095269)
			(xy 115.141139 -26.145766) (xy 115.110366 -26.192279) (xy 115.073149 -26.233816) (xy 115.030281 -26.269491)
			(xy 114.982675 -26.298545) (xy 114.931346 -26.320357) (xy 114.877389 -26.334463) (xy 114.821952 -26.340563)
			(xy 114.766218 -26.338526) (xy 114.711375 -26.328396) (xy 114.658591 -26.310389) (xy 114.608991 -26.284888)
			(xy 114.563633 -26.252437) (xy 114.523484 -26.213728) (xy 114.489398 -26.169585) (xy 114.462102 -26.12095)
			(xy 114.442179 -26.068859) (xy 114.430053 -26.014422) (xy 114.425982 -25.9588) (xy 112.305565 -25.9588)
			(xy 112.262518 -25.997075) (xy 112.19429 -26.047136) (xy 112.121674 -26.090588) (xy 112.045308 -26.127049)
			(xy 111.965864 -26.156199) (xy 111.884039 -26.177782) (xy 111.800552 -26.191607) (xy 111.716138 -26.197554)
			(xy 111.631537 -26.195571) (xy 111.547495 -26.185673) (xy 111.464748 -26.16795) (xy 111.384024 -26.142556)
			(xy 111.306033 -26.109714) (xy 111.231461 -26.069713) (xy 111.160961 -26.022905) (xy 111.095155 -25.969701)
			(xy 111.034619 -25.910569) (xy 110.979887 -25.846028) (xy 110.93144 -25.776645) (xy 110.889702 -25.70303)
			(xy 110.855041 -25.625831) (xy 110.827761 -25.545725) (xy 110.808103 -25.463416) (xy 110.796238 -25.379629)
			(xy 110.792272 -25.295098) (xy 106.917365 -25.295098) (xy 106.914774 -25.368998) (xy 106.903898 -25.452943)
			(xy 106.885208 -25.535501) (xy 106.858868 -25.615944) (xy 106.825109 -25.693568) (xy 106.784229 -25.767689)
			(xy 106.736587 -25.837655) (xy 106.682602 -25.902851) (xy 106.622748 -25.962705) (xy 106.557551 -26.01669)
			(xy 106.487584 -26.064332) (xy 106.413464 -26.105212) (xy 106.33584 -26.138969) (xy 106.255396 -26.165309)
			(xy 106.172838 -26.183999) (xy 106.088893 -26.194874) (xy 106.004299 -26.19784) (xy 105.919798 -26.19287)
			(xy 105.836135 -26.180007) (xy 105.754044 -26.159366) (xy 105.674247 -26.131127) (xy 105.597445 -26.095538)
			(xy 105.524314 -26.052913) (xy 105.455497 -26.003627) (xy 105.391598 -25.948111) (xy 105.333179 -25.886855)
			(xy 105.306622 -25.853898) (xy 105.292987 -25.837333) (xy 105.261136 -25.808592) (xy 105.224909 -25.78561)
			(xy 105.185337 -25.769041) (xy 105.143543 -25.759356) (xy 105.100716 -25.756829) (xy 105.058073 -25.761534)
			(xy 105.016827 -25.773336) (xy 104.97815 -25.7919) (xy 104.943141 -25.816698) (xy 104.927654 -25.831546)
			(xy 102.743 -28.0162) (xy 94.61119 -28.0162) (xy 92.332302 -30.295088) (xy 96.542364 -30.295088)
			(xy 96.54633 -30.210557) (xy 96.558195 -30.12677) (xy 96.577853 -30.044461) (xy 96.605133 -29.964355)
			(xy 96.639794 -29.887156) (xy 96.681532 -29.813541) (xy 96.729979 -29.744158) (xy 96.784711 -29.679617)
			(xy 96.845247 -29.620485) (xy 96.911053 -29.567281) (xy 96.981553 -29.520473) (xy 97.056125 -29.480472)
			(xy 97.134116 -29.44763) (xy 97.21484 -29.422236) (xy 97.297587 -29.404513) (xy 97.381629 -29.394615)
			(xy 97.46623 -29.392632) (xy 97.550644 -29.398579) (xy 97.634131 -29.412404) (xy 97.715956 -29.433987)
			(xy 97.7954 -29.463137) (xy 97.871766 -29.499598) (xy 97.944382 -29.54305) (xy 98.01261 -29.593111)
			(xy 98.07585 -29.649341) (xy 98.133547 -29.711246) (xy 98.185194 -29.778282) (xy 98.230336 -29.849859)
			(xy 98.268578 -29.925349) (xy 98.299582 -30.004088) (xy 98.323077 -30.085385) (xy 98.338856 -30.168524)
			(xy 98.34678 -30.252776) (xy 98.347276 -30.295088) (xy 98.34678 -30.3374) (xy 98.338856 -30.421652)
			(xy 98.323077 -30.504791) (xy 98.299582 -30.586088) (xy 98.268578 -30.664827) (xy 98.230336 -30.740317)
			(xy 98.185194 -30.811894) (xy 98.133547 -30.87893) (xy 98.07585 -30.940835) (xy 98.01261 -30.997065)
			(xy 97.944382 -31.047126) (xy 97.871766 -31.090578) (xy 97.7954 -31.127039) (xy 97.715956 -31.156189)
			(xy 97.634131 -31.177772) (xy 97.550644 -31.191597) (xy 97.46623 -31.197544) (xy 97.381629 -31.195561)
			(xy 97.297587 -31.185663) (xy 97.21484 -31.16794) (xy 97.134116 -31.142546) (xy 97.056125 -31.109704)
			(xy 96.981553 -31.069703) (xy 96.911053 -31.022895) (xy 96.845247 -30.969691) (xy 96.784711 -30.910559)
			(xy 96.729979 -30.846018) (xy 96.681532 -30.776635) (xy 96.639794 -30.70302) (xy 96.605133 -30.625821)
			(xy 96.577853 -30.545715) (xy 96.558195 -30.463406) (xy 96.54633 -30.379619) (xy 96.542364 -30.295088)
			(xy 92.332302 -30.295088) (xy 92.2274 -30.39999) (xy 92.2274 -32.3342) (xy 93.1672 -33.274) (xy 113.322608 -33.274)
		)
		(stroke
			(width 0)
			(type solid)
		)
		(fill yes)
		(layer "In2.Cu")
		(net "P3V3_BLAD1")
	)
	(gr_poly
		(pts
			(xy 154.2796 -26.7462) (xy 154.2796 -22.958806) (xy 150.176484 -18.85569) (xy 150.176484 -18.804128)
			(xy 150.176022 -18.782557) (xy 150.168727 -18.740036) (xy 150.154358 -18.699356) (xy 150.133329 -18.661687)
			(xy 150.106242 -18.628107) (xy 150.073875 -18.599583) (xy 150.037158 -18.576931) (xy 149.997143 -18.560804)
			(xy 149.95498 -18.551662) (xy 149.911879 -18.54977) (xy 149.869078 -18.555181) (xy 149.848316 -18.56105)
			(xy 149.809528 -18.572334) (xy 149.73027 -18.587965) (xy 149.64984 -18.595533) (xy 149.569058 -18.594963)
			(xy 149.488743 -18.586259) (xy 149.409713 -18.56951) (xy 149.332772 -18.544887) (xy 149.258702 -18.51264)
			(xy 149.188257 -18.473097) (xy 149.122152 -18.426661) (xy 149.061061 -18.373802) (xy 149.005603 -18.315059)
			(xy 148.956344 -18.25103) (xy 148.913785 -18.182365) (xy 148.878357 -18.109763) (xy 148.850422 -18.033962)
			(xy 148.830263 -17.955732) (xy 148.818085 -17.875871) (xy 148.814013 -17.795188) (xy 148.818088 -17.714506)
			(xy 148.830268 -17.634645) (xy 148.850429 -17.556416) (xy 148.878366 -17.480616) (xy 148.913796 -17.408014)
			(xy 148.956358 -17.339351) (xy 149.005619 -17.275323) (xy 149.061078 -17.216582) (xy 149.122171 -17.163725)
			(xy 149.188277 -17.11729) (xy 149.258723 -17.077749) (xy 149.332794 -17.045505) (xy 149.409736 -17.020884)
			(xy 149.488766 -17.004138) (xy 149.569081 -16.995436) (xy 149.649864 -16.994868) (xy 149.730293 -17.002439)
			(xy 149.809551 -17.018071) (xy 149.848316 -17.02943) (xy 149.869086 -17.035294) (xy 149.911896 -17.040742)
			(xy 149.955011 -17.038878) (xy 149.99719 -17.029755) (xy 150.037222 -17.013635) (xy 150.073954 -16.990983)
			(xy 150.10633 -16.96245) (xy 150.133418 -16.928856) (xy 150.154441 -16.891167) (xy 150.168792 -16.850468)
			(xy 150.176059 -16.80793) (xy 150.176484 -16.786352) (xy 150.176484 -16.250666) (xy 150.176035 -16.228912)
			(xy 150.168621 -16.186041) (xy 150.154015 -16.145059) (xy 150.132644 -16.107162) (xy 150.105132 -16.073458)
			(xy 150.072282 -16.044931) (xy 150.035055 -16.022414) (xy 149.994537 -16.006565) (xy 149.951912 -15.997847)
			(xy 149.908425 -15.996514) (xy 149.865347 -16.002606) (xy 149.844506 -16.008858) (xy 149.807032 -16.020366)
			(xy 149.7303 -16.036435) (xy 149.652311 -16.044409) (xy 149.573915 -16.044202) (xy 149.495969 -16.035814)
			(xy 149.419323 -16.019338) (xy 149.344816 -15.994954) (xy 149.273259 -15.962928) (xy 149.205436 -15.92361)
			(xy 149.142085 -15.877429) (xy 149.0839 -15.824889) (xy 149.031515 -15.766564) (xy 148.985503 -15.703091)
			(xy 148.946365 -15.635163) (xy 148.91453 -15.563522) (xy 148.890344 -15.48895) (xy 148.874072 -15.412261)
			(xy 148.865892 -15.334293) (xy 148.865892 -15.255896) (xy 148.874074 -15.177928) (xy 148.890347 -15.10124)
			(xy 148.914533 -15.026668) (xy 148.94637 -14.955027) (xy 148.985509 -14.8871) (xy 149.031522 -14.823628)
			(xy 149.083908 -14.765303) (xy 149.142094 -14.712764) (xy 149.205445 -14.666584) (xy 149.273269 -14.627267)
			(xy 149.344826 -14.595242) (xy 149.419334 -14.570859) (xy 149.495979 -14.554384) (xy 149.573926 -14.545998)
			(xy 149.652322 -14.545791) (xy 149.730311 -14.553766) (xy 149.807043 -14.569836) (xy 149.844506 -14.581378)
			(xy 149.865348 -14.587635) (xy 149.908429 -14.593747) (xy 149.951922 -14.59243) (xy 149.994554 -14.583721)
			(xy 150.035079 -14.567875) (xy 150.072312 -14.545356) (xy 150.105162 -14.516822) (xy 150.132671 -14.483108)
			(xy 150.154033 -14.4452) (xy 150.168623 -14.404207) (xy 150.176016 -14.361327) (xy 150.176484 -14.33957)
			(xy 150.176484 -13.804138) (xy 150.176023 -13.782566) (xy 150.168729 -13.740044) (xy 150.154361 -13.699363)
			(xy 150.133332 -13.661691) (xy 150.106245 -13.628111) (xy 150.073878 -13.599585) (xy 150.03716 -13.576932)
			(xy 149.997144 -13.560804) (xy 149.95498 -13.551662) (xy 149.911878 -13.54977) (xy 149.869075 -13.555181)
			(xy 149.848316 -13.56106) (xy 149.809528 -13.572344) (xy 149.730269 -13.587975) (xy 149.649838 -13.595543)
			(xy 149.569054 -13.594972) (xy 149.488738 -13.586268) (xy 149.409708 -13.569519) (xy 149.332766 -13.544895)
			(xy 149.258695 -13.512648) (xy 149.188249 -13.473104) (xy 149.122144 -13.426666) (xy 149.061052 -13.373807)
			(xy 149.005594 -13.315063) (xy 148.956335 -13.251033) (xy 148.913775 -13.182367) (xy 148.878347 -13.109764)
			(xy 148.850412 -13.033962) (xy 148.830253 -12.955731) (xy 148.818076 -12.875869) (xy 148.814004 -12.795185)
			(xy 148.818079 -12.714502) (xy 148.830259 -12.63464) (xy 148.85042 -12.55641) (xy 148.878359 -12.480609)
			(xy 148.913789 -12.408007) (xy 148.956351 -12.339343) (xy 149.005613 -12.275314) (xy 149.061073 -12.216573)
			(xy 149.122167 -12.163716) (xy 149.188274 -12.11728) (xy 149.258722 -12.077739) (xy 149.332793 -12.045495)
			(xy 149.409736 -12.020874) (xy 149.488767 -12.004128) (xy 149.569083 -11.995426) (xy 149.649867 -11.994858)
			(xy 149.730297 -12.00243) (xy 149.809556 -12.018063) (xy 149.848316 -12.02944) (xy 149.869078 -12.035331)
			(xy 149.911888 -12.040782) (xy 149.955003 -12.038918) (xy 149.997183 -12.029794) (xy 150.037214 -12.013672)
			(xy 150.073944 -11.991016) (xy 150.106316 -11.962477) (xy 150.133398 -11.928878) (xy 150.154412 -11.891184)
			(xy 150.168752 -11.850481) (xy 150.176007 -11.80794) (xy 150.176484 -11.786362) (xy 150.176484 -8.185912)
			(xy 146.308826 -4.318508) (xy 142.281148 -4.318508) (xy 141.75232 -3.78968) (xy 141.730318 -3.766947)
			(xy 141.691805 -3.716755) (xy 141.660172 -3.661966) (xy 141.635961 -3.603516) (xy 141.619587 -3.542407)
			(xy 141.611329 -3.479683) (xy 141.611329 -3.416417) (xy 141.619587 -3.353693) (xy 141.635961 -3.292584)
			(xy 141.660172 -3.234134) (xy 141.691805 -3.179345) (xy 141.730318 -3.129153) (xy 141.775053 -3.084418)
			(xy 141.825245 -3.045905) (xy 141.880034 -3.014272) (xy 141.938484 -2.990061) (xy 141.999593 -2.973687)
			(xy 142.062317 -2.965429) (xy 142.125583 -2.965429) (xy 142.188307 -2.973687) (xy 142.249416 -2.990061)
			(xy 142.307866 -3.014272) (xy 142.362655 -3.045905) (xy 142.412847 -3.084418) (xy 142.43558 -3.10642)
			(xy 142.681452 -3.352292) (xy 146.70913 -3.352292) (xy 147.215606 -3.858768) (xy 147.231968 -3.874438)
			(xy 147.269164 -3.900294) (xy 147.310356 -3.919144) (xy 147.354239 -3.930389) (xy 147.39942 -3.933673)
			(xy 147.444467 -3.928892) (xy 147.487952 -3.916198) (xy 147.528496 -3.895993) (xy 147.564814 -3.868917)
			(xy 147.580604 -3.852672) (xy 147.603042 -3.829407) (xy 147.653068 -3.788476) (xy 147.708104 -3.75458)
			(xy 147.767168 -3.728324) (xy 147.829204 -3.710176) (xy 147.893107 -3.700461) (xy 147.957734 -3.699353)
			(xy 148.021932 -3.70687) (xy 148.084555 -3.722878) (xy 148.144484 -3.747093) (xy 148.200651 -3.779082)
			(xy 148.252051 -3.818272) (xy 148.275294 -3.840734) (xy 151.585422 -7.151116) (xy 151.602064 -7.167047)
			(xy 151.639977 -7.193211) (xy 151.681984 -7.212114) (xy 151.726711 -7.223136) (xy 151.772692 -7.225916)
			(xy 151.818421 -7.220363) (xy 151.8624 -7.20666) (xy 151.903189 -7.185253) (xy 151.939452 -7.156846)
			(xy 151.970001 -7.122368) (xy 151.993836 -7.082949) (xy 152.010176 -7.03988) (xy 152.018485 -6.99457)
			(xy 152.019 -6.971538) (xy 152.019 -2.2352) (xy 151.2824 -1.4986) (xy 146.812508 -1.4986) (xy 146.788934 -1.499116)
			(xy 146.742596 -1.507808) (xy 146.698654 -1.524897) (xy 146.658618 -1.549795) (xy 146.623859 -1.581649)
			(xy 146.59557 -1.619366) (xy 146.574722 -1.661653) (xy 146.562029 -1.707059) (xy 146.557927 -1.754028)
			(xy 146.562555 -1.800947) (xy 146.568668 -1.82372) (xy 146.575815 -1.849987) (xy 146.583453 -1.903884)
			(xy 146.583353 -1.95832) (xy 146.575516 -2.012189) (xy 146.560101 -2.064396) (xy 146.537421 -2.113882)
			(xy 146.507937 -2.159642) (xy 146.472248 -2.200746) (xy 146.431078 -2.236359) (xy 146.385264 -2.265758)
			(xy 146.335737 -2.288347) (xy 146.283501 -2.303666) (xy 146.229618 -2.311404) (xy 146.175182 -2.311404)
			(xy 146.121299 -2.303666) (xy 146.069063 -2.288347) (xy 146.019536 -2.265758) (xy 145.973722 -2.236359)
			(xy 145.932552 -2.200746) (xy 145.896863 -2.159642) (xy 145.867379 -2.113882) (xy 145.844699 -2.064396)
			(xy 145.829284 -2.012189) (xy 145.821447 -1.95832) (xy 145.821347 -1.903884) (xy 145.828985 -1.849987)
			(xy 145.836132 -1.82372) (xy 145.842237 -1.800946) (xy 145.846866 -1.754028) (xy 145.842764 -1.707061)
			(xy 145.830071 -1.661656) (xy 145.809223 -1.61937) (xy 145.780935 -1.581654) (xy 145.746178 -1.549801)
			(xy 145.706142 -1.524903) (xy 145.662202 -1.507815) (xy 145.615865 -1.499123) (xy 145.592292 -1.4986)
			(xy 145.585942 -1.4986) (xy 145.569284 -1.49909) (xy 145.5371 -1.507704) (xy 145.508243 -1.524356)
			(xy 145.484681 -1.54791) (xy 145.46802 -1.576761) (xy 145.459395 -1.608942) (xy 145.458942 -1.6256)
			(xy 145.458942 -1.6637) (xy 145.47977 -1.69545) (xy 145.494369 -1.718512) (xy 145.517539 -1.767932)
			(xy 145.533431 -1.820149) (xy 145.54172 -1.874097) (xy 145.542238 -1.928676) (xy 145.534973 -1.982772)
			(xy 145.520074 -2.03528) (xy 145.497845 -2.08513) (xy 145.46874 -2.131304) (xy 145.433352 -2.17286)
			(xy 145.392405 -2.208949) (xy 145.346732 -2.238835) (xy 145.297267 -2.261908) (xy 145.24502 -2.277697)
			(xy 145.191055 -2.28588) (xy 145.136475 -2.286291) (xy 145.082394 -2.27892) (xy 145.029914 -2.263918)
			(xy 144.980108 -2.241591) (xy 144.933992 -2.212395) (xy 144.892506 -2.176926) (xy 144.856497 -2.135907)
			(xy 144.826701 -2.090176) (xy 144.803725 -2.040666) (xy 144.788039 -1.988387) (xy 144.779961 -1.934407)
			(xy 144.779658 -1.879826) (xy 144.787135 -1.825759) (xy 144.80224 -1.773309) (xy 144.824665 -1.723547)
			(xy 144.838928 -1.700276) (xy 144.846926 -1.686823) (xy 144.856758 -1.65712) (xy 144.859062 -1.625917)
			(xy 144.853699 -1.595093) (xy 144.84099 -1.566502) (xy 144.821702 -1.541866) (xy 144.796996 -1.522669)
			(xy 144.768359 -1.510066) (xy 144.737515 -1.504816) (xy 144.70632 -1.507234) (xy 144.691354 -1.511808)
			(xy 144.67032 -1.519382) (xy 144.631101 -1.540834) (xy 144.596244 -1.56882) (xy 144.566824 -1.602477)
			(xy 144.543751 -1.640764) (xy 144.527736 -1.682499) (xy 144.519276 -1.726394) (xy 144.518631 -1.771091)
			(xy 144.521682 -1.79324) (xy 144.525604 -1.820502) (xy 144.526495 -1.875571) (xy 144.519459 -1.930197)
			(xy 144.504643 -1.983244) (xy 144.482354 -2.033609) (xy 144.453056 -2.080246) (xy 144.417357 -2.122187)
			(xy 144.375999 -2.15856) (xy 144.329841 -2.188609) (xy 144.279843 -2.211709) (xy 144.227043 -2.227381)
			(xy 144.172538 -2.2353) (xy 144.117462 -2.2353) (xy 144.062957 -2.227381) (xy 144.010157 -2.211709)
			(xy 143.960159 -2.188609) (xy 143.914001 -2.15856) (xy 143.872643 -2.122187) (xy 143.836944 -2.080246)
			(xy 143.807646 -2.033609) (xy 143.785357 -1.983244) (xy 143.770541 -1.930197) (xy 143.763505 -1.875571)
			(xy 143.764396 -1.820502) (xy 143.768318 -1.79324) (xy 143.771377 -1.771446) (xy 143.770829 -1.727444)
			(xy 143.762709 -1.684195) (xy 143.74726 -1.642991) (xy 143.724943 -1.605064) (xy 143.696425 -1.57155)
			(xy 143.662561 -1.543449) (xy 143.624361 -1.521603) (xy 143.582969 -1.506664) (xy 143.539623 -1.499079)
			(xy 143.51762 -1.4986) (xy 143.49349 -1.4986) (xy 143.476843 -1.499144) (xy 143.444683 -1.507764)
			(xy 143.415849 -1.524413) (xy 143.392307 -1.547957) (xy 143.37566 -1.576792) (xy 143.367043 -1.608952)
			(xy 143.36649 -1.6256) (xy 143.36649 -1.652016) (xy 143.377158 -1.6764) (xy 143.387904 -1.702302)
			(xy 143.402537 -1.756434) (xy 143.40909 -1.812126) (xy 143.407419 -1.868176) (xy 143.397562 -1.923379)
			(xy 143.37973 -1.976544) (xy 143.354309 -2.026526) (xy 143.321845 -2.072249) (xy 143.283037 -2.112727)
			(xy 143.238723 -2.147088) (xy 143.189856 -2.174593) (xy 143.13749 -2.194649) (xy 143.082751 -2.206823)
			(xy 143.026821 -2.210853) (xy 142.970903 -2.206653) (xy 142.916202 -2.194313) (xy 142.863896 -2.174099)
			(xy 142.815113 -2.146446) (xy 142.770903 -2.11195) (xy 142.732219 -2.071355) (xy 142.699893 -2.025534)
			(xy 142.674623 -1.975475) (xy 142.656953 -1.922256) (xy 142.647263 -1.867024) (xy 142.645763 -1.810968)
			(xy 142.648686 -1.78308) (xy 142.650819 -1.761691) (xy 142.64872 -1.718761) (xy 142.639424 -1.676797)
			(xy 142.623196 -1.636997) (xy 142.600498 -1.600497) (xy 142.57198 -1.56834) (xy 142.538454 -1.541443)
			(xy 142.500879 -1.520575) (xy 142.460327 -1.506331) (xy 142.417955 -1.499117) (xy 142.396464 -1.4986)
			(xy 130.7846 -1.4986) (xy 129.6924 -2.5908) (xy 129.6924 -3.478973) (xy 131.902215 -3.478973) (xy 131.909822 -3.4251)
			(xy 131.925009 -3.372854) (xy 131.947466 -3.323296) (xy 131.976737 -3.277433) (xy 132.012229 -3.236195)
			(xy 132.053221 -3.200419) (xy 132.098881 -3.170831) (xy 132.148282 -3.148033) (xy 132.200421 -3.132485)
			(xy 132.254241 -3.124506) (xy 132.308649 -3.124255) (xy 132.36254 -3.131739) (xy 132.414821 -3.146805)
			(xy 132.46443 -3.169147) (xy 132.510361 -3.198313) (xy 132.55168 -3.23371) (xy 132.587551 -3.274619)
			(xy 132.617243 -3.320211) (xy 132.640156 -3.369559) (xy 132.648452 -3.395472) (xy 132.655917 -3.418267)
			(xy 132.67813 -3.460773) (xy 132.707913 -3.498364) (xy 132.744212 -3.52971) (xy 132.78574 -3.553701)
			(xy 132.831027 -3.569487) (xy 132.87847 -3.576509) (xy 132.902452 -3.576066) (xy 132.921693 -3.575503)
			(xy 132.960121 -3.577798) (xy 132.97916 -3.580638) (xy 132.995808 -3.582732) (xy 133.029167 -3.57927)
			(xy 133.060478 -3.567253) (xy 133.087589 -3.54751) (xy 133.108634 -3.521397) (xy 133.122166 -3.49071)
			(xy 133.12521 -3.474212) (xy 133.129744 -3.447112) (xy 133.145581 -3.3945) (xy 133.168805 -3.344705)
			(xy 133.198933 -3.298758) (xy 133.235343 -3.25761) (xy 133.277282 -3.222112) (xy 133.32388 -3.193)
			(xy 133.374173 -3.170877) (xy 133.427121 -3.156199) (xy 133.481627 -3.149272) (xy 133.536562 -3.150237)
			(xy 133.590791 -3.159076) (xy 133.64319 -3.175606) (xy 133.692675 -3.199483) (xy 133.738221 -3.230215)
			(xy 133.778886 -3.267164) (xy 133.813827 -3.309566) (xy 133.842323 -3.356544) (xy 133.863782 -3.407124)
			(xy 133.87776 -3.460261) (xy 133.883969 -3.514853) (xy 133.88228 -3.569772) (xy 133.872727 -3.623879)
			(xy 133.855508 -3.676056) (xy 133.830981 -3.725222) (xy 133.799652 -3.770359) (xy 133.76217 -3.810533)
			(xy 133.719311 -3.844913) (xy 133.671962 -3.872787) (xy 133.621103 -3.893577) (xy 133.567787 -3.906855)
			(xy 133.5405 -3.910076) (xy 133.525048 -3.912181) (xy 133.495725 -3.92276) (xy 133.469839 -3.940127)
			(xy 133.448932 -3.963249) (xy 133.434249 -3.990746) (xy 133.426665 -4.020982) (xy 133.4262 -4.036568)
			(xy 133.4262 -5.283454) (xy 133.491732 -5.355844) (xy 133.5405 -5.360924) (xy 133.567936 -5.364185)
			(xy 133.621535 -5.377589) (xy 133.67264 -5.398586) (xy 133.720181 -5.426734) (xy 133.763164 -5.461446)
			(xy 133.800691 -5.501996) (xy 133.831975 -5.547535) (xy 133.856363 -5.597111) (xy 133.873344 -5.649686)
			(xy 133.882564 -5.704161) (xy 133.883828 -5.759396) (xy 133.877112 -5.814236) (xy 133.862555 -5.867533)
			(xy 133.840462 -5.918173) (xy 133.811294 -5.965096) (xy 133.775663 -6.007321) (xy 133.734314 -6.043964)
			(xy 133.688111 -6.074259) (xy 133.638021 -6.097573) (xy 133.585092 -6.113416) (xy 133.530431 -6.121459)
			(xy 133.475181 -6.121532) (xy 133.420499 -6.113635) (xy 133.367528 -6.097932) (xy 133.317376 -6.074752)
			(xy 133.271093 -6.044579) (xy 133.229646 -6.008046) (xy 133.193903 -5.965916) (xy 133.164611 -5.91907)
			(xy 133.142384 -5.868489) (xy 133.127685 -5.815231) (xy 133.120823 -5.760409) (xy 133.120892 -5.73278)
			(xy 133.120691 -5.716968) (xy 133.113543 -5.686177) (xy 133.099044 -5.658089) (xy 133.078085 -5.634427)
			(xy 133.051952 -5.616645) (xy 133.022249 -5.605833) (xy 132.990799 -5.602656) (xy 132.975096 -5.60451)
			(xy 132.962219 -5.606372) (xy 132.936288 -5.608531) (xy 132.92328 -5.608828) (xy 132.899284 -5.609691)
			(xy 132.852257 -5.619368) (xy 132.807881 -5.637695) (xy 132.76773 -5.664021) (xy 132.73323 -5.697411)
			(xy 132.705606 -5.736679) (xy 132.685839 -5.780433) (xy 132.679694 -5.803646) (xy 132.672853 -5.830036)
			(xy 132.652767 -5.880717) (xy 132.625672 -5.928022) (xy 132.592119 -5.970988) (xy 132.552792 -6.008741)
			(xy 132.50849 -6.040511) (xy 132.460117 -6.06565) (xy 132.408659 -6.083648) (xy 132.355162 -6.094138)
			(xy 132.300717 -6.096905) (xy 132.246432 -6.091893) (xy 132.193414 -6.079205) (xy 132.142742 -6.059099)
			(xy 132.095448 -6.031985) (xy 132.052495 -5.998414) (xy 132.014759 -5.959071) (xy 131.983007 -5.914756)
			(xy 131.957887 -5.866373) (xy 131.939911 -5.814907) (xy 131.929443 -5.761406) (xy 131.926699 -5.70696)
			(xy 131.931732 -5.652678) (xy 131.944442 -5.599664) (xy 131.964569 -5.549001) (xy 131.991703 -5.501718)
			(xy 132.025291 -5.458779) (xy 132.06465 -5.421059) (xy 132.108977 -5.389325) (xy 132.157371 -5.364225)
			(xy 132.208844 -5.34627) (xy 132.262349 -5.335824) (xy 132.28955 -5.334) (xy 132.305642 -5.33269)
			(xy 132.336449 -5.323072) (xy 132.363849 -5.306019) (xy 132.386081 -5.282625) (xy 132.40172 -5.254394)
			(xy 132.409759 -5.223138) (xy 132.4102 -5.207) (xy 132.4102 -4.013708) (xy 132.409698 -3.997054)
			(xy 132.401079 -3.964879) (xy 132.384426 -3.936032) (xy 132.360874 -3.912479) (xy 132.332028 -3.895824)
			(xy 132.299854 -3.887203) (xy 132.2832 -3.886708) (xy 132.255996 -3.886224) (xy 132.20214 -3.878492)
			(xy 132.149929 -3.863185) (xy 132.100423 -3.840614) (xy 132.054628 -3.811237) (xy 132.013471 -3.775651)
			(xy 131.97779 -3.734576) (xy 131.948308 -3.688848) (xy 131.925623 -3.639395) (xy 131.910196 -3.58722)
			(xy 131.90234 -3.533381) (xy 131.902215 -3.478973) (xy 129.6924 -3.478973) (xy 129.6924 -6.198215)
			(xy 143.635908 -6.198215) (xy 143.639968 -6.142047) (xy 143.652239 -6.087086) (xy 143.672455 -6.034526)
			(xy 143.700176 -5.985508) (xy 143.734802 -5.941097) (xy 143.775579 -5.902258) (xy 143.821622 -5.869834)
			(xy 143.84655 -5.856732) (xy 143.862001 -5.848385) (xy 143.887885 -5.824669) (xy 143.906304 -5.794783)
			(xy 143.915856 -5.761002) (xy 143.9164 -5.743448) (xy 143.9164 -5.647436) (xy 143.915876 -5.630783)
			(xy 143.907264 -5.598611) (xy 143.890618 -5.569765) (xy 143.867073 -5.546211) (xy 143.8529 -5.537454)
			(xy 143.829066 -5.523096) (xy 143.785411 -5.488599) (xy 143.747233 -5.448125) (xy 143.715341 -5.402533)
			(xy 143.690411 -5.352791) (xy 143.672974 -5.299954) (xy 143.663399 -5.245145) (xy 143.661889 -5.189526)
			(xy 143.668476 -5.134278) (xy 143.683022 -5.080573) (xy 143.705216 -5.029552) (xy 143.734588 -4.982297)
			(xy 143.770515 -4.939811) (xy 143.812233 -4.902997) (xy 143.858858 -4.872634) (xy 143.9094 -4.849369)
			(xy 143.962786 -4.833694) (xy 144.017882 -4.825942) (xy 144.073521 -4.826278) (xy 144.12852 -4.834695)
			(xy 144.181713 -4.851014) (xy 144.231969 -4.874889) (xy 144.278224 -4.905813) (xy 144.319494 -4.943129)
			(xy 144.354905 -4.986046) (xy 144.383704 -5.033652) (xy 144.40528 -5.084938) (xy 144.412716 -5.11175)
			(xy 144.423638 -5.153914) (xy 144.492218 -5.207) (xy 145.81251 -5.207) (xy 145.827241 -5.206547)
			(xy 145.85591 -5.19976) (xy 145.882257 -5.186575) (xy 145.904875 -5.167696) (xy 145.922556 -5.144129)
			(xy 145.928842 -5.1308) (xy 145.940505 -5.105225) (xy 145.970276 -5.057547) (xy 146.006719 -5.014753)
			(xy 146.049047 -4.977768) (xy 146.096343 -4.947394) (xy 146.147584 -4.924288) (xy 146.20166 -4.90895)
			(xy 146.257401 -4.901711) (xy 146.313601 -4.902729) (xy 146.369044 -4.911982) (xy 146.422529 -4.929269)
			(xy 146.472899 -4.954215) (xy 146.519064 -4.986282) (xy 146.560025 -5.024776) (xy 146.594895 -5.068862)
			(xy 146.622919 -5.117587) (xy 146.643491 -5.169896) (xy 146.656166 -5.224658) (xy 146.660669 -5.280687)
			(xy 146.656903 -5.33677) (xy 146.64495 -5.391694) (xy 146.625068 -5.444269) (xy 146.597687 -5.493359)
			(xy 146.5634 -5.5379) (xy 146.543522 -5.557774) (xy 146.528051 -5.573266) (xy 146.502217 -5.608613)
			(xy 146.482821 -5.647863) (xy 146.470437 -5.689856) (xy 146.465432 -5.73335) (xy 146.467953 -5.777058)
			(xy 146.477925 -5.819688) (xy 146.495055 -5.859979) (xy 146.518835 -5.896738) (xy 146.533362 -5.91312)
			(xy 146.551536 -5.933378) (xy 146.582427 -5.978187) (xy 146.606638 -6.02693) (xy 146.623678 -6.078619)
			(xy 146.633201 -6.132204) (xy 146.635015 -6.186599) (xy 146.629081 -6.240699) (xy 146.615522 -6.293408)
			(xy 146.594611 -6.343655) (xy 146.566773 -6.390422) (xy 146.532573 -6.432759) (xy 146.492705 -6.469808)
			(xy 146.447978 -6.500816) (xy 146.399298 -6.525155) (xy 146.347655 -6.542331) (xy 146.294095 -6.551995)
			(xy 146.239705 -6.553952) (xy 146.185589 -6.54816) (xy 146.132845 -6.534739) (xy 146.082542 -6.513961)
			(xy 146.035703 -6.486246) (xy 145.993276 -6.452157) (xy 145.956122 -6.412387) (xy 145.924997 -6.367741)
			(xy 145.912332 -6.34365) (xy 145.903985 -6.328199) (xy 145.880269 -6.302315) (xy 145.850383 -6.283896)
			(xy 145.816602 -6.274344) (xy 145.799048 -6.2738) (xy 144.48409 -6.2738) (xy 144.469359 -6.274253)
			(xy 144.44069 -6.28104) (xy 144.414343 -6.294225) (xy 144.391725 -6.313104) (xy 144.374044 -6.336671)
			(xy 144.367758 -6.35) (xy 144.356084 -6.375627) (xy 144.326245 -6.423386) (xy 144.289711 -6.466241)
			(xy 144.247275 -6.50326) (xy 144.199858 -6.533639) (xy 144.148491 -6.556719) (xy 144.09429 -6.571999)
			(xy 144.038431 -6.579146) (xy 143.982129 -6.578005) (xy 143.926605 -6.568601) (xy 143.873067 -6.551138)
			(xy 143.822678 -6.525996) (xy 143.776531 -6.49372) (xy 143.735629 -6.455012) (xy 143.700861 -6.410713)
			(xy 143.672981 -6.361785) (xy 143.652596 -6.30929) (xy 143.640148 -6.254369) (xy 143.635908 -6.198215)
			(xy 129.6924 -6.198215) (xy 129.6924 -8.195056) (xy 136.884166 -8.195056) (xy 136.888147 -8.115292)
			(xy 136.90005 -8.03632) (xy 136.919757 -7.958926) (xy 136.947072 -7.883879) (xy 136.981723 -7.811924)
			(xy 137.023367 -7.743777) (xy 137.071589 -7.680115) (xy 137.12591 -7.621571) (xy 137.185791 -7.568726)
			(xy 137.250635 -7.522106) (xy 137.319799 -7.482174) (xy 137.392595 -7.449327) (xy 137.4683 -7.423892)
			(xy 137.546161 -7.406121) (xy 137.625405 -7.39619) (xy 137.705244 -7.394199) (xy 137.784884 -7.400167)
			(xy 137.863535 -7.414035) (xy 137.940414 -7.435666) (xy 138.014757 -7.464843) (xy 138.085825 -7.501278)
			(xy 138.152913 -7.544608) (xy 138.215352 -7.594402) (xy 138.272524 -7.650166) (xy 138.32386 -7.711345)
			(xy 138.368848 -7.777331) (xy 138.407044 -7.847469) (xy 138.438065 -7.921062) (xy 138.461606 -7.997377)
			(xy 138.47743 -8.075657) (xy 138.485382 -8.155124) (xy 138.48588 -8.195056) (xy 138.485382 -8.234988)
			(xy 138.47743 -8.314455) (xy 138.461606 -8.392735) (xy 138.438065 -8.46905) (xy 138.407044 -8.542643)
			(xy 138.368848 -8.612781) (xy 138.32386 -8.678767) (xy 138.272524 -8.739946) (xy 138.215352 -8.79571)
			(xy 138.152913 -8.845504) (xy 138.094212 -8.883417) (xy 138.708048 -8.883417) (xy 138.712928 -8.828774)
			(xy 138.725583 -8.775393) (xy 138.745752 -8.724374) (xy 138.773019 -8.67677) (xy 138.806822 -8.633561)
			(xy 138.846465 -8.595638) (xy 138.891129 -8.563782) (xy 138.939895 -8.538651) (xy 138.991758 -8.520763)
			(xy 139.045647 -8.510486) (xy 139.100452 -8.508031) (xy 139.155045 -8.513451) (xy 139.208298 -8.526632)
			(xy 139.259115 -8.547303) (xy 139.306448 -8.575039) (xy 139.349322 -8.609266) (xy 139.386852 -8.649281)
			(xy 139.418265 -8.694258) (xy 139.431014 -8.71855) (xy 139.44727 -8.750808) (xy 139.50823 -8.7884)
			(xy 141.034516 -8.7884) (xy 141.095476 -8.750808) (xy 141.111732 -8.71855) (xy 141.125371 -8.692673)
			(xy 141.159355 -8.645065) (xy 141.200203 -8.603197) (xy 141.246958 -8.568048) (xy 141.298527 -8.540441)
			(xy 141.353703 -8.521022) (xy 141.411194 -8.510245) (xy 141.440408 -8.508746) (xy 141.462893 -8.507484)
			(xy 141.506928 -8.498078) (xy 141.54862 -8.481067) (xy 141.586666 -8.456981) (xy 141.619878 -8.426574)
			(xy 141.647218 -8.390795) (xy 141.667831 -8.350762) (xy 141.681076 -8.307725) (xy 141.686537 -8.263029)
			(xy 141.685772 -8.240522) (xy 141.684034 -8.200238) (xy 141.687565 -8.119681) (xy 141.699175 -8.039887)
			(xy 141.718748 -7.961664) (xy 141.746084 -7.885804) (xy 141.780906 -7.813077) (xy 141.822863 -7.744218)
			(xy 141.871528 -7.679925) (xy 141.92641 -7.620849) (xy 141.986952 -7.56759) (xy 142.052541 -7.520685)
			(xy 142.122512 -7.480611) (xy 142.196157 -7.447772) (xy 142.27273 -7.422503) (xy 142.351455 -7.405059)
			(xy 142.431534 -7.395616) (xy 142.512157 -7.39427) (xy 142.592508 -7.401035) (xy 142.671771 -7.415843)
			(xy 142.749144 -7.438542) (xy 142.823844 -7.468904) (xy 142.895114 -7.506621) (xy 142.962231 -7.551311)
			(xy 143.024517 -7.60252) (xy 143.08134 -7.659731) (xy 143.132124 -7.722364) (xy 143.176355 -7.789785)
			(xy 143.213586 -7.86131) (xy 143.243438 -7.936215) (xy 143.26561 -8.013741) (xy 143.279877 -8.093103)
			(xy 143.286095 -8.173498) (xy 143.2842 -8.25411) (xy 143.274212 -8.334123) (xy 143.256232 -8.412728)
			(xy 143.230441 -8.489126) (xy 143.197102 -8.562546) (xy 143.17726 -8.597646) (xy 143.159988 -8.62711)
			(xy 143.159988 -8.6614) (xy 143.160543 -8.678047) (xy 143.16916 -8.710208) (xy 143.185806 -8.739042)
			(xy 143.209348 -8.762586) (xy 143.238181 -8.779236) (xy 143.270341 -8.787855) (xy 143.286988 -8.7884)
			(xy 143.472154 -8.7884) (xy 143.533114 -8.750808) (xy 143.54937 -8.71855) (xy 143.562451 -8.693657)
			(xy 143.594818 -8.647674) (xy 143.633584 -8.60694) (xy 143.677908 -8.572336) (xy 143.726831 -8.544613)
			(xy 143.779293 -8.52437) (xy 143.834158 -8.512046) (xy 143.890238 -8.507908) (xy 143.946318 -8.512046)
			(xy 144.001183 -8.52437) (xy 144.053645 -8.544613) (xy 144.102568 -8.572336) (xy 144.146892 -8.60694)
			(xy 144.185658 -8.647674) (xy 144.218025 -8.693657) (xy 144.231106 -8.71855) (xy 144.247362 -8.750808)
			(xy 144.308322 -8.7884) (xy 145.835116 -8.7884) (xy 145.896076 -8.750808) (xy 145.912332 -8.71855)
			(xy 145.925954 -8.692684) (xy 145.959914 -8.645101) (xy 146.000729 -8.603251) (xy 146.047447 -8.56811)
			(xy 146.098974 -8.5405) (xy 146.154108 -8.521066) (xy 146.211559 -8.510263) (xy 146.240754 -8.508746)
			(xy 146.263237 -8.507514) (xy 146.30727 -8.498123) (xy 146.348957 -8.481117) (xy 146.386994 -8.457027)
			(xy 146.420188 -8.42661) (xy 146.4475 -8.390817) (xy 146.468075 -8.35077) (xy 146.481267 -8.307723)
			(xy 146.486664 -8.263025) (xy 146.485864 -8.240522) (xy 146.484063 -8.201064) (xy 146.48737 -8.12214)
			(xy 146.498435 -8.043926) (xy 146.517149 -7.967181) (xy 146.54333 -7.892653) (xy 146.576725 -7.821066)
			(xy 146.617008 -7.753116) (xy 146.663788 -7.689464) (xy 146.716609 -7.630729) (xy 146.774959 -7.577482)
			(xy 146.838269 -7.530241) (xy 146.905924 -7.489464) (xy 146.977266 -7.45555) (xy 147.051602 -7.428827)
			(xy 147.128208 -7.409555) (xy 147.20634 -7.397922) (xy 147.285238 -7.394041) (xy 147.364134 -7.397949)
			(xy 147.442262 -7.409609) (xy 147.518862 -7.428907) (xy 147.593188 -7.455656) (xy 147.664519 -7.489595)
			(xy 147.73216 -7.530394) (xy 147.795454 -7.577657) (xy 147.853785 -7.630925) (xy 147.906586 -7.689678)
			(xy 147.953344 -7.753346) (xy 147.993603 -7.82131) (xy 148.026974 -7.892908) (xy 148.05313 -7.967445)
			(xy 148.071817 -8.044196) (xy 148.082855 -8.122415) (xy 148.086135 -8.20134) (xy 148.081626 -8.280204)
			(xy 148.069371 -8.358241) (xy 148.04949 -8.434691) (xy 148.03628 -8.471916) (xy 148.028659 -8.494126)
			(xy 148.020826 -8.540418) (xy 148.02162 -8.587362) (xy 148.031014 -8.633364) (xy 148.048689 -8.676861)
			(xy 148.074044 -8.716376) (xy 148.10622 -8.750568) (xy 148.144123 -8.778276) (xy 148.186467 -8.798559)
			(xy 148.209 -8.805164) (xy 148.209 -11.3792) (xy 147.7772 -11.3792) (xy 147.760552 -11.379743) (xy 147.728389 -11.388361)
			(xy 147.699554 -11.405009) (xy 147.676009 -11.428554) (xy 147.659361 -11.457389) (xy 147.650743 -11.489552)
			(xy 147.6502 -11.5062) (xy 147.6502 -12.0396) (xy 146.483578 -12.0396) (xy 146.457162 -12.0523) (xy 146.431033 -12.06443)
			(xy 146.376035 -12.081561) (xy 146.319086 -12.090224) (xy 146.261482 -12.090224) (xy 146.204533 -12.081561)
			(xy 146.149535 -12.06443) (xy 146.123406 -12.0523) (xy 146.09699 -12.0396) (xy 144.083532 -12.0396)
			(xy 144.057116 -12.0523) (xy 144.032575 -12.063686) (xy 143.981083 -12.080273) (xy 143.927765 -12.08942)
			(xy 143.873689 -12.090943) (xy 143.81994 -12.084811) (xy 143.767596 -12.071149) (xy 143.717707 -12.050229)
			(xy 143.671274 -12.022471) (xy 143.649954 -12.005818) (xy 143.63288 -11.992556) (xy 143.59516 -11.971437)
			(xy 143.554409 -11.95701) (xy 143.511803 -11.949691) (xy 143.468573 -11.949691) (xy 143.425967 -11.95701)
			(xy 143.385216 -11.971437) (xy 143.347496 -11.992556) (xy 143.330422 -12.005818) (xy 143.307656 -12.023599)
			(xy 143.257818 -12.052805) (xy 143.204145 -12.074157) (xy 143.147864 -12.087167) (xy 143.090265 -12.091537)
			(xy 143.032666 -12.087167) (xy 142.976385 -12.074157) (xy 142.922712 -12.052805) (xy 142.872874 -12.023599)
			(xy 142.850108 -12.005818) (xy 142.833031 -11.992522) (xy 142.79529 -11.971344) (xy 142.754503 -11.956875)
			(xy 142.711853 -11.949534) (xy 142.668577 -11.949534) (xy 142.625927 -11.956875) (xy 142.58514 -11.971344)
			(xy 142.547399 -11.992522) (xy 142.530322 -12.005818) (xy 142.509267 -12.02232) (xy 142.463419 -12.04988)
			(xy 142.414168 -12.070758) (xy 142.362482 -12.084546) (xy 142.309375 -12.090971) (xy 142.255892 -12.089908)
			(xy 142.203082 -12.081377) (xy 142.151984 -12.065546) (xy 142.103602 -12.042727) (xy 142.080996 -12.028424)
			(xy 142.049246 -12.007596) (xy 141.941804 -12.007596) (xy 141.8844 -12.065) (xy 141.629892 -12.065)
			(xy 141.610334 -12.07135) (xy 141.581127 -12.080407) (xy 141.520765 -12.090163) (xy 141.459619 -12.090163)
			(xy 141.399257 -12.080407) (xy 141.37005 -12.07135) (xy 141.350492 -12.065) (xy 139.229846 -12.065)
			(xy 139.210288 -12.07135) (xy 139.181081 -12.080407) (xy 139.120719 -12.090163) (xy 139.059573 -12.090163)
			(xy 138.999211 -12.080407) (xy 138.970004 -12.07135) (xy 138.950446 -12.065) (xy 138.7094 -12.065)
			(xy 138.7094 -11.733784) (xy 138.709146 -11.730228) (xy 138.708648 -11.71982) (xy 138.708648 -11.69898)
			(xy 138.709146 -11.688572) (xy 138.7094 -11.685016) (xy 138.7094 -8.914384) (xy 138.709146 -8.910828)
			(xy 138.708048 -8.883417) (xy 138.094212 -8.883417) (xy 138.085825 -8.888834) (xy 138.014757 -8.925269)
			(xy 137.940414 -8.954446) (xy 137.863535 -8.976077) (xy 137.784884 -8.989945) (xy 137.705244 -8.995913)
			(xy 137.625405 -8.993922) (xy 137.546161 -8.983991) (xy 137.4683 -8.96622) (xy 137.392595 -8.940785)
			(xy 137.319799 -8.907938) (xy 137.250635 -8.868006) (xy 137.185791 -8.821386) (xy 137.12591 -8.768541)
			(xy 137.071589 -8.709997) (xy 137.023367 -8.646335) (xy 136.981723 -8.578188) (xy 136.947072 -8.506233)
			(xy 136.919757 -8.431186) (xy 136.90005 -8.353792) (xy 136.888147 -8.27482) (xy 136.884166 -8.195056)
			(xy 129.6924 -8.195056) (xy 129.6924 -10.295128) (xy 134.462532 -10.295128) (xy 134.466498 -10.210597)
			(xy 134.478363 -10.12681) (xy 134.498021 -10.044501) (xy 134.525301 -9.964395) (xy 134.559962 -9.887196)
			(xy 134.6017 -9.813581) (xy 134.650147 -9.744198) (xy 134.704879 -9.679657) (xy 134.765415 -9.620525)
			(xy 134.831221 -9.567321) (xy 134.901721 -9.520513) (xy 134.976293 -9.480512) (xy 135.054284 -9.44767)
			(xy 135.135008 -9.422276) (xy 135.217755 -9.404553) (xy 135.301797 -9.394655) (xy 135.386398 -9.392672)
			(xy 135.470812 -9.398619) (xy 135.554299 -9.412444) (xy 135.636124 -9.434027) (xy 135.715568 -9.463177)
			(xy 135.791934 -9.499638) (xy 135.86455 -9.54309) (xy 135.932778 -9.593151) (xy 135.996018 -9.649381)
			(xy 136.053715 -9.711286) (xy 136.105362 -9.778322) (xy 136.150504 -9.849899) (xy 136.188746 -9.925389)
			(xy 136.21975 -10.004128) (xy 136.243245 -10.085425) (xy 136.259024 -10.168564) (xy 136.266948 -10.252816)
			(xy 136.267444 -10.295128) (xy 136.266948 -10.33744) (xy 136.259024 -10.421692) (xy 136.243245 -10.504831)
			(xy 136.21975 -10.586128) (xy 136.188746 -10.664867) (xy 136.150504 -10.740357) (xy 136.105362 -10.811934)
			(xy 136.053715 -10.87897) (xy 135.996018 -10.940875) (xy 135.932778 -10.997105) (xy 135.86455 -11.047166)
			(xy 135.791934 -11.090618) (xy 135.715568 -11.127079) (xy 135.636124 -11.156229) (xy 135.554299 -11.177812)
			(xy 135.470812 -11.191637) (xy 135.386398 -11.197584) (xy 135.301797 -11.195601) (xy 135.217755 -11.185703)
			(xy 135.135008 -11.16798) (xy 135.054284 -11.142586) (xy 134.976293 -11.109744) (xy 134.901721 -11.069743)
			(xy 134.831221 -11.022935) (xy 134.765415 -10.969731) (xy 134.704879 -10.910599) (xy 134.650147 -10.846058)
			(xy 134.6017 -10.776675) (xy 134.559962 -10.70306) (xy 134.525301 -10.625861) (xy 134.498021 -10.545755)
			(xy 134.478363 -10.463446) (xy 134.466498 -10.379659) (xy 134.462532 -10.295128) (xy 129.6924 -10.295128)
			(xy 129.6924 -12.79525) (xy 134.56413 -12.79525) (xy 134.568111 -12.715486) (xy 134.580014 -12.636514)
			(xy 134.599721 -12.55912) (xy 134.627036 -12.484073) (xy 134.661687 -12.412118) (xy 134.703331 -12.343971)
			(xy 134.751553 -12.280309) (xy 134.805874 -12.221765) (xy 134.865755 -12.16892) (xy 134.930599 -12.1223)
			(xy 134.999763 -12.082368) (xy 135.072559 -12.049521) (xy 135.148264 -12.024086) (xy 135.226125 -12.006315)
			(xy 135.305369 -11.996384) (xy 135.385208 -11.994393) (xy 135.464848 -12.000361) (xy 135.543499 -12.014229)
			(xy 135.620378 -12.03586) (xy 135.694721 -12.065037) (xy 135.765789 -12.101472) (xy 135.832877 -12.144802)
			(xy 135.895316 -12.194596) (xy 135.952488 -12.25036) (xy 136.003824 -12.311539) (xy 136.048812 -12.377525)
			(xy 136.087008 -12.447663) (xy 136.118029 -12.521256) (xy 136.14157 -12.597571) (xy 136.157394 -12.675851)
			(xy 136.165346 -12.755318) (xy 136.165844 -12.79525) (xy 136.165346 -12.835182) (xy 136.157394 -12.914649)
			(xy 136.14157 -12.992929) (xy 136.118029 -13.069244) (xy 136.087008 -13.142837) (xy 136.048812 -13.212975)
			(xy 136.003824 -13.278961) (xy 135.952488 -13.34014) (xy 135.895316 -13.395904) (xy 135.832877 -13.445698)
			(xy 135.765789 -13.489028) (xy 135.694721 -13.525463) (xy 135.620378 -13.55464) (xy 135.543499 -13.576271)
			(xy 135.464848 -13.590139) (xy 135.385208 -13.596107) (xy 135.305369 -13.594116) (xy 135.226125 -13.584185)
			(xy 135.148264 -13.566414) (xy 135.072559 -13.540979) (xy 134.999763 -13.508132) (xy 134.930599 -13.4682)
			(xy 134.865755 -13.42158) (xy 134.805874 -13.368735) (xy 134.751553 -13.310191) (xy 134.703331 -13.246529)
			(xy 134.661687 -13.178382) (xy 134.627036 -13.106427) (xy 134.599721 -13.03138) (xy 134.580014 -12.953986)
			(xy 134.568111 -12.875014) (xy 134.56413 -12.79525) (xy 129.6924 -12.79525) (xy 129.6924 -14.439259)
			(xy 136.470123 -14.439259) (xy 136.470123 -14.340973) (xy 136.478032 -14.243006) (xy 136.493798 -14.145993)
			(xy 136.517319 -14.050564) (xy 136.548443 -13.957336) (xy 136.586968 -13.866915) (xy 136.632643 -13.779888)
			(xy 136.685174 -13.696817) (xy 136.744218 -13.618244) (xy 136.809393 -13.544676) (xy 136.880277 -13.476591)
			(xy 136.95641 -13.41443) (xy 137.037297 -13.358598) (xy 137.122415 -13.309455) (xy 137.211212 -13.267321)
			(xy 137.30311 -13.232468) (xy 137.397516 -13.205123) (xy 137.493815 -13.185464) (xy 137.591384 -13.173617)
			(xy 137.68959 -13.169659) (xy 137.787796 -13.173617) (xy 137.885365 -13.185464) (xy 137.981664 -13.205123)
			(xy 138.07607 -13.232468) (xy 138.167968 -13.267321) (xy 138.256765 -13.309455) (xy 138.341883 -13.358598)
			(xy 138.42277 -13.41443) (xy 138.498903 -13.476591) (xy 138.569787 -13.544676) (xy 138.634962 -13.618244)
			(xy 138.694006 -13.696817) (xy 138.746537 -13.779888) (xy 138.792212 -13.866915) (xy 138.830737 -13.957336)
			(xy 138.861861 -14.050564) (xy 138.885382 -14.145993) (xy 138.901148 -14.243006) (xy 138.909057 -14.340973)
			(xy 138.909552 -14.390116) (xy 138.909057 -14.439259) (xy 138.901148 -14.537226) (xy 138.885382 -14.634239)
			(xy 138.861861 -14.729668) (xy 138.856503 -14.745716) (xy 146.401028 -14.745716) (xy 146.401028 -14.059916)
			(xy 146.401532 -14.017555) (xy 146.409585 -13.933218) (xy 146.425619 -13.850028) (xy 146.449487 -13.768738)
			(xy 146.480975 -13.690086) (xy 146.519797 -13.614783) (xy 146.5656 -13.543511) (xy 146.617971 -13.476915)
			(xy 146.676436 -13.4156) (xy 146.740464 -13.360119) (xy 146.809476 -13.310976) (xy 146.882846 -13.268616)
			(xy 146.959911 -13.233421) (xy 147.039973 -13.205712) (xy 147.122306 -13.185738) (xy 147.206165 -13.173681)
			(xy 147.29079 -13.16965) (xy 147.375415 -13.173681) (xy 147.459274 -13.185738) (xy 147.541607 -13.205712)
			(xy 147.621669 -13.233421) (xy 147.698734 -13.268616) (xy 147.772104 -13.310976) (xy 147.841116 -13.360119)
			(xy 147.905144 -13.4156) (xy 147.963609 -13.476915) (xy 148.01598 -13.543511) (xy 148.061783 -13.614783)
			(xy 148.100605 -13.690086) (xy 148.132093 -13.768738) (xy 148.155961 -13.850028) (xy 148.171995 -13.933218)
			(xy 148.180048 -14.017555) (xy 148.180552 -14.059916) (xy 148.180552 -14.694916) (xy 148.18005 -14.737199)
			(xy 148.172244 -14.821405) (xy 148.156702 -14.904531) (xy 148.133555 -14.985868) (xy 148.103 -15.064722)
			(xy 148.0653 -15.14042) (xy 148.020774 -15.212316) (xy 147.969805 -15.279796) (xy 147.912825 -15.342285)
			(xy 147.850322 -15.399249) (xy 147.782829 -15.450202) (xy 147.710922 -15.49471) (xy 147.635215 -15.532392)
			(xy 147.556354 -15.562926) (xy 147.475011 -15.586054) (xy 147.391881 -15.601576) (xy 147.307673 -15.60936)
			(xy 147.26539 -15.609824) (xy 147.222957 -15.609282) (xy 147.138497 -15.60099) (xy 147.055257 -15.584458)
			(xy 146.974039 -15.559845) (xy 146.895624 -15.527389) (xy 146.82077 -15.487401) (xy 146.750196 -15.440267)
			(xy 146.684584 -15.386442) (xy 146.624564 -15.326443) (xy 146.570715 -15.26085) (xy 146.523556 -15.190293)
			(xy 146.483542 -15.115452) (xy 146.451058 -15.03705) (xy 146.426416 -14.95584) (xy 146.409855 -14.872606)
			(xy 146.401533 -14.788149) (xy 146.401028 -14.745716) (xy 138.856503 -14.745716) (xy 138.830737 -14.822896)
			(xy 138.792212 -14.913317) (xy 138.746537 -15.000345) (xy 138.694006 -15.083415) (xy 138.634962 -15.161988)
			(xy 138.569787 -15.235556) (xy 138.498903 -15.303641) (xy 138.42277 -15.365802) (xy 138.341883 -15.421634)
			(xy 138.256765 -15.470777) (xy 138.167968 -15.512911) (xy 138.07607 -15.547764) (xy 137.981664 -15.575109)
			(xy 137.885365 -15.594768) (xy 137.787796 -15.606615) (xy 137.68959 -15.610573) (xy 137.591384 -15.606615)
			(xy 137.493815 -15.594768) (xy 137.397516 -15.575109) (xy 137.30311 -15.547764) (xy 137.211212 -15.512911)
			(xy 137.122415 -15.470777) (xy 137.037297 -15.421634) (xy 136.95641 -15.365802) (xy 136.880277 -15.303641)
			(xy 136.809393 -15.235556) (xy 136.744218 -15.161988) (xy 136.685174 -15.083415) (xy 136.632643 -15.000345)
			(xy 136.586968 -14.913317) (xy 136.548443 -14.822896) (xy 136.517319 -14.729668) (xy 136.493798 -14.634239)
			(xy 136.478032 -14.537226) (xy 136.470123 -14.439259) (xy 129.6924 -14.439259) (xy 129.6924 -17.79524)
			(xy 134.56413 -17.79524) (xy 134.568111 -17.715476) (xy 134.580014 -17.636504) (xy 134.599721 -17.55911)
			(xy 134.627036 -17.484063) (xy 134.661687 -17.412108) (xy 134.703331 -17.343961) (xy 134.751553 -17.280299)
			(xy 134.805874 -17.221755) (xy 134.865755 -17.16891) (xy 134.930599 -17.12229) (xy 134.999763 -17.082358)
			(xy 135.072559 -17.049511) (xy 135.148264 -17.024076) (xy 135.226125 -17.006305) (xy 135.305369 -16.996374)
			(xy 135.385208 -16.994383) (xy 135.464848 -17.000351) (xy 135.543499 -17.014219) (xy 135.620378 -17.03585)
			(xy 135.694721 -17.065027) (xy 135.765789 -17.101462) (xy 135.832877 -17.144792) (xy 135.895316 -17.194586)
			(xy 135.952488 -17.25035) (xy 136.003824 -17.311529) (xy 136.048812 -17.377515) (xy 136.087008 -17.447653)
			(xy 136.118029 -17.521246) (xy 136.14157 -17.597561) (xy 136.157394 -17.675841) (xy 136.165346 -17.755308)
			(xy 136.165844 -17.79524) (xy 136.165346 -17.835172) (xy 136.157394 -17.914639) (xy 136.14157 -17.992919)
			(xy 136.118029 -18.069234) (xy 136.087008 -18.142827) (xy 136.048812 -18.212965) (xy 136.003824 -18.278951)
			(xy 135.952488 -18.34013) (xy 135.895316 -18.395894) (xy 135.832877 -18.445688) (xy 135.765789 -18.489018)
			(xy 135.694721 -18.525453) (xy 135.620378 -18.55463) (xy 135.543499 -18.576261) (xy 135.464848 -18.590129)
			(xy 135.385208 -18.596097) (xy 135.305369 -18.594106) (xy 135.226125 -18.584175) (xy 135.148264 -18.566404)
			(xy 135.072559 -18.540969) (xy 134.999763 -18.508122) (xy 134.930599 -18.46819) (xy 134.865755 -18.42157)
			(xy 134.805874 -18.368725) (xy 134.751553 -18.310181) (xy 134.703331 -18.246519) (xy 134.661687 -18.178372)
			(xy 134.627036 -18.106417) (xy 134.599721 -18.03137) (xy 134.580014 -17.953976) (xy 134.568111 -17.875004)
			(xy 134.56413 -17.79524) (xy 129.6924 -17.79524) (xy 129.6924 -20.295108) (xy 134.462532 -20.295108)
			(xy 134.466498 -20.210577) (xy 134.478363 -20.12679) (xy 134.498021 -20.044481) (xy 134.525301 -19.964375)
			(xy 134.559962 -19.887176) (xy 134.6017 -19.813561) (xy 134.650147 -19.744178) (xy 134.704879 -19.679637)
			(xy 134.765415 -19.620505) (xy 134.831221 -19.567301) (xy 134.901721 -19.520493) (xy 134.976293 -19.480492)
			(xy 135.054284 -19.44765) (xy 135.135008 -19.422256) (xy 135.217755 -19.404533) (xy 135.301797 -19.394635)
			(xy 135.386398 -19.392652) (xy 135.470812 -19.398599) (xy 135.554299 -19.412424) (xy 135.636124 -19.434007)
			(xy 135.715568 -19.463157) (xy 135.791934 -19.499618) (xy 135.86455 -19.54307) (xy 135.932778 -19.593131)
			(xy 135.996018 -19.649361) (xy 136.053715 -19.711266) (xy 136.105362 -19.778302) (xy 136.150504 -19.849879)
			(xy 136.188746 -19.925369) (xy 136.21975 -20.004108) (xy 136.243245 -20.085405) (xy 136.249203 -20.1168)
			(xy 138.308078 -20.1168) (xy 138.312149 -20.061178) (xy 138.324275 -20.006741) (xy 138.344198 -19.95465)
			(xy 138.371494 -19.906015) (xy 138.40558 -19.861872) (xy 138.445729 -19.823163) (xy 138.491087 -19.790712)
			(xy 138.540687 -19.765211) (xy 138.593471 -19.747204) (xy 138.648314 -19.737074) (xy 138.704048 -19.735037)
			(xy 138.759485 -19.741137) (xy 138.813442 -19.755243) (xy 138.864771 -19.777055) (xy 138.912377 -19.806109)
			(xy 138.955245 -19.841784) (xy 138.992462 -19.883321) (xy 139.023235 -19.929834) (xy 139.027532 -19.939)
			(xy 139.908278 -19.939) (xy 139.912349 -19.883378) (xy 139.924475 -19.828941) (xy 139.944398 -19.77685)
			(xy 139.971694 -19.728215) (xy 140.00578 -19.684072) (xy 140.045929 -19.645363) (xy 140.091287 -19.612912)
			(xy 140.140887 -19.587411) (xy 140.193671 -19.569404) (xy 140.248514 -19.559274) (xy 140.304248 -19.557237)
			(xy 140.359685 -19.563337) (xy 140.413642 -19.577443) (xy 140.464971 -19.599255) (xy 140.512577 -19.628309)
			(xy 140.555445 -19.663984) (xy 140.592662 -19.705521) (xy 140.623435 -19.752034) (xy 140.647107 -19.802531)
			(xy 140.663175 -19.855938) (xy 140.671295 -19.911114) (xy 140.671804 -19.939) (xy 140.671295 -19.966886)
			(xy 140.663175 -20.022062) (xy 140.647107 -20.075469) (xy 140.635206 -20.100857) (xy 141.508525 -20.100857)
			(xy 141.514686 -20.046743) (xy 141.528479 -19.994056) (xy 141.549624 -19.943865) (xy 141.577692 -19.897192)
			(xy 141.612112 -19.854984) (xy 141.652185 -19.8181) (xy 141.697095 -19.787289) (xy 141.745931 -19.763178)
			(xy 141.797698 -19.746257) (xy 141.851346 -19.736869) (xy 141.905784 -19.735206) (xy 141.959905 -19.741302)
			(xy 142.012609 -19.755032) (xy 142.062825 -19.776117) (xy 142.109533 -19.804128) (xy 142.151782 -19.838498)
			(xy 142.188714 -19.878526) (xy 142.219578 -19.923399) (xy 142.243748 -19.972205) (xy 142.2527 -19.997928)
			(xy 142.260068 -20.018805) (xy 142.280957 -20.057834) (xy 142.308295 -20.092651) (xy 142.341253 -20.122204)
			(xy 142.378835 -20.145597) (xy 142.419902 -20.162123) (xy 142.463212 -20.171281) (xy 142.507453 -20.172795)
			(xy 142.551288 -20.166618) (xy 142.572486 -20.160234) (xy 142.597675 -20.152566) (xy 142.649512 -20.143346)
			(xy 142.702125 -20.141344) (xy 142.754513 -20.146599) (xy 142.805681 -20.15901) (xy 142.854654 -20.178342)
			(xy 142.900503 -20.204228) (xy 142.942355 -20.236174) (xy 142.979415 -20.273573) (xy 143.010977 -20.315715)
			(xy 143.024098 -20.338542) (xy 143.035806 -20.358573) (xy 143.065207 -20.394454) (xy 143.100637 -20.424398)
			(xy 143.140917 -20.447409) (xy 143.184706 -20.46272) (xy 143.230548 -20.469822) (xy 143.276917 -20.468479)
			(xy 143.322271 -20.458735) (xy 143.343884 -20.450302) (xy 143.368083 -20.440725) (xy 143.418406 -20.42746)
			(xy 143.470066 -20.421165) (xy 143.522102 -20.421955) (xy 143.573547 -20.429817) (xy 143.623444 -20.444604)
			(xy 143.670866 -20.466042) (xy 143.693134 -20.479512) (xy 143.711859 -20.490771) (xy 143.752274 -20.507366)
			(xy 143.794934 -20.516798) (xy 143.838578 -20.518789) (xy 143.881919 -20.51328) (xy 143.923677 -20.500433)
			(xy 143.96262 -20.480628) (xy 143.997599 -20.454449) (xy 144.01292 -20.438872) (xy 144.031376 -20.420026)
			(xy 144.072539 -20.387044) (xy 144.117852 -20.360046) (xy 144.166452 -20.339545) (xy 144.217412 -20.325933)
			(xy 144.269761 -20.319469) (xy 144.322501 -20.320275) (xy 144.374628 -20.328338) (xy 144.400016 -20.335494)
			(xy 144.422091 -20.341546) (xy 144.467575 -20.346612) (xy 144.513231 -20.343452) (xy 144.557584 -20.332169)
			(xy 144.5992 -20.313127) (xy 144.636734 -20.286942) (xy 144.668972 -20.254459) (xy 144.694874 -20.216728)
			(xy 144.713602 -20.17497) (xy 144.719548 -20.152868) (xy 144.726328 -20.126887) (xy 144.746322 -20.077051)
			(xy 144.773104 -20.030509) (xy 144.806146 -19.988181) (xy 144.844795 -19.950903) (xy 144.888287 -19.91941)
			(xy 144.935765 -19.894325) (xy 144.98629 -19.876143) (xy 145.038865 -19.865222) (xy 145.092452 -19.861779)
			(xy 145.145993 -19.865881) (xy 145.198429 -19.877448) (xy 145.223738 -19.886422) (xy 145.246229 -19.894243)
			(xy 145.293154 -19.902301) (xy 145.340759 -19.901482) (xy 145.387379 -19.891817) (xy 145.431386 -19.873641)
			(xy 145.471239 -19.847592) (xy 145.505547 -19.814578) (xy 145.533109 -19.775756) (xy 145.543524 -19.754342)
			(xy 145.555507 -19.729397) (xy 145.585632 -19.682975) (xy 145.622146 -19.641392) (xy 145.664286 -19.605521)
			(xy 145.711166 -19.576114) (xy 145.761802 -19.553789) (xy 145.815133 -19.539014) (xy 145.870039 -19.532099)
			(xy 145.925368 -19.533188) (xy 145.979959 -19.54226) (xy 146.032666 -19.559124) (xy 146.082384 -19.583426)
			(xy 146.12807 -19.614656) (xy 146.168764 -19.652158) (xy 146.203613 -19.695147) (xy 146.231886 -19.742719)
			(xy 146.252989 -19.793877) (xy 146.26648 -19.847547) (xy 146.272075 -19.902603) (xy 146.269658 -19.95789)
			(xy 146.259278 -20.012247) (xy 146.241154 -20.064535) (xy 146.215665 -20.113655) (xy 146.183348 -20.158578)
			(xy 146.144879 -20.19836) (xy 146.101067 -20.232167) (xy 146.052829 -20.25929) (xy 146.00118 -20.279159)
			(xy 145.947201 -20.291357) (xy 145.892027 -20.295629) (xy 145.836814 -20.291885) (xy 145.782721 -20.280203)
			(xy 145.75663 -20.270978) (xy 145.73415 -20.263122) (xy 145.687221 -20.255068) (xy 145.639613 -20.255891)
			(xy 145.59299 -20.265562) (xy 145.548983 -20.283743) (xy 145.509128 -20.309797) (xy 145.474821 -20.342815)
			(xy 145.447259 -20.381642) (xy 145.436844 -20.403058) (xy 145.424963 -20.427677) (xy 145.395313 -20.473599)
			(xy 145.359411 -20.514818) (xy 145.317992 -20.550489) (xy 145.271906 -20.579883) (xy 145.222096 -20.602396)
			(xy 145.169581 -20.617568) (xy 145.115439 -20.625089) (xy 145.060778 -20.624803) (xy 145.006717 -20.616717)
			(xy 144.980406 -20.609306) (xy 144.958325 -20.603279) (xy 144.912843 -20.59821) (xy 144.867189 -20.601366)
			(xy 144.822837 -20.612646) (xy 144.781222 -20.631685) (xy 144.743689 -20.657867) (xy 144.71145 -20.690348)
			(xy 144.685549 -20.728075) (xy 144.666821 -20.769831) (xy 144.660874 -20.791932) (xy 144.653804 -20.818785)
			(xy 144.632883 -20.87022) (xy 144.604728 -20.918081) (xy 144.569934 -20.961356) (xy 144.529235 -20.999132)
			(xy 144.483492 -21.030611) (xy 144.43367 -21.055128) (xy 144.38082 -21.072166) (xy 144.32606 -21.081365)
			(xy 144.270544 -21.082531) (xy 144.215445 -21.075639) (xy 144.161927 -21.060834) (xy 144.11112 -21.03843)
			(xy 144.087342 -21.024088) (xy 144.068631 -21.012804) (xy 144.028212 -20.996211) (xy 143.98555 -20.986782)
			(xy 143.941903 -20.984794) (xy 143.89856 -20.990307) (xy 143.8568 -21.003157) (xy 143.817856 -21.022966)
			(xy 143.782877 -21.049149) (xy 143.767556 -21.064728) (xy 143.748273 -21.084482) (xy 143.704971 -21.118721)
			(xy 143.657189 -21.146364) (xy 143.605922 -21.166836) (xy 143.552241 -21.179708) (xy 143.497265 -21.184712)
			(xy 143.442142 -21.181743) (xy 143.388022 -21.170865) (xy 143.336033 -21.152302) (xy 143.287261 -21.126444)
			(xy 143.242723 -21.093829) (xy 143.203349 -21.055138) (xy 143.169959 -21.011178) (xy 143.156178 -20.987258)
			(xy 143.144494 -20.967212) (xy 143.11509 -20.931329) (xy 143.079656 -20.901385) (xy 143.039372 -20.878376)
			(xy 142.995579 -20.863067) (xy 142.949734 -20.855968) (xy 142.903362 -20.857315) (xy 142.858006 -20.867063)
			(xy 142.836392 -20.875498) (xy 142.8098 -20.885989) (xy 142.754328 -20.899788) (xy 142.697418 -20.905156)
			(xy 142.640343 -20.901972) (xy 142.584383 -20.890307) (xy 142.53079 -20.870423) (xy 142.480764 -20.842765)
			(xy 142.435424 -20.807952) (xy 142.395787 -20.766764) (xy 142.362739 -20.720122) (xy 142.33702 -20.669072)
			(xy 142.32763 -20.642072) (xy 142.320228 -20.621208) (xy 142.299342 -20.582182) (xy 142.272008 -20.547366)
			(xy 142.239054 -20.517814) (xy 142.201478 -20.49442) (xy 142.160416 -20.477892) (xy 142.11711 -20.468731)
			(xy 142.072873 -20.467213) (xy 142.029041 -20.473385) (xy 142.007844 -20.479766) (xy 141.98181 -20.487764)
			(xy 141.92814 -20.497023) (xy 141.873698 -20.498555) (xy 141.819592 -20.49233) (xy 141.766921 -20.478473)
			(xy 141.716756 -20.457267) (xy 141.670116 -20.429143) (xy 141.62795 -20.394673) (xy 141.591114 -20.354556)
			(xy 141.560357 -20.309608) (xy 141.536305 -20.260744) (xy 141.519446 -20.208956) (xy 141.510123 -20.155297)
			(xy 141.508525 -20.100857) (xy 140.635206 -20.100857) (xy 140.623435 -20.125966) (xy 140.592662 -20.172479)
			(xy 140.555445 -20.214016) (xy 140.512577 -20.249691) (xy 140.464971 -20.278745) (xy 140.413642 -20.300557)
			(xy 140.359685 -20.314663) (xy 140.304248 -20.320763) (xy 140.248514 -20.318726) (xy 140.193671 -20.308596)
			(xy 140.140887 -20.290589) (xy 140.091287 -20.265088) (xy 140.045929 -20.232637) (xy 140.00578 -20.193928)
			(xy 139.971694 -20.149785) (xy 139.944398 -20.10115) (xy 139.924475 -20.049059) (xy 139.912349 -19.994622)
			(xy 139.908278 -19.939) (xy 139.027532 -19.939) (xy 139.046907 -19.980331) (xy 139.062975 -20.033738)
			(xy 139.071095 -20.088914) (xy 139.071604 -20.1168) (xy 139.071095 -20.144686) (xy 139.062975 -20.199862)
			(xy 139.046907 -20.253269) (xy 139.023235 -20.303766) (xy 138.992462 -20.350279) (xy 138.955245 -20.391816)
			(xy 138.912377 -20.427491) (xy 138.864771 -20.456545) (xy 138.813442 -20.478357) (xy 138.759485 -20.492463)
			(xy 138.704048 -20.498563) (xy 138.648314 -20.496526) (xy 138.593471 -20.486396) (xy 138.540687 -20.468389)
			(xy 138.491087 -20.442888) (xy 138.445729 -20.410437) (xy 138.40558 -20.371728) (xy 138.371494 -20.327585)
			(xy 138.344198 -20.27895) (xy 138.324275 -20.226859) (xy 138.312149 -20.172422) (xy 138.308078 -20.1168)
			(xy 136.249203 -20.1168) (xy 136.259024 -20.168544) (xy 136.266948 -20.252796) (xy 136.267444 -20.295108)
			(xy 136.266948 -20.33742) (xy 136.259024 -20.421672) (xy 136.243245 -20.504811) (xy 136.21975 -20.586108)
			(xy 136.188746 -20.664847) (xy 136.150504 -20.740337) (xy 136.105362 -20.811914) (xy 136.053715 -20.87895)
			(xy 135.996018 -20.940855) (xy 135.932778 -20.997085) (xy 135.86455 -21.047146) (xy 135.791934 -21.090598)
			(xy 135.715568 -21.127059) (xy 135.636124 -21.156209) (xy 135.554299 -21.177792) (xy 135.470812 -21.191617)
			(xy 135.386398 -21.197564) (xy 135.301797 -21.195581) (xy 135.217755 -21.185683) (xy 135.135008 -21.16796)
			(xy 135.054284 -21.142566) (xy 134.976293 -21.109724) (xy 134.901721 -21.069723) (xy 134.831221 -21.022915)
			(xy 134.765415 -20.969711) (xy 134.704879 -20.910579) (xy 134.650147 -20.846038) (xy 134.6017 -20.776655)
			(xy 134.559962 -20.70304) (xy 134.525301 -20.625841) (xy 134.498021 -20.545735) (xy 134.478363 -20.463426)
			(xy 134.466498 -20.379639) (xy 134.462532 -20.295108) (xy 129.6924 -20.295108) (xy 129.6924 -20.825968)
			(xy 130.77571 -21.909278) (xy 130.787126 -21.920062) (xy 130.814059 -21.936194) (xy 130.844117 -21.945255)
			(xy 130.875478 -21.946695) (xy 130.90624 -21.940427) (xy 130.934538 -21.92683) (xy 130.946906 -21.917152)
			(xy 130.968932 -21.899475) (xy 131.017185 -21.870132) (xy 131.069237 -21.848223) (xy 131.12395 -21.834228)
			(xy 131.180129 -21.828452) (xy 131.236545 -21.831022) (xy 131.291966 -21.841882) (xy 131.34518 -21.860794)
			(xy 131.395024 -21.887345) (xy 131.440409 -21.920954) (xy 131.480343 -21.960888) (xy 131.513953 -22.006272)
			(xy 131.540505 -22.056116) (xy 131.559417 -22.10933) (xy 131.570277 -22.164751) (xy 131.572848 -22.221167)
			(xy 131.567073 -22.277346) (xy 131.553078 -22.332059) (xy 131.53117 -22.384111) (xy 131.501827 -22.432365)
			(xy 131.484116 -22.454362) (xy 131.47442 -22.466721) (xy 131.460817 -22.495025) (xy 131.46077 -22.495256)
			(xy 134.56413 -22.495256) (xy 134.568111 -22.415492) (xy 134.580014 -22.33652) (xy 134.599721 -22.259126)
			(xy 134.627036 -22.184079) (xy 134.661687 -22.112124) (xy 134.703331 -22.043977) (xy 134.751553 -21.980315)
			(xy 134.805874 -21.921771) (xy 134.865755 -21.868926) (xy 134.930599 -21.822306) (xy 134.999763 -21.782374)
			(xy 135.072559 -21.749527) (xy 135.148264 -21.724092) (xy 135.226125 -21.706321) (xy 135.305369 -21.69639)
			(xy 135.385208 -21.694399) (xy 135.464848 -21.700367) (xy 135.543499 -21.714235) (xy 135.620378 -21.735866)
			(xy 135.694721 -21.765043) (xy 135.765789 -21.801478) (xy 135.832877 -21.844808) (xy 135.895316 -21.894602)
			(xy 135.952488 -21.950366) (xy 136.003824 -22.011545) (xy 136.048812 -22.077531) (xy 136.087008 -22.147669)
			(xy 136.118029 -22.221262) (xy 136.134852 -22.2758) (xy 142.823182 -22.2758) (xy 142.827253 -22.220178)
			(xy 142.839379 -22.165741) (xy 142.859302 -22.11365) (xy 142.886598 -22.065015) (xy 142.920684 -22.020872)
			(xy 142.960833 -21.982163) (xy 143.006191 -21.949712) (xy 143.055791 -21.924211) (xy 143.108575 -21.906204)
			(xy 143.163418 -21.896074) (xy 143.219152 -21.894037) (xy 143.274589 -21.900137) (xy 143.328546 -21.914243)
			(xy 143.379875 -21.936055) (xy 143.427481 -21.965109) (xy 143.470349 -22.000784) (xy 143.507566 -22.042321)
			(xy 143.538339 -22.088834) (xy 143.562011 -22.139331) (xy 143.578079 -22.192738) (xy 143.586199 -22.247914)
			(xy 143.586708 -22.2758) (xy 143.586199 -22.303686) (xy 143.578079 -22.358862) (xy 143.562011 -22.412269)
			(xy 143.538339 -22.462766) (xy 143.516844 -22.495256) (xy 148.814038 -22.495256) (xy 148.818019 -22.415492)
			(xy 148.829922 -22.33652) (xy 148.849629 -22.259126) (xy 148.876944 -22.184079) (xy 148.911595 -22.112124)
			(xy 148.953239 -22.043977) (xy 149.001461 -21.980315) (xy 149.055782 -21.921771) (xy 149.115663 -21.868926)
			(xy 149.180507 -21.822306) (xy 149.249671 -21.782374) (xy 149.322467 -21.749527) (xy 149.398172 -21.724092)
			(xy 149.476033 -21.706321) (xy 149.555277 -21.69639) (xy 149.635116 -21.694399) (xy 149.714756 -21.700367)
			(xy 149.793407 -21.714235) (xy 149.870286 -21.735866) (xy 149.944629 -21.765043) (xy 150.015697 -21.801478)
			(xy 150.082785 -21.844808) (xy 150.145224 -21.894602) (xy 150.202396 -21.950366) (xy 150.253732 -22.011545)
			(xy 150.29872 -22.077531) (xy 150.336916 -22.147669) (xy 150.367937 -22.221262) (xy 150.391478 -22.297577)
			(xy 150.407302 -22.375857) (xy 150.415254 -22.455324) (xy 150.415752 -22.495256) (xy 150.415254 -22.535188)
			(xy 150.407302 -22.614655) (xy 150.391478 -22.692935) (xy 150.367937 -22.76925) (xy 150.336916 -22.842843)
			(xy 150.29872 -22.912981) (xy 150.253732 -22.978967) (xy 150.202396 -23.040146) (xy 150.145224 -23.09591)
			(xy 150.082785 -23.145704) (xy 150.015697 -23.189034) (xy 149.944629 -23.225469) (xy 149.870286 -23.254646)
			(xy 149.793407 -23.276277) (xy 149.714756 -23.290145) (xy 149.635116 -23.296113) (xy 149.555277 -23.294122)
			(xy 149.476033 -23.284191) (xy 149.398172 -23.26642) (xy 149.322467 -23.240985) (xy 149.249671 -23.208138)
			(xy 149.180507 -23.168206) (xy 149.115663 -23.121586) (xy 149.055782 -23.068741) (xy 149.001461 -23.010197)
			(xy 148.953239 -22.946535) (xy 148.911595 -22.878388) (xy 148.876944 -22.806433) (xy 148.849629 -22.731386)
			(xy 148.829922 -22.653992) (xy 148.818019 -22.57502) (xy 148.814038 -22.495256) (xy 143.516844 -22.495256)
			(xy 143.507566 -22.509279) (xy 143.470349 -22.550816) (xy 143.427481 -22.586491) (xy 143.379875 -22.615545)
			(xy 143.328546 -22.637357) (xy 143.274589 -22.651463) (xy 143.219152 -22.657563) (xy 143.163418 -22.655526)
			(xy 143.108575 -22.645396) (xy 143.055791 -22.627389) (xy 143.006191 -22.601888) (xy 142.960833 -22.569437)
			(xy 142.920684 -22.530728) (xy 142.886598 -22.486585) (xy 142.859302 -22.43795) (xy 142.839379 -22.385859)
			(xy 142.827253 -22.331422) (xy 142.823182 -22.2758) (xy 136.134852 -22.2758) (xy 136.14157 -22.297577)
			(xy 136.157394 -22.375857) (xy 136.165346 -22.455324) (xy 136.165844 -22.495256) (xy 136.165346 -22.535188)
			(xy 136.157394 -22.614655) (xy 136.14157 -22.692935) (xy 136.137046 -22.7076) (xy 139.108178 -22.7076)
			(xy 139.112249 -22.651978) (xy 139.124375 -22.597541) (xy 139.144298 -22.54545) (xy 139.171594 -22.496815)
			(xy 139.20568 -22.452672) (xy 139.245829 -22.413963) (xy 139.291187 -22.381512) (xy 139.340787 -22.356011)
			(xy 139.393571 -22.338004) (xy 139.448414 -22.327874) (xy 139.504148 -22.325837) (xy 139.559585 -22.331937)
			(xy 139.613542 -22.346043) (xy 139.664871 -22.367855) (xy 139.712477 -22.396909) (xy 139.755345 -22.432584)
			(xy 139.792562 -22.474121) (xy 139.823335 -22.520634) (xy 139.847007 -22.571131) (xy 139.863075 -22.624538)
			(xy 139.871195 -22.679714) (xy 139.871704 -22.7076) (xy 139.871195 -22.735486) (xy 139.863075 -22.790662)
			(xy 139.847007 -22.844069) (xy 139.823335 -22.894566) (xy 139.792562 -22.941079) (xy 139.755345 -22.982616)
			(xy 139.712477 -23.018291) (xy 139.664871 -23.047345) (xy 139.613542 -23.069157) (xy 139.559585 -23.083263)
			(xy 139.504148 -23.089363) (xy 139.448414 -23.087326) (xy 139.393571 -23.077196) (xy 139.340787 -23.059189)
			(xy 139.291187 -23.033688) (xy 139.245829 -23.001237) (xy 139.20568 -22.962528) (xy 139.171594 -22.918385)
			(xy 139.144298 -22.86975) (xy 139.124375 -22.817659) (xy 139.112249 -22.763222) (xy 139.108178 -22.7076)
			(xy 136.137046 -22.7076) (xy 136.118029 -22.76925) (xy 136.087008 -22.842843) (xy 136.048812 -22.912981)
			(xy 136.003824 -22.978967) (xy 135.952488 -23.040146) (xy 135.895316 -23.09591) (xy 135.832877 -23.145704)
			(xy 135.765789 -23.189034) (xy 135.694721 -23.225469) (xy 135.620378 -23.254646) (xy 135.543499 -23.276277)
			(xy 135.464848 -23.290145) (xy 135.385208 -23.296113) (xy 135.305369 -23.294122) (xy 135.226125 -23.284191)
			(xy 135.148264 -23.26642) (xy 135.072559 -23.240985) (xy 134.999763 -23.208138) (xy 134.930599 -23.168206)
			(xy 134.865755 -23.121586) (xy 134.805874 -23.068741) (xy 134.751553 -23.010197) (xy 134.703331 -22.946535)
			(xy 134.661687 -22.878388) (xy 134.627036 -22.806433) (xy 134.599721 -22.731386) (xy 134.580014 -22.653992)
			(xy 134.568111 -22.57502) (xy 134.56413 -22.495256) (xy 131.46077 -22.495256) (xy 131.454543 -22.525795)
			(xy 131.455977 -22.557166) (xy 131.465033 -22.587235) (xy 131.481162 -22.61418) (xy 131.49199 -22.625558)
			(xy 131.642866 -22.77618) (xy 131.658983 -22.791633) (xy 131.695586 -22.817197) (xy 131.736092 -22.835975)
			(xy 131.779256 -22.847387) (xy 131.823749 -22.851084) (xy 131.868204 -22.846951) (xy 131.911254 -22.835115)
			(xy 131.951573 -22.815941) (xy 131.970018 -22.803358) (xy 131.993234 -22.787424) (xy 132.043386 -22.76183)
			(xy 132.096756 -22.743885) (xy 132.152184 -22.73398) (xy 132.208466 -22.732328) (xy 132.264379 -22.738967)
			(xy 132.318709 -22.753751) (xy 132.370277 -22.776361) (xy 132.417961 -22.806304) (xy 132.460726 -22.84293)
			(xy 132.497643 -22.885445) (xy 132.527911 -22.932923) (xy 132.550872 -22.984335) (xy 132.566027 -23.038563)
			(xy 132.573047 -23.09443) (xy 132.57178 -23.150722) (xy 132.562253 -23.206216) (xy 132.553964 -23.233126)
			(xy 132.548977 -23.249968) (xy 132.547448 -23.285046) (xy 132.555552 -23.319209) (xy 132.572672 -23.349864)
			(xy 132.584698 -23.362666) (xy 133.924548 -24.702262) (xy 133.924548 -25.2222) (xy 133.924042 -25.25054)
			(xy 133.917636 -25.295098) (xy 137.632452 -25.295098) (xy 137.636418 -25.210567) (xy 137.648283 -25.12678)
			(xy 137.667941 -25.044471) (xy 137.695221 -24.964365) (xy 137.729882 -24.887166) (xy 137.77162 -24.813551)
			(xy 137.820067 -24.744168) (xy 137.874799 -24.679627) (xy 137.935335 -24.620495) (xy 138.001141 -24.567291)
			(xy 138.071641 -24.520483) (xy 138.146213 -24.480482) (xy 138.224204 -24.44764) (xy 138.304928 -24.422246)
			(xy 138.387675 -24.404523) (xy 138.471717 -24.394625) (xy 138.556318 -24.392642) (xy 138.640732 -24.398589)
			(xy 138.724219 -24.412414) (xy 138.806044 -24.433997) (xy 138.885488 -24.463147) (xy 138.961854 -24.499608)
			(xy 139.03447 -24.54306) (xy 139.102698 -24.593121) (xy 139.165938 -24.649351) (xy 139.223635 -24.711256)
			(xy 139.275282 -24.778292) (xy 139.320424 -24.849869) (xy 139.358666 -24.925359) (xy 139.38967 -25.004098)
			(xy 139.413165 -25.085395) (xy 139.428944 -25.168534) (xy 139.436868 -25.252786) (xy 139.437364 -25.295098)
			(xy 143.032492 -25.295098) (xy 143.036458 -25.210567) (xy 143.048323 -25.12678) (xy 143.067981 -25.044471)
			(xy 143.095261 -24.964365) (xy 143.129922 -24.887166) (xy 143.17166 -24.813551) (xy 143.220107 -24.744168)
			(xy 143.274839 -24.679627) (xy 143.335375 -24.620495) (xy 143.401181 -24.567291) (xy 143.471681 -24.520483)
			(xy 143.546253 -24.480482) (xy 143.624244 -24.44764) (xy 143.704968 -24.422246) (xy 143.787715 -24.404523)
			(xy 143.871757 -24.394625) (xy 143.956358 -24.392642) (xy 144.040772 -24.398589) (xy 144.124259 -24.412414)
			(xy 144.206084 -24.433997) (xy 144.285528 -24.463147) (xy 144.361894 -24.499608) (xy 144.43451 -24.54306)
			(xy 144.502738 -24.593121) (xy 144.565978 -24.649351) (xy 144.623675 -24.711256) (xy 144.675322 -24.778292)
			(xy 144.720464 -24.849869) (xy 144.758706 -24.925359) (xy 144.78971 -25.004098) (xy 144.813205 -25.085395)
			(xy 144.828984 -25.168534) (xy 144.836908 -25.252786) (xy 144.837404 -25.295098) (xy 148.71244 -25.295098)
			(xy 148.716406 -25.210567) (xy 148.728271 -25.12678) (xy 148.747929 -25.044471) (xy 148.775209 -24.964365)
			(xy 148.80987 -24.887166) (xy 148.851608 -24.813551) (xy 148.900055 -24.744168) (xy 148.954787 -24.679627)
			(xy 149.015323 -24.620495) (xy 149.081129 -24.567291) (xy 149.151629 -24.520483) (xy 149.226201 -24.480482)
			(xy 149.304192 -24.44764) (xy 149.384916 -24.422246) (xy 149.467663 -24.404523) (xy 149.551705 -24.394625)
			(xy 149.636306 -24.392642) (xy 149.72072 -24.398589) (xy 149.804207 -24.412414) (xy 149.886032 -24.433997)
			(xy 149.965476 -24.463147) (xy 150.041842 -24.499608) (xy 150.114458 -24.54306) (xy 150.182686 -24.593121)
			(xy 150.245926 -24.649351) (xy 150.303623 -24.711256) (xy 150.35527 -24.778292) (xy 150.400412 -24.849869)
			(xy 150.438654 -24.925359) (xy 150.469658 -25.004098) (xy 150.493153 -25.085395) (xy 150.508932 -25.168534)
			(xy 150.516856 -25.252786) (xy 150.517352 -25.295098) (xy 150.516856 -25.33741) (xy 150.508932 -25.421662)
			(xy 150.493153 -25.504801) (xy 150.469658 -25.586098) (xy 150.438654 -25.664837) (xy 150.400412 -25.740327)
			(xy 150.35527 -25.811904) (xy 150.303623 -25.87894) (xy 150.245926 -25.940845) (xy 150.182686 -25.997075)
			(xy 150.114458 -26.047136) (xy 150.041842 -26.090588) (xy 149.965476 -26.127049) (xy 149.886032 -26.156199)
			(xy 149.804207 -26.177782) (xy 149.72072 -26.191607) (xy 149.636306 -26.197554) (xy 149.551705 -26.195571)
			(xy 149.467663 -26.185673) (xy 149.384916 -26.16795) (xy 149.304192 -26.142556) (xy 149.226201 -26.109714)
			(xy 149.151629 -26.069713) (xy 149.081129 -26.022905) (xy 149.015323 -25.969701) (xy 148.954787 -25.910569)
			(xy 148.900055 -25.846028) (xy 148.851608 -25.776645) (xy 148.80987 -25.70303) (xy 148.775209 -25.625831)
			(xy 148.747929 -25.545725) (xy 148.728271 -25.463416) (xy 148.716406 -25.379629) (xy 148.71244 -25.295098)
			(xy 144.837404 -25.295098) (xy 144.836908 -25.33741) (xy 144.828984 -25.421662) (xy 144.813205 -25.504801)
			(xy 144.78971 -25.586098) (xy 144.758706 -25.664837) (xy 144.720464 -25.740327) (xy 144.675322 -25.811904)
			(xy 144.623675 -25.87894) (xy 144.565978 -25.940845) (xy 144.502738 -25.997075) (xy 144.43451 -26.047136)
			(xy 144.361894 -26.090588) (xy 144.285528 -26.127049) (xy 144.206084 -26.156199) (xy 144.124259 -26.177782)
			(xy 144.040772 -26.191607) (xy 143.956358 -26.197554) (xy 143.871757 -26.195571) (xy 143.787715 -26.185673)
			(xy 143.704968 -26.16795) (xy 143.624244 -26.142556) (xy 143.546253 -26.109714) (xy 143.471681 -26.069713)
			(xy 143.401181 -26.022905) (xy 143.335375 -25.969701) (xy 143.274839 -25.910569) (xy 143.220107 -25.846028)
			(xy 143.17166 -25.776645) (xy 143.129922 -25.70303) (xy 143.095261 -25.625831) (xy 143.067981 -25.545725)
			(xy 143.048323 -25.463416) (xy 143.036458 -25.379629) (xy 143.032492 -25.295098) (xy 139.437364 -25.295098)
			(xy 139.436868 -25.33741) (xy 139.428944 -25.421662) (xy 139.413165 -25.504801) (xy 139.38967 -25.586098)
			(xy 139.358666 -25.664837) (xy 139.320424 -25.740327) (xy 139.275282 -25.811904) (xy 139.223635 -25.87894)
			(xy 139.165938 -25.940845) (xy 139.102698 -25.997075) (xy 139.03447 -26.047136) (xy 138.961854 -26.090588)
			(xy 138.885488 -26.127049) (xy 138.806044 -26.156199) (xy 138.724219 -26.177782) (xy 138.640732 -26.191607)
			(xy 138.556318 -26.197554) (xy 138.471717 -26.195571) (xy 138.387675 -26.185673) (xy 138.304928 -26.16795)
			(xy 138.224204 -26.142556) (xy 138.146213 -26.109714) (xy 138.071641 -26.069713) (xy 138.001141 -26.022905)
			(xy 137.935335 -25.969701) (xy 137.874799 -25.910569) (xy 137.820067 -25.846028) (xy 137.77162 -25.776645)
			(xy 137.729882 -25.70303) (xy 137.695221 -25.625831) (xy 137.667941 -25.545725) (xy 137.648283 -25.463416)
			(xy 137.636418 -25.379629) (xy 137.632452 -25.295098) (xy 133.917636 -25.295098) (xy 133.915976 -25.306643)
			(xy 133.900007 -25.361026) (xy 133.876462 -25.412584) (xy 133.845819 -25.460266) (xy 133.808701 -25.503101)
			(xy 133.765866 -25.540219) (xy 133.718184 -25.570862) (xy 133.666626 -25.594407) (xy 133.612243 -25.610376)
			(xy 133.55614 -25.618442) (xy 133.49946 -25.618442) (xy 133.443357 -25.610376) (xy 133.388974 -25.594407)
			(xy 133.337416 -25.570862) (xy 133.289734 -25.540219) (xy 133.246899 -25.503101) (xy 133.209781 -25.460266)
			(xy 133.179138 -25.412584) (xy 133.155593 -25.361026) (xy 133.139624 -25.306643) (xy 133.131558 -25.25054)
			(xy 133.131052 -25.2222) (xy 133.131052 -25.030938) (xy 132.691886 -24.591518) (xy 132.676015 -24.576312)
			(xy 132.640049 -24.55105) (xy 132.600276 -24.532347) (xy 132.557879 -24.520762) (xy 132.514122 -24.516639)
			(xy 132.470308 -24.520101) (xy 132.427741 -24.531045) (xy 132.38769 -24.549145) (xy 132.351347 -24.573861)
			(xy 132.319796 -24.604458) (xy 132.293975 -24.640024) (xy 132.283962 -24.65959) (xy 132.271391 -24.684272)
			(xy 132.240425 -24.730197) (xy 132.20337 -24.771366) (xy 132.160946 -24.806978) (xy 132.113979 -24.836339)
			(xy 132.063383 -24.858879) (xy 132.010143 -24.874159) (xy 131.955295 -24.88188) (xy 131.9276 -24.882348)
			(xy 131.636262 -24.882348) (xy 130.125978 -23.37181) (xy 130.10933 -23.355872) (xy 130.0714 -23.329697)
			(xy 130.029373 -23.31079) (xy 129.984625 -23.299773) (xy 129.938623 -23.297005) (xy 129.892877 -23.302577)
			(xy 129.848886 -23.316308) (xy 129.808091 -23.337746) (xy 129.771831 -23.366189) (xy 129.741295 -23.400704)
			(xy 129.717483 -23.44016) (xy 129.701176 -23.483262) (xy 129.692909 -23.528599) (xy 129.6924 -23.551642)
			(xy 129.6924 -25.3492) (xy 129.159 -25.8826) (xy 129.159 -27.521154) (xy 130.222752 -28.584906) (xy 130.239459 -28.600897)
			(xy 130.277532 -28.627142) (xy 130.319727 -28.646062) (xy 130.364649 -28.657032) (xy 130.410815 -28.659691)
			(xy 130.456699 -28.65395) (xy 130.500787 -28.639999) (xy 130.541621 -28.618299) (xy 130.577854 -28.589566)
			(xy 130.608287 -28.554751) (xy 130.620516 -28.535122) (xy 130.650627 -28.48546) (xy 130.716846 -28.390037)
			(xy 130.789607 -28.299502) (xy 130.86855 -28.214303) (xy 130.953284 -28.134862) (xy 131.04339 -28.061572)
			(xy 131.138424 -27.994793) (xy 131.237915 -27.934858) (xy 131.341371 -27.882061) (xy 131.448281 -27.836664)
			(xy 131.558117 -27.798892) (xy 131.670336 -27.768931) (xy 131.784383 -27.746929) (xy 131.899693 -27.732994)
			(xy 132.015698 -27.727197) (xy 132.131823 -27.729565) (xy 132.247495 -27.740087) (xy 132.362142 -27.758711)
			(xy 132.475197 -27.785344) (xy 132.586101 -27.819855) (xy 132.694306 -27.862074) (xy 132.799276 -27.911792)
			(xy 132.900494 -27.968762) (xy 132.997459 -28.032704) (xy 133.089691 -28.103301) (xy 133.176735 -28.180205)
			(xy 133.258159 -28.263034) (xy 133.333563 -28.35138) (xy 133.402572 -28.444806) (xy 133.464846 -28.54285)
			(xy 133.520077 -28.645028) (xy 133.567992 -28.750834) (xy 133.608355 -28.859745) (xy 133.625082 -28.91536)
			(xy 133.63702 -28.956) (xy 133.704838 -29.0068) (xy 152.019 -29.0068)
		)
		(stroke
			(width 0)
			(type solid)
		)
		(fill yes)
		(layer "In2.Cu")
		(net "P3V3_BLAD1")
	)
	(gr_poly
		(pts
			(xy 375.539 -27.0256) (xy 375.539 -22.918928) (xy 371.277896 -18.658078) (xy 371.277896 -18.55216)
			(xy 371.277469 -18.53672) (xy 371.270053 -18.506743) (xy 371.255643 -18.479431) (xy 371.235084 -18.456388)
			(xy 371.209586 -18.438969) (xy 371.180645 -18.428197) (xy 371.149963 -18.424704) (xy 371.119342 -18.428696)
			(xy 371.09058 -18.439938) (xy 371.077744 -18.448528) (xy 371.045132 -18.471036) (xy 370.976256 -18.510225)
			(xy 370.903845 -18.542419) (xy 370.828608 -18.5673) (xy 370.751281 -18.584627) (xy 370.67262 -18.594229)
			(xy 370.593396 -18.596012) (xy 370.514383 -18.58996) (xy 370.436354 -18.576131) (xy 370.360074 -18.55466)
			(xy 370.286288 -18.525758) (xy 370.215718 -18.489708) (xy 370.149055 -18.446862) (xy 370.086952 -18.397639)
			(xy 370.030016 -18.342521) (xy 369.978803 -18.282048) (xy 369.933816 -18.216811) (xy 369.895495 -18.147449)
			(xy 369.864213 -18.074639) (xy 369.840278 -17.999096) (xy 369.823924 -17.921557) (xy 369.815311 -17.842782)
			(xy 369.814522 -17.763542) (xy 369.821566 -17.684611) (xy 369.836374 -17.606762) (xy 369.858801 -17.530757)
			(xy 369.888627 -17.45734) (xy 369.925561 -17.387228) (xy 369.969241 -17.321109) (xy 370.019239 -17.259629)
			(xy 370.075068 -17.203389) (xy 370.136179 -17.15294) (xy 370.201976 -17.108776) (xy 370.271814 -17.071328)
			(xy 370.34501 -17.040963) (xy 370.420848 -17.017979) (xy 370.498586 -17.0026) (xy 370.577463 -16.994976)
			(xy 370.656708 -16.995183) (xy 370.735544 -17.003217) (xy 370.813201 -17.019002) (xy 370.888918 -17.042381)
			(xy 370.925598 -17.05737) (xy 370.946759 -17.065706) (xy 370.991152 -17.075564) (xy 371.036592 -17.077363)
			(xy 371.081627 -17.071046) (xy 371.124818 -17.056814) (xy 371.164786 -17.035122) (xy 371.200255 -17.006663)
			(xy 371.230093 -16.972345) (xy 371.253347 -16.933265) (xy 371.269273 -16.89067) (xy 371.277364 -16.84592)
			(xy 371.277896 -16.823182) (xy 371.277896 -16.211804) (xy 371.277408 -16.188807) (xy 371.269147 -16.143563)
			(xy 371.252876 -16.100544) (xy 371.229126 -16.061158) (xy 371.198674 -16.02669) (xy 371.162515 -15.998267)
			(xy 371.121829 -15.976819) (xy 371.077947 -15.963045) (xy 371.032303 -15.957395) (xy 370.986387 -15.960055)
			(xy 370.9417 -15.970938) (xy 370.920518 -15.979902) (xy 370.885364 -15.995061) (xy 370.812633 -16.018967)
			(xy 370.737845 -16.035337) (xy 370.661777 -16.044002) (xy 370.585223 -16.04487) (xy 370.508979 -16.037934)
			(xy 370.433838 -16.023264) (xy 370.360583 -16.001014) (xy 370.289977 -15.971415) (xy 370.222754 -15.934776)
			(xy 370.159615 -15.891478) (xy 370.101216 -15.841971) (xy 370.048166 -15.786772) (xy 370.001016 -15.726454)
			(xy 369.960259 -15.661646) (xy 369.926317 -15.593022) (xy 369.899544 -15.521296) (xy 369.880219 -15.447216)
			(xy 369.868544 -15.371552) (xy 369.864639 -15.295093) (xy 369.868545 -15.218633) (xy 369.880222 -15.14297)
			(xy 369.899548 -15.06889) (xy 369.926322 -14.997165) (xy 369.960266 -14.928541) (xy 370.001025 -14.863734)
			(xy 370.048176 -14.803417) (xy 370.101227 -14.748219) (xy 370.159627 -14.698713) (xy 370.222767 -14.655416)
			(xy 370.28999 -14.618778) (xy 370.360597 -14.589181) (xy 370.433852 -14.566933) (xy 370.508993 -14.552264)
			(xy 370.585238 -14.545329) (xy 370.661792 -14.546199) (xy 370.737859 -14.554865) (xy 370.812647 -14.571237)
			(xy 370.885378 -14.595144) (xy 370.920518 -14.610334) (xy 370.941719 -14.619237) (xy 370.986397 -14.630089)
			(xy 371.032298 -14.632728) (xy 371.077926 -14.627068) (xy 371.121791 -14.613293) (xy 371.162463 -14.591852)
			(xy 371.198615 -14.563445) (xy 371.229068 -14.528999) (xy 371.252829 -14.489637) (xy 371.269121 -14.446644)
			(xy 371.277415 -14.40142) (xy 371.277896 -14.378432) (xy 371.277896 -13.767308) (xy 371.277392 -13.744568)
			(xy 371.269299 -13.699815) (xy 371.25337 -13.657216) (xy 371.230114 -13.618133) (xy 371.200273 -13.583812)
			(xy 371.1648 -13.555351) (xy 371.124828 -13.533658) (xy 371.081633 -13.519425) (xy 371.036594 -13.513107)
			(xy 370.991151 -13.514906) (xy 370.946753 -13.524765) (xy 370.925598 -13.53312) (xy 370.888134 -13.54834)
			(xy 370.810815 -13.572038) (xy 370.731501 -13.587821) (xy 370.651 -13.595528) (xy 370.570132 -13.59508)
			(xy 370.489722 -13.586482) (xy 370.410587 -13.56982) (xy 370.333536 -13.545266) (xy 370.259353 -13.513069)
			(xy 370.188793 -13.473558) (xy 370.122577 -13.427134) (xy 370.061378 -13.374271) (xy 370.005819 -13.315508)
			(xy 369.956469 -13.251443) (xy 369.913828 -13.182729) (xy 369.878332 -13.110067) (xy 369.850342 -13.034196)
			(xy 369.830143 -12.95589) (xy 369.817942 -12.875947) (xy 369.813863 -12.795181) (xy 369.817946 -12.714415)
			(xy 369.830151 -12.634472) (xy 369.850353 -12.556167) (xy 369.878347 -12.480297) (xy 369.913847 -12.407637)
			(xy 369.956491 -12.338925) (xy 370.005845 -12.274863) (xy 370.061406 -12.216102) (xy 370.122607 -12.163242)
			(xy 370.188826 -12.116822) (xy 370.259388 -12.077314) (xy 370.333572 -12.04512) (xy 370.410625 -12.02057)
			(xy 370.48976 -12.003912) (xy 370.570171 -11.995318) (xy 370.651039 -11.994874) (xy 370.731539 -12.002584)
			(xy 370.810853 -12.018371) (xy 370.88817 -12.042074) (xy 370.925598 -12.05738) (xy 370.946759 -12.065716)
			(xy 370.991153 -12.075573) (xy 371.036593 -12.077372) (xy 371.081628 -12.071055) (xy 371.12482 -12.056823)
			(xy 371.164789 -12.035132) (xy 371.200259 -12.006673) (xy 371.230097 -11.972355) (xy 371.253352 -11.933275)
			(xy 371.26928 -11.89068) (xy 371.277372 -11.84593) (xy 371.277896 -11.823192) (xy 371.277896 -8.180578)
			(xy 368.152426 -5.055108) (xy 367.8936 -5.055108) (xy 367.872001 -5.055542) (xy 367.829426 -5.062851)
			(xy 367.788702 -5.077259) (xy 367.751003 -5.098349) (xy 367.717416 -5.125515) (xy 367.68891 -5.157972)
			(xy 367.666306 -5.194784) (xy 367.650258 -5.23489) (xy 367.641227 -5.277133) (xy 367.639854 -5.298694)
			(xy 367.638382 -5.324717) (xy 367.629208 -5.376026) (xy 367.613126 -5.425606) (xy 367.590434 -5.47253)
			(xy 367.561556 -5.515922) (xy 367.527033 -5.554972) (xy 367.50752 -5.572252) (xy 367.490616 -5.587454)
			(xy 367.461973 -5.622752) (xy 367.440067 -5.662584) (xy 367.425599 -5.705678) (xy 367.419029 -5.750658)
			(xy 367.420566 -5.796089) (xy 367.430163 -5.840523) (xy 367.447512 -5.882539) (xy 367.472061 -5.920799)
			(xy 367.4872 -5.937758) (xy 367.505502 -5.95813) (xy 367.53668 -6.003152) (xy 367.561101 -6.052168)
			(xy 367.578264 -6.104172) (xy 367.587815 -6.158096) (xy 367.589559 -6.212832) (xy 367.58346 -6.267254)
			(xy 367.569643 -6.320245) (xy 367.548391 -6.370717) (xy 367.520143 -6.417632) (xy 367.485477 -6.460026)
			(xy 367.445106 -6.497029) (xy 367.39986 -6.52788) (xy 367.350668 -6.551946) (xy 367.29854 -6.568731)
			(xy 367.244549 -6.577891) (xy 367.189802 -6.579239) (xy 367.135425 -6.572745) (xy 367.082536 -6.558544)
			(xy 367.032219 -6.536928) (xy 366.98551 -6.50834) (xy 366.943368 -6.473368) (xy 366.906659 -6.43273)
			(xy 366.876137 -6.387261) (xy 366.852428 -6.337896) (xy 366.843818 -6.3119) (xy 366.838534 -6.296679)
			(xy 366.821478 -6.269356) (xy 366.79812 -6.247178) (xy 366.76995 -6.23156) (xy 366.738765 -6.223499)
			(xy 366.72266 -6.223) (xy 365.263684 -6.223) (xy 365.20755 -6.253226) (xy 365.18977 -6.28015) (xy 365.173829 -6.30345)
			(xy 365.136188 -6.345524) (xy 365.092759 -6.381593) (xy 365.04449 -6.410869) (xy 364.992434 -6.432714)
			(xy 364.937728 -6.446652) (xy 364.881565 -6.452377) (xy 364.825171 -6.449765) (xy 364.769778 -6.438873)
			(xy 364.716595 -6.419938) (xy 364.666781 -6.393374) (xy 364.621425 -6.359761) (xy 364.581516 -6.319833)
			(xy 364.547925 -6.27446) (xy 364.521386 -6.224633) (xy 364.502477 -6.17144) (xy 364.491613 -6.116041)
			(xy 364.489028 -6.059647) (xy 364.494781 -6.003487) (xy 364.508745 -5.948787) (xy 364.530616 -5.896742)
			(xy 364.559917 -5.848487) (xy 364.57763 -5.826506) (xy 364.591344 -5.809266) (xy 364.61323 -5.77104)
			(xy 364.628196 -5.729612) (xy 364.635793 -5.686224) (xy 364.635793 -5.642176) (xy 364.628196 -5.598788)
			(xy 364.61323 -5.55736) (xy 364.591344 -5.519134) (xy 364.57763 -5.501894) (xy 364.559331 -5.479045)
			(xy 364.529233 -5.428838) (xy 364.507163 -5.37462) (xy 364.493641 -5.317666) (xy 364.490762 -5.288534)
			(xy 364.488329 -5.264978) (xy 364.475834 -5.219306) (xy 364.455093 -5.176739) (xy 364.426825 -5.138752)
			(xy 364.392009 -5.10666) (xy 364.351849 -5.081573) (xy 364.307737 -5.064362) (xy 364.2612 -5.055622)
			(xy 364.237524 -5.055108) (xy 363.972348 -5.055108) (xy 362.75772 -3.84048) (xy 362.735718 -3.817747)
			(xy 362.697205 -3.767555) (xy 362.665572 -3.712766) (xy 362.641361 -3.654316) (xy 362.624987 -3.593207)
			(xy 362.616729 -3.530483) (xy 362.616729 -3.467217) (xy 362.624987 -3.404493) (xy 362.641361 -3.343384)
			(xy 362.665572 -3.284934) (xy 362.697205 -3.230145) (xy 362.735718 -3.179953) (xy 362.780453 -3.135218)
			(xy 362.830645 -3.096705) (xy 362.885434 -3.065072) (xy 362.943884 -3.040861) (xy 363.004993 -3.024487)
			(xy 363.067717 -3.016229) (xy 363.130983 -3.016229) (xy 363.193707 -3.024487) (xy 363.254816 -3.040861)
			(xy 363.313266 -3.065072) (xy 363.368055 -3.096705) (xy 363.418247 -3.135218) (xy 363.44098 -3.15722)
			(xy 364.372652 -4.088892) (xy 368.55273 -4.088892) (xy 368.687604 -4.223766) (xy 368.703575 -4.23905)
			(xy 368.739775 -4.264415) (xy 368.779816 -4.28314) (xy 368.82249 -4.294662) (xy 368.866513 -4.298633)
			(xy 368.910561 -4.294934) (xy 368.953305 -4.283676) (xy 368.99346 -4.265199) (xy 369.029817 -4.240058)
			(xy 369.06128 -4.209011) (xy 369.074446 -4.191254) (xy 369.092165 -4.167015) (xy 369.132665 -4.122689)
			(xy 369.178348 -4.083726) (xy 369.228509 -4.050727) (xy 369.282374 -4.0242) (xy 369.339112 -4.004555)
			(xy 369.397847 -3.992096) (xy 369.457674 -3.987013) (xy 369.517669 -3.989387) (xy 369.576907 -3.999179)
			(xy 369.634475 -4.016239) (xy 369.689483 -4.040305) (xy 369.741084 -4.071003) (xy 369.788482 -4.107862)
			(xy 369.81003 -4.12877) (xy 373.006112 -7.324852) (xy 373.006112 -9.438132) (xy 373.006607 -9.461172)
			(xy 373.014902 -9.506498) (xy 373.031234 -9.549586) (xy 373.055066 -9.589024) (xy 373.085619 -9.623518)
			(xy 373.121889 -9.651939) (xy 373.16269 -9.673355) (xy 373.206682 -9.687064) (xy 373.252426 -9.692616)
			(xy 373.298421 -9.689831) (xy 373.34316 -9.678798) (xy 373.385177 -9.659881) (xy 373.423095 -9.633698)
			(xy 373.43969 -9.61771) (xy 375.165874 -7.891526) (xy 375.182202 -7.874457) (xy 375.208848 -7.83546)
			(xy 375.227829 -7.792211) (xy 375.238491 -7.7462) (xy 375.240468 -7.69901) (xy 375.233691 -7.652268)
			(xy 375.218393 -7.607584) (xy 375.195102 -7.566495) (xy 375.16462 -7.530418) (xy 375.127996 -7.500594)
			(xy 375.107454 -7.488936) (xy 375.041307 -7.452427) (xy 374.912574 -7.373307) (xy 374.788242 -7.287436)
			(xy 374.668665 -7.195058) (xy 374.554183 -7.096437) (xy 374.445122 -6.991852) (xy 374.341792 -6.881601)
			(xy 374.244487 -6.765999) (xy 374.153484 -6.645372) (xy 374.069041 -6.520066) (xy 373.9914 -6.390436)
			(xy 373.92078 -6.25685) (xy 373.857382 -6.11969) (xy 373.801387 -5.979344) (xy 373.752955 -5.836213)
			(xy 373.712222 -5.690703) (xy 373.679305 -5.543228) (xy 373.654298 -5.394209) (xy 373.637271 -5.244067)
			(xy 373.628273 -5.093232) (xy 373.627329 -4.942132) (xy 373.634443 -4.791196) (xy 373.649594 -4.640854)
			(xy 373.672739 -4.491533) (xy 373.703812 -4.343659) (xy 373.742725 -4.197652) (xy 373.789366 -4.053927)
			(xy 373.843604 -3.912893) (xy 373.905284 -3.774952) (xy 373.974231 -3.640495) (xy 374.050248 -3.509905)
			(xy 374.133119 -3.383554) (xy 374.222609 -3.261801) (xy 374.318463 -3.144992) (xy 374.420408 -3.03346)
			(xy 374.473978 -2.980182) (xy 374.48955 -2.964216) (xy 374.5154 -2.927877) (xy 374.534509 -2.887583)
			(xy 374.546291 -2.844573) (xy 374.550385 -2.800166) (xy 374.546663 -2.755726) (xy 374.535242 -2.712618)
			(xy 374.51647 -2.672166) (xy 374.490926 -2.635612) (xy 374.475502 -2.619502) (xy 373.38 -1.524) (xy 367.903252 -1.524)
			(xy 367.880812 -1.524455) (xy 367.836624 -1.532294) (xy 367.794499 -1.547773) (xy 367.755747 -1.570409)
			(xy 367.721574 -1.599501) (xy 367.693043 -1.634142) (xy 367.671039 -1.673256) (xy 367.656247 -1.715627)
			(xy 367.649128 -1.759938) (xy 367.649902 -1.80481) (xy 367.658546 -1.848848) (xy 367.67479 -1.890684)
			(xy 367.686082 -1.91008) (xy 367.699996 -1.933914) (xy 367.721564 -1.984713) (xy 367.735586 -2.038089)
			(xy 367.74177 -2.092929) (xy 367.739987 -2.148088) (xy 367.730274 -2.202414) (xy 367.712834 -2.254774)
			(xy 367.688031 -2.304074) (xy 367.656382 -2.349285) (xy 367.618549 -2.389464) (xy 367.575321 -2.423771)
			(xy 367.5276 -2.451491) (xy 367.476383 -2.472045) (xy 367.422738 -2.485004) (xy 367.367786 -2.490098)
			(xy 367.312674 -2.48722) (xy 367.258551 -2.47643) (xy 367.206548 -2.457953) (xy 367.157751 -2.432175)
			(xy 367.113177 -2.399635) (xy 367.073758 -2.361011) (xy 367.05667 -2.33934) (xy 367.042501 -2.321581)
			(xy 367.008976 -2.290926) (xy 366.970536 -2.26672) (xy 366.928404 -2.249735) (xy 366.883924 -2.240511)
			(xy 366.838512 -2.239343) (xy 366.793616 -2.246267) (xy 366.750667 -2.261064) (xy 366.711033 -2.283262)
			(xy 366.675977 -2.312152) (xy 366.660938 -2.32918) (xy 366.642448 -2.350284) (xy 366.600341 -2.387365)
			(xy 366.553257 -2.417878) (xy 366.502211 -2.441166) (xy 366.448305 -2.456726) (xy 366.392701 -2.464222)
			(xy 366.336598 -2.463493) (xy 366.281208 -2.454554) (xy 366.227724 -2.437599) (xy 366.177301 -2.412993)
			(xy 366.131025 -2.381266) (xy 366.089896 -2.343103) (xy 366.0548 -2.299328) (xy 366.026495 -2.250885)
			(xy 366.00559 -2.198817) (xy 365.992537 -2.14425) (xy 365.987618 -2.088359) (xy 365.990938 -2.03235)
			(xy 366.002426 -1.977432) (xy 366.021834 -1.924789) (xy 366.034828 -1.89992) (xy 366.044951 -1.880456)
			(xy 366.059086 -1.838926) (xy 366.065878 -1.795586) (xy 366.065126 -1.751723) (xy 366.056852 -1.708641)
			(xy 366.041302 -1.66762) (xy 366.018939 -1.629879) (xy 365.990425 -1.59654) (xy 365.95661 -1.568593)
			(xy 365.918497 -1.546869) (xy 365.87722 -1.532013) (xy 365.834005 -1.524467) (xy 365.81207 -1.524)
			(xy 365.557562 -1.524) (xy 365.540917 -1.524548) (xy 365.508763 -1.533172) (xy 365.479936 -1.549823)
			(xy 365.4564 -1.573366) (xy 365.439757 -1.602198) (xy 365.431143 -1.634355) (xy 365.430562 -1.651)
			(xy 365.430562 -1.681226) (xy 365.457232 -1.734312) (xy 365.481362 -1.7526) (xy 365.5033 -1.769741)
			(xy 365.542446 -1.809327) (xy 365.575422 -1.854182) (xy 365.601527 -1.903354) (xy 365.620207 -1.955799)
			(xy 365.631065 -2.010402) (xy 365.633871 -2.066004) (xy 365.628564 -2.121423) (xy 365.615258 -2.175482)
			(xy 365.594234 -2.227032) (xy 365.565941 -2.274979) (xy 365.530978 -2.318303) (xy 365.490089 -2.356085)
			(xy 365.444142 -2.387522) (xy 365.394113 -2.411946) (xy 365.341066 -2.428839) (xy 365.286126 -2.43784)
			(xy 365.230461 -2.43876) (xy 365.175254 -2.431578) (xy 365.121677 -2.416448) (xy 365.070869 -2.39369)
			(xy 365.023909 -2.363788) (xy 364.981794 -2.327377) (xy 364.945419 -2.285232) (xy 364.915557 -2.238246)
			(xy 364.892842 -2.187418) (xy 364.877757 -2.133829) (xy 364.870622 -2.078615) (xy 364.871589 -2.022951)
			(xy 364.880637 -1.968019) (xy 364.897574 -1.914986) (xy 364.909354 -1.88976) (xy 364.919176 -1.868501)
			(xy 364.93173 -1.823392) (xy 364.935807 -1.776745) (xy 364.93127 -1.730142) (xy 364.918272 -1.685158)
			(xy 364.897254 -1.643317) (xy 364.868925 -1.606034) (xy 364.834246 -1.574572) (xy 364.794391 -1.549995)
			(xy 364.750707 -1.533136) (xy 364.704674 -1.524565) (xy 364.681262 -1.524) (xy 364.584234 -1.524)
			(xy 364.568884 -1.524502) (xy 364.539088 -1.531913) (xy 364.51192 -1.546218) (xy 364.488949 -1.566591)
			(xy 364.471502 -1.591856) (xy 364.465616 -1.606042) (xy 364.44047 -1.672336) (xy 364.435154 -1.687805)
			(xy 364.431749 -1.720325) (xy 364.436747 -1.752638) (xy 364.449818 -1.782609) (xy 364.45952 -1.79578)
			(xy 364.476322 -1.8179) (xy 364.504024 -1.866046) (xy 364.524451 -1.917699) (xy 364.537172 -1.971769)
			(xy 364.541918 -2.027112) (xy 364.538589 -2.082559) (xy 364.527256 -2.136937) (xy 364.508157 -2.189096)
			(xy 364.481696 -2.237935) (xy 364.448433 -2.282421) (xy 364.409071 -2.321613) (xy 364.364442 -2.354683)
			(xy 364.31549 -2.380932) (xy 364.263248 -2.399806) (xy 364.208822 -2.410904) (xy 364.153362 -2.413994)
			(xy 364.09804 -2.409008) (xy 364.044025 -2.396053) (xy 363.99246 -2.375403) (xy 363.944434 -2.347494)
			(xy 363.900963 -2.312916) (xy 363.862966 -2.272399) (xy 363.831245 -2.226802) (xy 363.806471 -2.177086)
			(xy 363.789168 -2.124303) (xy 363.779702 -2.06957) (xy 363.778273 -2.014042) (xy 363.78491 -1.958893)
			(xy 363.799474 -1.90529) (xy 363.810042 -1.8796) (xy 363.818753 -1.858416) (xy 363.829252 -1.813837)
			(xy 363.831595 -1.768097) (xy 363.825704 -1.722678) (xy 363.811771 -1.67905) (xy 363.790247 -1.638624)
			(xy 363.761828 -1.602708) (xy 363.727433 -1.572465) (xy 363.688177 -1.548874) (xy 363.64533 -1.532698)
			(xy 363.600277 -1.524461) (xy 363.577378 -1.524) (xy 350.7486 -1.524) (xy 350.2406 -2.032) (xy 350.2406 -3.481556)
			(xy 352.901959 -3.481556) (xy 352.909229 -3.427489) (xy 352.924128 -3.375009) (xy 352.94635 -3.325186)
			(xy 352.975444 -3.279037) (xy 353.010815 -3.237503) (xy 353.051742 -3.201432) (xy 353.09739 -3.171558)
			(xy 353.146828 -3.148493) (xy 353.199048 -3.132705) (xy 353.252984 -3.124517) (xy 353.307537 -3.124096)
			(xy 353.361593 -3.131451) (xy 353.41405 -3.146431) (xy 353.463838 -3.168731) (xy 353.509942 -3.197897)
			(xy 353.551421 -3.233332) (xy 353.587428 -3.274315) (xy 353.61723 -3.32001) (xy 353.640219 -3.369484)
			(xy 353.648518 -3.395472) (xy 353.655923 -3.418289) (xy 353.678144 -3.460799) (xy 353.707936 -3.498392)
			(xy 353.744245 -3.529737) (xy 353.785783 -3.553724) (xy 353.831081 -3.569503) (xy 353.878532 -3.576515)
			(xy 353.902518 -3.576066) (xy 353.921759 -3.575508) (xy 353.960187 -3.577799) (xy 353.979226 -3.580638)
			(xy 353.995867 -3.582799) (xy 354.029232 -3.579321) (xy 354.060546 -3.567291) (xy 354.087658 -3.547534)
			(xy 354.108702 -3.52141) (xy 354.122233 -3.490714) (xy 354.125276 -3.474212) (xy 354.129836 -3.446866)
			(xy 354.145883 -3.393801) (xy 354.169443 -3.343617) (xy 354.20002 -3.297372) (xy 354.236969 -3.256041)
			(xy 354.279511 -3.220494) (xy 354.326752 -3.19148) (xy 354.377695 -3.169611) (xy 354.431267 -3.155346)
			(xy 354.48634 -3.148987) (xy 354.541754 -3.150668) (xy 354.59634 -3.160352) (xy 354.64895 -3.177837)
			(xy 354.698474 -3.202753) (xy 354.74387 -3.234576) (xy 354.784181 -3.272636) (xy 354.818557 -3.31613)
			(xy 354.846275 -3.364142) (xy 354.866751 -3.415661) (xy 354.879553 -3.469602) (xy 354.884411 -3.524827)
			(xy 354.881224 -3.580175) (xy 354.870058 -3.634478) (xy 354.851149 -3.686592) (xy 354.824895 -3.73542)
			(xy 354.791848 -3.779933) (xy 354.752706 -3.819194) (xy 354.708293 -3.852374) (xy 354.659545 -3.878776)
			(xy 354.607487 -3.897843) (xy 354.553219 -3.909173) (xy 354.52558 -3.911346) (xy 354.509621 -3.91275)
			(xy 354.479136 -3.922577) (xy 354.45206 -3.939688) (xy 354.430101 -3.963006) (xy 354.414644 -3.991058)
			(xy 354.406662 -4.022077) (xy 354.4062 -4.038092) (xy 354.4062 -5.232908) (xy 354.406679 -5.248921)
			(xy 354.41466 -5.279935) (xy 354.430115 -5.307984) (xy 354.452071 -5.331298) (xy 354.479143 -5.348407)
			(xy 354.509624 -5.358233) (xy 354.52558 -5.359654) (xy 354.553358 -5.361883) (xy 354.607896 -5.373324)
			(xy 354.660189 -5.392578) (xy 354.709125 -5.419234) (xy 354.753663 -5.452725) (xy 354.792855 -5.49234)
			(xy 354.825866 -5.537234) (xy 354.851995 -5.586453) (xy 354.870687 -5.63895) (xy 354.881542 -5.693608)
			(xy 354.88433 -5.749263) (xy 354.878992 -5.804731) (xy 354.865642 -5.858834) (xy 354.844563 -5.910418)
			(xy 354.816203 -5.958387) (xy 354.781168 -6.00172) (xy 354.740201 -6.039495) (xy 354.694174 -6.070909)
			(xy 354.644067 -6.095293) (xy 354.590946 -6.112128) (xy 354.53594 -6.121055) (xy 354.480222 -6.121886)
			(xy 354.424975 -6.114603) (xy 354.371375 -6.099359) (xy 354.320563 -6.07648) (xy 354.27362 -6.046453)
			(xy 354.231545 -6.009916) (xy 354.195233 -5.967647) (xy 354.165456 -5.920545) (xy 354.142848 -5.869612)
			(xy 354.12789 -5.815932) (xy 354.120901 -5.760647) (xy 354.120958 -5.73278) (xy 354.120796 -5.716966)
			(xy 354.113645 -5.686169) (xy 354.099142 -5.658076) (xy 354.078176 -5.634412) (xy 354.052035 -5.61663)
			(xy 354.022324 -5.605822) (xy 353.990868 -5.602652) (xy 353.975162 -5.60451) (xy 353.962284 -5.606365)
			(xy 353.936353 -5.608529) (xy 353.923346 -5.608828) (xy 353.899353 -5.609748) (xy 353.852329 -5.619413)
			(xy 353.807953 -5.637729) (xy 353.767802 -5.664045) (xy 353.733301 -5.697427) (xy 353.705675 -5.736688)
			(xy 353.685905 -5.780436) (xy 353.67976 -5.803646) (xy 353.673001 -5.830128) (xy 353.652846 -5.880932)
			(xy 353.625648 -5.92834) (xy 353.591964 -5.971382) (xy 353.552482 -6.009177) (xy 353.508012 -6.040952)
			(xy 353.459463 -6.066057) (xy 353.407828 -6.083977) (xy 353.354165 -6.094345) (xy 353.299571 -6.096951)
			(xy 353.245164 -6.09174) (xy 353.192058 -6.078819) (xy 353.141338 -6.058453) (xy 353.094044 -6.031058)
			(xy 353.051142 -5.997195) (xy 353.013512 -5.957557) (xy 352.981922 -5.912955) (xy 352.95702 -5.864301)
			(xy 352.939314 -5.812593) (xy 352.929169 -5.758887) (xy 352.92679 -5.704283) (xy 352.932227 -5.649898)
			(xy 352.945369 -5.596846) (xy 352.965946 -5.546211) (xy 352.993537 -5.499031) (xy 353.027578 -5.456271)
			(xy 353.067373 -5.418805) (xy 353.112106 -5.387401) (xy 353.160862 -5.362702) (xy 353.212644 -5.345212)
			(xy 353.266392 -5.33529) (xy 353.29368 -5.333746) (xy 353.309859 -5.332634) (xy 353.340871 -5.323176)
			(xy 353.368504 -5.306215) (xy 353.390976 -5.282844) (xy 353.406842 -5.254569) (xy 353.415078 -5.22321)
			(xy 353.4156 -5.207) (xy 353.4156 -4.013708) (xy 353.415091 -3.996947) (xy 353.406363 -3.964582)
			(xy 353.389507 -3.935607) (xy 353.365686 -3.912022) (xy 353.336545 -3.895455) (xy 353.304095 -3.887049)
			(xy 353.28733 -3.886708) (xy 353.26005 -3.886578) (xy 353.205971 -3.879392) (xy 353.153468 -3.864575)
			(xy 353.10361 -3.84243) (xy 353.057416 -3.813408) (xy 353.015827 -3.778101) (xy 352.979692 -3.737231)
			(xy 352.949748 -3.691629) (xy 352.926605 -3.642227) (xy 352.910736 -3.590032) (xy 352.902464 -3.536108)
			(xy 352.901959 -3.481556) (xy 350.2406 -3.481556) (xy 350.2406 -8.213481) (xy 357.884059 -8.213481)
			(xy 357.886189 -8.133889) (xy 357.89621 -8.054902) (xy 357.914021 -7.9773) (xy 357.939447 -7.901848)
			(xy 357.972237 -7.829294) (xy 358.012067 -7.760352) (xy 358.058543 -7.695704) (xy 358.111206 -7.635988)
			(xy 358.169537 -7.581795) (xy 358.232959 -7.533659) (xy 358.300845 -7.492056) (xy 358.372526 -7.457397)
			(xy 358.447293 -7.430025) (xy 358.524408 -7.410208) (xy 358.603108 -7.398144) (xy 358.682618 -7.393951)
			(xy 358.762151 -7.397671) (xy 358.840923 -7.409267) (xy 358.918154 -7.428625) (xy 358.993082 -7.455553)
			(xy 359.064968 -7.489785) (xy 359.133101 -7.530983) (xy 359.196807 -7.578741) (xy 359.255459 -7.632587)
			(xy 359.308477 -7.691988) (xy 359.355336 -7.756358) (xy 359.395575 -7.825062) (xy 359.428796 -7.897421)
			(xy 359.45467 -7.972719) (xy 359.472942 -8.050215) (xy 359.483433 -8.129141) (xy 359.486037 -8.208718)
			(xy 359.480729 -8.288161) (xy 359.467562 -8.366685) (xy 359.446666 -8.443515) (xy 359.418247 -8.51789)
			(xy 359.400856 -8.553704) (xy 359.387394 -8.580628) (xy 359.387394 -8.6106) (xy 359.387943 -8.627248)
			(xy 359.39656 -8.659409) (xy 359.413208 -8.688244) (xy 359.436751 -8.711788) (xy 359.465585 -8.728437)
			(xy 359.497746 -8.737056) (xy 359.514394 -8.7376) (xy 359.66527 -8.7376) (xy 359.681003 -8.737187)
			(xy 359.711518 -8.729522) (xy 359.73922 -8.714602) (xy 359.762413 -8.693342) (xy 359.771442 -8.68045)
			(xy 359.787337 -8.657221) (xy 359.824815 -8.615229) (xy 359.868056 -8.579201) (xy 359.916122 -8.549917)
			(xy 359.96797 -8.528014) (xy 360.022472 -8.513967) (xy 360.078448 -8.508081) (xy 360.13468 -8.510484)
			(xy 360.189949 -8.521123) (xy 360.243055 -8.539769) (xy 360.292845 -8.566015) (xy 360.338238 -8.599292)
			(xy 360.378248 -8.638878) (xy 360.412007 -8.683913) (xy 360.438783 -8.73342) (xy 360.457993 -8.786324)
			(xy 360.4641 -8.8138) (xy 360.468112 -8.830768) (xy 360.484075 -8.861754) (xy 360.507819 -8.887272)
			(xy 360.537576 -8.905422) (xy 360.571132 -8.914854) (xy 360.58856 -8.9154) (xy 362.005118 -8.9154)
			(xy 362.075222 -8.85825) (xy 362.084112 -8.8138) (xy 362.090242 -8.786281) (xy 362.109507 -8.733296)
			(xy 362.136359 -8.683723) (xy 362.170212 -8.638641) (xy 362.210331 -8.59903) (xy 362.255842 -8.565754)
			(xy 362.305753 -8.539537) (xy 362.358979 -8.52095) (xy 362.414361 -8.510396) (xy 362.442506 -8.508746)
			(xy 362.464871 -8.507379) (xy 362.508619 -8.497704) (xy 362.549992 -8.480507) (xy 362.587709 -8.456321)
			(xy 362.6206 -8.425896) (xy 362.647646 -8.390175) (xy 362.668009 -8.350265) (xy 362.681057 -8.307402)
			(xy 362.686387 -8.262915) (xy 362.685584 -8.240522) (xy 362.683804 -8.200599) (xy 362.687243 -8.120754)
			(xy 362.69862 -8.041648) (xy 362.717821 -7.96407) (xy 362.744657 -7.888791) (xy 362.77886 -7.81656)
			(xy 362.82009 -7.748097) (xy 362.867936 -7.684082) (xy 362.921921 -7.625153) (xy 362.98151 -7.571896)
			(xy 363.046109 -7.524841) (xy 363.115074 -7.484457) (xy 363.18772 -7.451145) (xy 363.263323 -7.425237)
			(xy 363.341132 -7.406991) (xy 363.420371 -7.396589) (xy 363.500253 -7.394133) (xy 363.579982 -7.399648)
			(xy 363.658765 -7.41308) (xy 363.735817 -7.434294) (xy 363.810372 -7.46308) (xy 363.881688 -7.499152)
			(xy 363.949055 -7.542149) (xy 364.011803 -7.591645) (xy 364.069307 -7.647146) (xy 364.120995 -7.708101)
			(xy 364.166352 -7.773902) (xy 364.204928 -7.843895) (xy 364.236337 -7.917384) (xy 364.260269 -7.993636)
			(xy 364.276484 -8.071893) (xy 364.28482 -8.151376) (xy 364.285196 -8.231295) (xy 364.277608 -8.310853)
			(xy 364.26213 -8.389259) (xy 364.238917 -8.465733) (xy 364.2082 -8.539514) (xy 364.170285 -8.609867)
			(xy 364.125549 -8.676092) (xy 364.100364 -8.70712) (xy 364.09044 -8.719692) (xy 364.076713 -8.748623)
			(xy 364.070625 -8.780061) (xy 364.072559 -8.812025) (xy 364.082394 -8.8425) (xy 364.099509 -8.869565)
			(xy 364.122826 -8.891514) (xy 364.150876 -8.906963) (xy 364.181889 -8.914939) (xy 364.1979 -8.9154)
			(xy 364.437422 -8.9154) (xy 364.507526 -8.85825) (xy 364.516416 -8.8138) (xy 364.522384 -8.786929)
			(xy 364.541012 -8.735134) (xy 364.566888 -8.686553) (xy 364.599476 -8.642194) (xy 364.6381 -8.602978)
			(xy 364.681957 -8.569719) (xy 364.730139 -8.543106) (xy 364.781644 -8.523692) (xy 364.835404 -8.51188)
			(xy 364.890304 -8.507916) (xy 364.945204 -8.51188) (xy 364.998964 -8.523692) (xy 365.050469 -8.543106)
			(xy 365.098651 -8.569719) (xy 365.142508 -8.602978) (xy 365.181132 -8.642194) (xy 365.21372 -8.686553)
			(xy 365.239596 -8.735134) (xy 365.258224 -8.786929) (xy 365.264192 -8.8138) (xy 365.268211 -8.830766)
			(xy 365.284173 -8.861751) (xy 365.307915 -8.887269) (xy 365.337671 -8.90542) (xy 365.371225 -8.914853)
			(xy 365.388652 -8.9154) (xy 366.805718 -8.9154) (xy 366.875822 -8.85825) (xy 366.884712 -8.8138)
			(xy 366.890815 -8.786302) (xy 366.910053 -8.733365) (xy 366.936865 -8.683831) (xy 366.970667 -8.638776)
			(xy 367.010724 -8.599179) (xy 367.056167 -8.565901) (xy 367.106008 -8.539664) (xy 367.159165 -8.521039)
			(xy 367.214481 -8.510431) (xy 367.242598 -8.508746) (xy 367.264963 -8.507372) (xy 367.30871 -8.497698)
			(xy 367.350084 -8.480502) (xy 367.3878 -8.456318) (xy 367.420692 -8.425894) (xy 367.447738 -8.390173)
			(xy 367.468101 -8.350264) (xy 367.481149 -8.307401) (xy 367.486479 -8.262915) (xy 367.485676 -8.240522)
			(xy 367.483942 -8.200143) (xy 367.487511 -8.119397) (xy 367.499198 -8.039422) (xy 367.518885 -7.961031)
			(xy 367.546371 -7.885024) (xy 367.581376 -7.812173) (xy 367.623544 -7.74322) (xy 367.672445 -7.678867)
			(xy 367.727582 -7.619769) (xy 367.788394 -7.566528) (xy 367.854261 -7.519686) (xy 367.924513 -7.47972)
			(xy 367.998434 -7.447036) (xy 368.075273 -7.421967) (xy 368.154247 -7.404769) (xy 368.234552 -7.395616)
			(xy 368.31537 -7.394602) (xy 368.395879 -7.401736) (xy 368.47526 -7.416948) (xy 368.552703 -7.44008)
			(xy 368.627422 -7.470899) (xy 368.698654 -7.50909) (xy 368.765676 -7.554264) (xy 368.827805 -7.605962)
			(xy 368.884407 -7.663658) (xy 368.934908 -7.726763) (xy 368.978793 -7.794636) (xy 369.015615 -7.866586)
			(xy 369.045 -7.94188) (xy 369.066648 -8.019752) (xy 369.080338 -8.099409) (xy 369.085933 -8.18004)
			(xy 369.083374 -8.260824) (xy 369.072687 -8.340939) (xy 369.053982 -8.419569) (xy 369.027449 -8.495915)
			(xy 368.993358 -8.569198) (xy 368.952055 -8.638673) (xy 368.903963 -8.703632) (xy 368.849569 -8.763415)
			(xy 368.789428 -8.817412) (xy 368.724152 -8.865074) (xy 368.654405 -8.905916) (xy 368.580898 -8.939522)
			(xy 368.504379 -8.96555) (xy 368.425627 -8.983734) (xy 368.385598 -8.989314) (xy 368.337846 -8.99541)
			(xy 368.2746 -9.067038) (xy 368.2746 -12.0396) (xy 367.483644 -12.0396) (xy 367.457228 -12.0523)
			(xy 367.431099 -12.06443) (xy 367.376101 -12.081561) (xy 367.319152 -12.090224) (xy 367.261548 -12.090224)
			(xy 367.204599 -12.081561) (xy 367.149601 -12.06443) (xy 367.123472 -12.0523) (xy 367.097056 -12.0396)
			(xy 365.083598 -12.0396) (xy 365.057182 -12.0523) (xy 365.031053 -12.06443) (xy 364.976055 -12.081561)
			(xy 364.919106 -12.090224) (xy 364.861502 -12.090224) (xy 364.804553 -12.081561) (xy 364.749555 -12.06443)
			(xy 364.723426 -12.0523) (xy 364.69701 -12.0396) (xy 364.283498 -12.0396) (xy 364.257082 -12.0523)
			(xy 364.230953 -12.06443) (xy 364.175955 -12.081561) (xy 364.119006 -12.090224) (xy 364.061402 -12.090224)
			(xy 364.004453 -12.081561) (xy 363.949455 -12.06443) (xy 363.923326 -12.0523) (xy 363.89691 -12.0396)
			(xy 363.483652 -12.0396) (xy 363.457236 -12.0523) (xy 363.431107 -12.06443) (xy 363.376109 -12.081561)
			(xy 363.31916 -12.090224) (xy 363.261556 -12.090224) (xy 363.204607 -12.081561) (xy 363.149609 -12.06443)
			(xy 363.12348 -12.0523) (xy 363.097064 -12.0396) (xy 362.683552 -12.0396) (xy 362.657136 -12.0523)
			(xy 362.631007 -12.06443) (xy 362.576009 -12.081561) (xy 362.51906 -12.090224) (xy 362.461456 -12.090224)
			(xy 362.404507 -12.081561) (xy 362.349509 -12.06443) (xy 362.32338 -12.0523) (xy 362.296964 -12.0396)
			(xy 360.283506 -12.0396) (xy 360.25709 -12.0523) (xy 360.230961 -12.06443) (xy 360.175963 -12.081561)
			(xy 360.119014 -12.090224) (xy 360.06141 -12.090224) (xy 360.004461 -12.081561) (xy 359.949463 -12.06443)
			(xy 359.923334 -12.0523) (xy 359.896918 -12.0396) (xy 359.5116 -12.0396) (xy 359.5116 -10.0584) (xy 359.511057 -10.041752)
			(xy 359.502439 -10.009589) (xy 359.485791 -9.980754) (xy 359.462246 -9.957209) (xy 359.433411 -9.940561)
			(xy 359.401248 -9.931943) (xy 359.3846 -9.9314) (xy 358.6226 -9.9314) (xy 358.6226 -9.057894) (xy 358.565958 -8.988044)
			(xy 358.521508 -8.9789) (xy 358.48264 -8.970275) (xy 358.406696 -8.94636) (xy 358.333501 -8.915026)
			(xy 358.263778 -8.876581) (xy 358.198214 -8.831406) (xy 358.137459 -8.779945) (xy 358.082112 -8.722709)
			(xy 358.032719 -8.660261) (xy 357.989769 -8.593219) (xy 357.953685 -8.522244) (xy 357.924824 -8.448039)
			(xy 357.903472 -8.371335) (xy 357.889838 -8.292891) (xy 357.884059 -8.213481) (xy 350.2406 -8.213481)
			(xy 350.2406 -10.295128) (xy 355.462344 -10.295128) (xy 355.46631 -10.210597) (xy 355.478175 -10.12681)
			(xy 355.497833 -10.044501) (xy 355.525113 -9.964395) (xy 355.559774 -9.887196) (xy 355.601512 -9.813581)
			(xy 355.649959 -9.744198) (xy 355.704691 -9.679657) (xy 355.765227 -9.620525) (xy 355.831033 -9.567321)
			(xy 355.901533 -9.520513) (xy 355.976105 -9.480512) (xy 356.054096 -9.44767) (xy 356.13482 -9.422276)
			(xy 356.217567 -9.404553) (xy 356.301609 -9.394655) (xy 356.38621 -9.392672) (xy 356.470624 -9.398619)
			(xy 356.554111 -9.412444) (xy 356.635936 -9.434027) (xy 356.71538 -9.463177) (xy 356.791746 -9.499638)
			(xy 356.864362 -9.54309) (xy 356.93259 -9.593151) (xy 356.99583 -9.649381) (xy 357.053527 -9.711286)
			(xy 357.105174 -9.778322) (xy 357.150316 -9.849899) (xy 357.188558 -9.925389) (xy 357.219562 -10.004128)
			(xy 357.243057 -10.085425) (xy 357.258836 -10.168564) (xy 357.26676 -10.252816) (xy 357.267256 -10.295128)
			(xy 357.26676 -10.33744) (xy 357.258836 -10.421692) (xy 357.243057 -10.504831) (xy 357.219562 -10.586128)
			(xy 357.188558 -10.664867) (xy 357.150316 -10.740357) (xy 357.105174 -10.811934) (xy 357.053527 -10.87897)
			(xy 356.99583 -10.940875) (xy 356.93259 -10.997105) (xy 356.864362 -11.047166) (xy 356.791746 -11.090618)
			(xy 356.71538 -11.127079) (xy 356.635936 -11.156229) (xy 356.554111 -11.177812) (xy 356.470624 -11.191637)
			(xy 356.38621 -11.197584) (xy 356.301609 -11.195601) (xy 356.217567 -11.185703) (xy 356.13482 -11.16798)
			(xy 356.054096 -11.142586) (xy 355.976105 -11.109744) (xy 355.901533 -11.069743) (xy 355.831033 -11.022935)
			(xy 355.765227 -10.969731) (xy 355.704691 -10.910599) (xy 355.649959 -10.846058) (xy 355.601512 -10.776675)
			(xy 355.559774 -10.70306) (xy 355.525113 -10.625861) (xy 355.497833 -10.545755) (xy 355.478175 -10.463446)
			(xy 355.46631 -10.379659) (xy 355.462344 -10.295128) (xy 350.2406 -10.295128) (xy 350.2406 -12.79525)
			(xy 355.563942 -12.79525) (xy 355.567923 -12.715486) (xy 355.579826 -12.636514) (xy 355.599533 -12.55912)
			(xy 355.626848 -12.484073) (xy 355.661499 -12.412118) (xy 355.703143 -12.343971) (xy 355.751365 -12.280309)
			(xy 355.805686 -12.221765) (xy 355.865567 -12.16892) (xy 355.930411 -12.1223) (xy 355.999575 -12.082368)
			(xy 356.072371 -12.049521) (xy 356.148076 -12.024086) (xy 356.225937 -12.006315) (xy 356.305181 -11.996384)
			(xy 356.38502 -11.994393) (xy 356.46466 -12.000361) (xy 356.543311 -12.014229) (xy 356.62019 -12.03586)
			(xy 356.694533 -12.065037) (xy 356.765601 -12.101472) (xy 356.832689 -12.144802) (xy 356.895128 -12.194596)
			(xy 356.9523 -12.25036) (xy 357.003636 -12.311539) (xy 357.048624 -12.377525) (xy 357.08682 -12.447663)
			(xy 357.117841 -12.521256) (xy 357.141382 -12.597571) (xy 357.157206 -12.675851) (xy 357.165158 -12.755318)
			(xy 357.165656 -12.79525) (xy 357.165158 -12.835182) (xy 357.157206 -12.914649) (xy 357.141382 -12.992929)
			(xy 357.117841 -13.069244) (xy 357.08682 -13.142837) (xy 357.048624 -13.212975) (xy 357.003636 -13.278961)
			(xy 356.9523 -13.34014) (xy 356.895128 -13.395904) (xy 356.832689 -13.445698) (xy 356.765601 -13.489028)
			(xy 356.694533 -13.525463) (xy 356.62019 -13.55464) (xy 356.543311 -13.576271) (xy 356.46466 -13.590139)
			(xy 356.38502 -13.596107) (xy 356.305181 -13.594116) (xy 356.225937 -13.584185) (xy 356.148076 -13.566414)
			(xy 356.072371 -13.540979) (xy 355.999575 -13.508132) (xy 355.930411 -13.4682) (xy 355.865567 -13.42158)
			(xy 355.805686 -13.368735) (xy 355.751365 -13.310191) (xy 355.703143 -13.246529) (xy 355.661499 -13.178382)
			(xy 355.626848 -13.106427) (xy 355.599533 -13.03138) (xy 355.579826 -12.953986) (xy 355.567923 -12.875014)
			(xy 355.563942 -12.79525) (xy 350.2406 -12.79525) (xy 350.2406 -14.439005) (xy 357.470189 -14.439005)
			(xy 357.470189 -14.340719) (xy 357.478098 -14.242752) (xy 357.493864 -14.145739) (xy 357.517385 -14.05031)
			(xy 357.548509 -13.957082) (xy 357.587034 -13.866661) (xy 357.632709 -13.779634) (xy 357.68524 -13.696563)
			(xy 357.744284 -13.61799) (xy 357.809459 -13.544422) (xy 357.880343 -13.476337) (xy 357.956476 -13.414176)
			(xy 358.037363 -13.358344) (xy 358.122481 -13.309201) (xy 358.211278 -13.267067) (xy 358.303176 -13.232214)
			(xy 358.397582 -13.204869) (xy 358.493881 -13.18521) (xy 358.59145 -13.173363) (xy 358.689656 -13.169405)
			(xy 358.787862 -13.173363) (xy 358.885431 -13.18521) (xy 358.98173 -13.204869) (xy 359.076136 -13.232214)
			(xy 359.168034 -13.267067) (xy 359.256831 -13.309201) (xy 359.341949 -13.358344) (xy 359.422836 -13.414176)
			(xy 359.498969 -13.476337) (xy 359.569853 -13.544422) (xy 359.635028 -13.61799) (xy 359.694072 -13.696563)
			(xy 359.746603 -13.779634) (xy 359.792278 -13.866661) (xy 359.830803 -13.957082) (xy 359.861927 -14.05031)
			(xy 359.885448 -14.145739) (xy 359.901214 -14.242752) (xy 359.909123 -14.340719) (xy 359.909618 -14.389862)
			(xy 359.909123 -14.439005) (xy 359.901214 -14.536972) (xy 359.885448 -14.633985) (xy 359.861927 -14.729414)
			(xy 359.856569 -14.745462) (xy 367.401348 -14.745462) (xy 367.401348 -14.059662) (xy 367.401852 -14.017314)
			(xy 367.409903 -13.933) (xy 367.425932 -13.849834) (xy 367.449793 -13.768567) (xy 367.481272 -13.689937)
			(xy 367.520083 -13.614656) (xy 367.565873 -13.543404) (xy 367.618229 -13.476828) (xy 367.676677 -13.41553)
			(xy 367.740687 -13.360065) (xy 367.809679 -13.310936) (xy 367.883029 -13.268587) (xy 367.960072 -13.233403)
			(xy 368.040111 -13.205701) (xy 368.12242 -13.185733) (xy 368.206255 -13.17368) (xy 368.290856 -13.16965)
			(xy 368.375457 -13.17368) (xy 368.459292 -13.185733) (xy 368.541601 -13.205701) (xy 368.62164 -13.233403)
			(xy 368.698683 -13.268587) (xy 368.772033 -13.310936) (xy 368.841025 -13.360065) (xy 368.905035 -13.41553)
			(xy 368.963483 -13.476828) (xy 369.015839 -13.543404) (xy 369.061629 -13.614656) (xy 369.10044 -13.689937)
			(xy 369.131919 -13.768567) (xy 369.15578 -13.849834) (xy 369.171809 -13.933) (xy 369.17986 -14.017314)
			(xy 369.180364 -14.059662) (xy 369.180364 -14.694662) (xy 369.179898 -14.73694) (xy 369.1721 -14.821134)
			(xy 369.156565 -14.90425) (xy 369.133428 -14.985578) (xy 369.102885 -15.064424) (xy 369.065196 -15.140115)
			(xy 369.020685 -15.212005) (xy 368.969729 -15.279482) (xy 368.912765 -15.341969) (xy 368.850277 -15.398933)
			(xy 368.7828 -15.449888) (xy 368.71091 -15.494399) (xy 368.635218 -15.532087) (xy 368.556372 -15.56263)
			(xy 368.475044 -15.585767) (xy 368.391928 -15.601301) (xy 368.307734 -15.609099) (xy 368.265456 -15.60957)
			(xy 368.223029 -15.609129) (xy 368.138583 -15.600808) (xy 368.05536 -15.584249) (xy 367.97416 -15.559613)
			(xy 367.895766 -15.527137) (xy 367.820933 -15.487133) (xy 367.750381 -15.439987) (xy 367.684791 -15.386153)
			(xy 367.624792 -15.326149) (xy 367.570964 -15.260553) (xy 367.523825 -15.189996) (xy 367.483828 -15.115159)
			(xy 367.451359 -15.036763) (xy 367.426731 -14.955561) (xy 367.41018 -14.872336) (xy 367.401867 -14.787889)
			(xy 367.401348 -14.745462) (xy 359.856569 -14.745462) (xy 359.830803 -14.822642) (xy 359.792278 -14.913063)
			(xy 359.746603 -15.000091) (xy 359.694072 -15.083161) (xy 359.635028 -15.161734) (xy 359.569853 -15.235302)
			(xy 359.498969 -15.303387) (xy 359.422836 -15.365548) (xy 359.341949 -15.42138) (xy 359.256831 -15.470523)
			(xy 359.168034 -15.512657) (xy 359.076136 -15.54751) (xy 358.98173 -15.574855) (xy 358.885431 -15.594514)
			(xy 358.787862 -15.606361) (xy 358.689656 -15.610319) (xy 358.59145 -15.606361) (xy 358.493881 -15.594514)
			(xy 358.397582 -15.574855) (xy 358.303176 -15.54751) (xy 358.211278 -15.512657) (xy 358.122481 -15.470523)
			(xy 358.037363 -15.42138) (xy 357.956476 -15.365548) (xy 357.880343 -15.303387) (xy 357.809459 -15.235302)
			(xy 357.744284 -15.161734) (xy 357.68524 -15.083161) (xy 357.632709 -15.000091) (xy 357.587034 -14.913063)
			(xy 357.548509 -14.822642) (xy 357.517385 -14.729414) (xy 357.493864 -14.633985) (xy 357.478098 -14.536972)
			(xy 357.470189 -14.439005) (xy 350.2406 -14.439005) (xy 350.2406 -17.79524) (xy 355.563942 -17.79524)
			(xy 355.567923 -17.715476) (xy 355.579826 -17.636504) (xy 355.599533 -17.55911) (xy 355.626848 -17.484063)
			(xy 355.661499 -17.412108) (xy 355.703143 -17.343961) (xy 355.751365 -17.280299) (xy 355.805686 -17.221755)
			(xy 355.865567 -17.16891) (xy 355.930411 -17.12229) (xy 355.999575 -17.082358) (xy 356.072371 -17.049511)
			(xy 356.148076 -17.024076) (xy 356.225937 -17.006305) (xy 356.305181 -16.996374) (xy 356.38502 -16.994383)
			(xy 356.46466 -17.000351) (xy 356.543311 -17.014219) (xy 356.62019 -17.03585) (xy 356.694533 -17.065027)
			(xy 356.765601 -17.101462) (xy 356.832689 -17.144792) (xy 356.895128 -17.194586) (xy 356.9523 -17.25035)
			(xy 357.003636 -17.311529) (xy 357.048624 -17.377515) (xy 357.08682 -17.447653) (xy 357.117841 -17.521246)
			(xy 357.141382 -17.597561) (xy 357.157206 -17.675841) (xy 357.165158 -17.755308) (xy 357.165656 -17.79524)
			(xy 357.165158 -17.835172) (xy 357.157206 -17.914639) (xy 357.141382 -17.992919) (xy 357.117841 -18.069234)
			(xy 357.08682 -18.142827) (xy 357.048624 -18.212965) (xy 357.003636 -18.278951) (xy 356.9523 -18.34013)
			(xy 356.895128 -18.395894) (xy 356.832689 -18.445688) (xy 356.765601 -18.489018) (xy 356.694533 -18.525453)
			(xy 356.62019 -18.55463) (xy 356.543311 -18.576261) (xy 356.46466 -18.590129) (xy 356.38502 -18.596097)
			(xy 356.305181 -18.594106) (xy 356.225937 -18.584175) (xy 356.148076 -18.566404) (xy 356.072371 -18.540969)
			(xy 355.999575 -18.508122) (xy 355.930411 -18.46819) (xy 355.865567 -18.42157) (xy 355.805686 -18.368725)
			(xy 355.751365 -18.310181) (xy 355.703143 -18.246519) (xy 355.661499 -18.178372) (xy 355.626848 -18.106417)
			(xy 355.599533 -18.03137) (xy 355.579826 -17.953976) (xy 355.567923 -17.875004) (xy 355.563942 -17.79524)
			(xy 350.2406 -17.79524) (xy 350.2406 -19.1008) (xy 349.594932 -19.746468) (xy 349.583469 -19.758577)
			(xy 349.56675 -19.787414) (xy 349.55809 -19.819603) (xy 349.558082 -19.852936) (xy 349.566727 -19.885129)
			(xy 349.583432 -19.913975) (xy 349.594932 -19.926046) (xy 349.963949 -20.295108) (xy 355.462344 -20.295108)
			(xy 355.46631 -20.210577) (xy 355.478175 -20.12679) (xy 355.497833 -20.044481) (xy 355.525113 -19.964375)
			(xy 355.559774 -19.887176) (xy 355.601512 -19.813561) (xy 355.649959 -19.744178) (xy 355.704691 -19.679637)
			(xy 355.765227 -19.620505) (xy 355.831033 -19.567301) (xy 355.901533 -19.520493) (xy 355.976105 -19.480492)
			(xy 356.054096 -19.44765) (xy 356.13482 -19.422256) (xy 356.217567 -19.404533) (xy 356.301609 -19.394635)
			(xy 356.38621 -19.392652) (xy 356.470624 -19.398599) (xy 356.554111 -19.412424) (xy 356.635936 -19.434007)
			(xy 356.71538 -19.463157) (xy 356.791746 -19.499618) (xy 356.864362 -19.54307) (xy 356.93259 -19.593131)
			(xy 356.99583 -19.649361) (xy 357.053527 -19.711266) (xy 357.105174 -19.778302) (xy 357.150316 -19.849879)
			(xy 357.182596 -19.9136) (xy 359.308144 -19.9136) (xy 359.312215 -19.857978) (xy 359.324341 -19.803541)
			(xy 359.344264 -19.75145) (xy 359.37156 -19.702815) (xy 359.405646 -19.658672) (xy 359.445795 -19.619963)
			(xy 359.491153 -19.587512) (xy 359.540753 -19.562011) (xy 359.593537 -19.544004) (xy 359.64838 -19.533874)
			(xy 359.704114 -19.531837) (xy 359.759551 -19.537937) (xy 359.813508 -19.552043) (xy 359.864837 -19.573855)
			(xy 359.912443 -19.602909) (xy 359.955311 -19.638584) (xy 359.992528 -19.680121) (xy 360.023301 -19.726634)
			(xy 360.046973 -19.777131) (xy 360.063041 -19.830538) (xy 360.071161 -19.885714) (xy 360.07167 -19.9136)
			(xy 360.908344 -19.9136) (xy 360.912415 -19.857978) (xy 360.924541 -19.803541) (xy 360.944464 -19.75145)
			(xy 360.97176 -19.702815) (xy 361.005846 -19.658672) (xy 361.045995 -19.619963) (xy 361.091353 -19.587512)
			(xy 361.140953 -19.562011) (xy 361.193737 -19.544004) (xy 361.24858 -19.533874) (xy 361.304314 -19.531837)
			(xy 361.359751 -19.537937) (xy 361.413708 -19.552043) (xy 361.465037 -19.573855) (xy 361.512643 -19.602909)
			(xy 361.555511 -19.638584) (xy 361.592728 -19.680121) (xy 361.623501 -19.726634) (xy 361.647173 -19.777131)
			(xy 361.663241 -19.830538) (xy 361.671361 -19.885714) (xy 361.67187 -19.9136) (xy 361.671361 -19.941486)
			(xy 361.663241 -19.996662) (xy 361.647173 -20.050069) (xy 361.639923 -20.065535) (xy 362.508296 -20.065535)
			(xy 362.512421 -20.0106) (xy 362.524405 -19.956831) (xy 362.543998 -19.905344) (xy 362.570793 -19.857211)
			(xy 362.604232 -19.813433) (xy 362.643621 -19.774919) (xy 362.68814 -19.742471) (xy 362.736862 -19.716764)
			(xy 362.788776 -19.698332) (xy 362.842801 -19.687559) (xy 362.897814 -19.684668) (xy 362.95267 -19.68972)
			(xy 363.00623 -19.70261) (xy 363.057378 -19.723069) (xy 363.105052 -19.750673) (xy 363.14826 -19.784847)
			(xy 363.186104 -19.82488) (xy 363.217795 -19.86994) (xy 363.230668 -19.894296) (xy 363.241733 -19.915003)
			(xy 363.270294 -19.95226) (xy 363.305211 -19.98364) (xy 363.345296 -20.008074) (xy 363.389186 -20.024733)
			(xy 363.435388 -20.033051) (xy 363.482332 -20.032743) (xy 363.528422 -20.023822) (xy 363.550454 -20.015708)
			(xy 363.576299 -20.006034) (xy 363.630038 -19.99348) (xy 363.685024 -19.988794) (xy 363.740113 -19.992076)
			(xy 363.794154 -20.003255) (xy 363.846022 -20.022101) (xy 363.894636 -20.048218) (xy 363.938983 -20.081064)
			(xy 363.978137 -20.119954) (xy 364.011284 -20.164076) (xy 364.037731 -20.212512) (xy 364.047786 -20.238212)
			(xy 364.055737 -20.258508) (xy 364.077625 -20.296201) (xy 364.105623 -20.329608) (xy 364.13891 -20.357748)
			(xy 364.176509 -20.379797) (xy 364.217319 -20.395108) (xy 364.260143 -20.403232) (xy 364.303725 -20.40393)
			(xy 364.346788 -20.397183) (xy 364.367572 -20.390612) (xy 364.392866 -20.382524) (xy 364.445029 -20.372576)
			(xy 364.498067 -20.369951) (xy 364.550957 -20.3747) (xy 364.602679 -20.386733) (xy 364.652235 -20.405815)
			(xy 364.675674 -20.418298) (xy 364.695202 -20.428654) (xy 364.736974 -20.443104) (xy 364.780615 -20.450111)
			(xy 364.824811 -20.449464) (xy 364.868229 -20.441182) (xy 364.909559 -20.425515) (xy 364.947557 -20.402936)
			(xy 364.981077 -20.374124) (xy 364.99546 -20.357338) (xy 365.013428 -20.33634) (xy 365.054309 -20.299157)
			(xy 365.100125 -20.268258) (xy 365.149918 -20.244287) (xy 365.202646 -20.227746) (xy 365.257208 -20.218981)
			(xy 365.312464 -20.218174) (xy 365.367259 -20.225344) (xy 365.393986 -20.23237) (xy 365.417004 -20.238365)
			(xy 365.464378 -20.24259) (xy 365.51171 -20.237927) (xy 365.557349 -20.224538) (xy 365.599698 -20.20289)
			(xy 365.637281 -20.173741) (xy 365.668783 -20.138108) (xy 365.693105 -20.097235) (xy 365.709397 -20.052551)
			(xy 365.713772 -20.02917) (xy 365.718724 -20.002242) (xy 365.735297 -19.950061) (xy 365.759158 -19.900784)
			(xy 365.789818 -19.855424) (xy 365.826646 -19.814912) (xy 365.868887 -19.78008) (xy 365.915673 -19.751644)
			(xy 365.966044 -19.730188) (xy 366.018964 -19.716151) (xy 366.073347 -19.709823) (xy 366.128076 -19.711333)
			(xy 366.182027 -19.720651) (xy 366.234092 -19.737584) (xy 366.258856 -19.749262) (xy 366.27922 -19.758754)
			(xy 366.322376 -19.771232) (xy 366.367053 -19.775926) (xy 366.41186 -19.772691) (xy 366.4554 -19.761626)
			(xy 366.496315 -19.743077) (xy 366.533331 -19.717621) (xy 366.565293 -19.686053) (xy 366.578642 -19.667982)
			(xy 366.595208 -19.645353) (xy 366.633927 -19.60478) (xy 366.678168 -19.570313) (xy 366.726978 -19.542694)
			(xy 366.779306 -19.52252) (xy 366.834024 -19.510223) (xy 366.889953 -19.506071) (xy 366.945887 -19.510151)
			(xy 367.000621 -19.522376) (xy 367.052975 -19.542483) (xy 367.101821 -19.570039) (xy 367.146107 -19.604448)
			(xy 367.184877 -19.644971) (xy 367.217298 -19.690733) (xy 367.242669 -19.740749) (xy 367.260444 -19.79394)
			(xy 367.27024 -19.849161) (xy 367.271846 -19.90522) (xy 367.265227 -19.960911) (xy 367.250526 -20.015032)
			(xy 367.22806 -20.066418) (xy 367.198312 -20.113961) (xy 367.161925 -20.156637) (xy 367.119682 -20.193525)
			(xy 367.072493 -20.223832) (xy 367.021376 -20.246903) (xy 366.967431 -20.262241) (xy 366.911823 -20.269517)
			(xy 366.855748 -20.268573) (xy 366.800416 -20.259429) (xy 366.747019 -20.242283) (xy 366.721644 -20.230338)
			(xy 366.70128 -20.220846) (xy 366.658124 -20.208368) (xy 366.613447 -20.203674) (xy 366.56864 -20.206909)
			(xy 366.5251 -20.217974) (xy 366.484185 -20.236523) (xy 366.447169 -20.261979) (xy 366.415207 -20.293547)
			(xy 366.401858 -20.311618) (xy 366.386488 -20.332718) (xy 366.35082 -20.370836) (xy 366.310285 -20.403732)
			(xy 366.265643 -20.430793) (xy 366.217727 -20.451511) (xy 366.167433 -20.4655) (xy 366.1157 -20.472498)
			(xy 366.063497 -20.472375) (xy 366.011798 -20.465132) (xy 365.986568 -20.45843) (xy 365.963535 -20.452496)
			(xy 365.916167 -20.448263) (xy 365.868839 -20.452918) (xy 365.823204 -20.466299) (xy 365.780856 -20.487938)
			(xy 365.743274 -20.51708) (xy 365.711772 -20.552707) (xy 365.68745 -20.593573) (xy 365.671158 -20.638252)
			(xy 365.666782 -20.66163) (xy 365.66175 -20.689292) (xy 365.64455 -20.74282) (xy 365.619681 -20.793245)
			(xy 365.58768 -20.839474) (xy 365.549242 -20.880505) (xy 365.505197 -20.915451) (xy 365.456501 -20.943555)
			(xy 365.404207 -20.964207) (xy 365.349449 -20.97696) (xy 365.293412 -20.981539) (xy 365.237309 -20.977844)
			(xy 365.182357 -20.965956) (xy 365.129744 -20.946131) (xy 365.104934 -20.932902) (xy 365.085402 -20.922554)
			(xy 365.043631 -20.908103) (xy 364.999991 -20.901095) (xy 364.955796 -20.901741) (xy 364.912379 -20.910022)
			(xy 364.871048 -20.925688) (xy 364.833051 -20.948266) (xy 364.799531 -20.977077) (xy 364.785148 -20.993862)
			(xy 364.766556 -21.015615) (xy 364.724041 -21.053914) (xy 364.676284 -21.085434) (xy 364.624355 -21.109468)
			(xy 364.569418 -21.125476) (xy 364.512707 -21.1331) (xy 364.455494 -21.132169) (xy 364.399061 -21.122704)
			(xy 364.344675 -21.104916) (xy 364.293555 -21.079205) (xy 364.246849 -21.046148) (xy 364.205603 -21.006486)
			(xy 364.170744 -20.961109) (xy 364.143052 -20.911034) (xy 364.132622 -20.884388) (xy 364.124662 -20.864096)
			(xy 364.102775 -20.826403) (xy 364.074778 -20.792997) (xy 364.041493 -20.764857) (xy 364.003894 -20.742808)
			(xy 363.963085 -20.727496) (xy 363.920263 -20.719372) (xy 363.876682 -20.718672) (xy 363.83362 -20.725417)
			(xy 363.812836 -20.731988) (xy 363.786865 -20.740365) (xy 363.73322 -20.750368) (xy 363.678697 -20.752625)
			(xy 363.624408 -20.74709) (xy 363.571462 -20.733876) (xy 363.520939 -20.713252) (xy 363.47387 -20.68564)
			(xy 363.431216 -20.651603) (xy 363.393848 -20.611835) (xy 363.362527 -20.567149) (xy 363.349794 -20.543012)
			(xy 363.338661 -20.522344) (xy 363.31011 -20.485089) (xy 363.275204 -20.453709) (xy 363.23513 -20.429272)
			(xy 363.191251 -20.412608) (xy 363.145058 -20.404283) (xy 363.098122 -20.404582) (xy 363.052038 -20.413492)
			(xy 363.030008 -20.4216) (xy 363.004198 -20.431231) (xy 362.950567 -20.443822) (xy 362.895683 -20.448568)
			(xy 362.840687 -20.44537) (xy 362.786723 -20.434296) (xy 362.734913 -20.415575) (xy 362.686335 -20.389596)
			(xy 362.641998 -20.356901) (xy 362.602825 -20.318168) (xy 362.56963 -20.274203) (xy 362.543104 -20.225921)
			(xy 362.523798 -20.174326) (xy 362.512115 -20.120491) (xy 362.508296 -20.065535) (xy 361.639923 -20.065535)
			(xy 361.623501 -20.100566) (xy 361.592728 -20.147079) (xy 361.555511 -20.188616) (xy 361.512643 -20.224291)
			(xy 361.465037 -20.253345) (xy 361.413708 -20.275157) (xy 361.359751 -20.289263) (xy 361.304314 -20.295363)
			(xy 361.24858 -20.293326) (xy 361.193737 -20.283196) (xy 361.140953 -20.265189) (xy 361.091353 -20.239688)
			(xy 361.045995 -20.207237) (xy 361.005846 -20.168528) (xy 360.97176 -20.124385) (xy 360.944464 -20.07575)
			(xy 360.924541 -20.023659) (xy 360.912415 -19.969222) (xy 360.908344 -19.9136) (xy 360.07167 -19.9136)
			(xy 360.071161 -19.941486) (xy 360.063041 -19.996662) (xy 360.046973 -20.050069) (xy 360.023301 -20.100566)
			(xy 359.992528 -20.147079) (xy 359.955311 -20.188616) (xy 359.912443 -20.224291) (xy 359.864837 -20.253345)
			(xy 359.813508 -20.275157) (xy 359.759551 -20.289263) (xy 359.704114 -20.295363) (xy 359.64838 -20.293326)
			(xy 359.593537 -20.283196) (xy 359.540753 -20.265189) (xy 359.491153 -20.239688) (xy 359.445795 -20.207237)
			(xy 359.405646 -20.168528) (xy 359.37156 -20.124385) (xy 359.344264 -20.07575) (xy 359.324341 -20.023659)
			(xy 359.312215 -19.969222) (xy 359.308144 -19.9136) (xy 357.182596 -19.9136) (xy 357.188558 -19.925369)
			(xy 357.219562 -20.004108) (xy 357.243057 -20.085405) (xy 357.258836 -20.168544) (xy 357.26676 -20.252796)
			(xy 357.267256 -20.295108) (xy 357.26676 -20.33742) (xy 357.258836 -20.421672) (xy 357.243057 -20.504811)
			(xy 357.219562 -20.586108) (xy 357.188558 -20.664847) (xy 357.150316 -20.740337) (xy 357.105174 -20.811914)
			(xy 357.053527 -20.87895) (xy 356.99583 -20.940855) (xy 356.93259 -20.997085) (xy 356.864362 -21.047146)
			(xy 356.791746 -21.090598) (xy 356.71538 -21.127059) (xy 356.635936 -21.156209) (xy 356.554111 -21.177792)
			(xy 356.470624 -21.191617) (xy 356.38621 -21.197564) (xy 356.301609 -21.195581) (xy 356.217567 -21.185683)
			(xy 356.13482 -21.16796) (xy 356.054096 -21.142566) (xy 355.976105 -21.109724) (xy 355.901533 -21.069723)
			(xy 355.831033 -21.022915) (xy 355.765227 -20.969711) (xy 355.704691 -20.910579) (xy 355.649959 -20.846038)
			(xy 355.601512 -20.776655) (xy 355.559774 -20.70304) (xy 355.525113 -20.625841) (xy 355.497833 -20.545735)
			(xy 355.478175 -20.463426) (xy 355.46631 -20.379639) (xy 355.462344 -20.295108) (xy 349.963949 -20.295108)
			(xy 351.677224 -22.008592) (xy 351.693833 -22.024498) (xy 351.731669 -22.05063) (xy 351.77359 -22.069528)
			(xy 351.818226 -22.080574) (xy 351.864122 -22.083409) (xy 351.909779 -22.077939) (xy 351.953706 -22.064344)
			(xy 351.99447 -22.043066) (xy 352.030741 -22.014801) (xy 352.061333 -21.980471) (xy 352.073718 -21.961094)
			(xy 352.088502 -21.937753) (xy 352.12374 -21.895198) (xy 352.164748 -21.858172) (xy 352.210668 -21.827448)
			(xy 352.260539 -21.803669) (xy 352.313319 -21.787331) (xy 352.367903 -21.778778) (xy 352.42315 -21.778188)
			(xy 352.477905 -21.785572) (xy 352.531022 -21.800777) (xy 352.58139 -21.823485) (xy 352.627956 -21.85322)
			(xy 352.669746 -21.889361) (xy 352.705886 -21.931152) (xy 352.73562 -21.977719) (xy 352.758327 -22.028088)
			(xy 352.77353 -22.081206) (xy 352.780913 -22.13596) (xy 352.780321 -22.191208) (xy 352.771766 -22.245791)
			(xy 352.755427 -22.298571) (xy 352.731647 -22.348441) (xy 352.700921 -22.39436) (xy 352.663894 -22.435367)
			(xy 352.621339 -22.470604) (xy 352.597974 -22.48535) (xy 352.582472 -22.495256) (xy 355.563942 -22.495256)
			(xy 355.567923 -22.415492) (xy 355.579826 -22.33652) (xy 355.599533 -22.259126) (xy 355.626848 -22.184079)
			(xy 355.661499 -22.112124) (xy 355.703143 -22.043977) (xy 355.751365 -21.980315) (xy 355.805686 -21.921771)
			(xy 355.865567 -21.868926) (xy 355.930411 -21.822306) (xy 355.999575 -21.782374) (xy 356.072371 -21.749527)
			(xy 356.148076 -21.724092) (xy 356.225937 -21.706321) (xy 356.305181 -21.69639) (xy 356.38502 -21.694399)
			(xy 356.46466 -21.700367) (xy 356.543311 -21.714235) (xy 356.62019 -21.735866) (xy 356.694533 -21.765043)
			(xy 356.765601 -21.801478) (xy 356.832689 -21.844808) (xy 356.895128 -21.894602) (xy 356.9523 -21.950366)
			(xy 357.003636 -22.011545) (xy 357.048624 -22.077531) (xy 357.08682 -22.147669) (xy 357.117841 -22.221262)
			(xy 357.141382 -22.297577) (xy 357.157206 -22.375857) (xy 357.165158 -22.455324) (xy 357.165453 -22.479)
			(xy 362.685582 -22.479) (xy 362.689653 -22.423378) (xy 362.701779 -22.368941) (xy 362.721702 -22.31685)
			(xy 362.748998 -22.268215) (xy 362.783084 -22.224072) (xy 362.823233 -22.185363) (xy 362.868591 -22.152912)
			(xy 362.918191 -22.127411) (xy 362.970975 -22.109404) (xy 363.025818 -22.099274) (xy 363.081552 -22.097237)
			(xy 363.136989 -22.103337) (xy 363.190946 -22.117443) (xy 363.242275 -22.139255) (xy 363.289881 -22.168309)
			(xy 363.332749 -22.203984) (xy 363.369966 -22.245521) (xy 363.400739 -22.292034) (xy 363.424411 -22.342531)
			(xy 363.434902 -22.3774) (xy 363.904782 -22.3774) (xy 363.908853 -22.321778) (xy 363.920979 -22.267341)
			(xy 363.940902 -22.21525) (xy 363.968198 -22.166615) (xy 364.002284 -22.122472) (xy 364.042433 -22.083763)
			(xy 364.087791 -22.051312) (xy 364.137391 -22.025811) (xy 364.190175 -22.007804) (xy 364.245018 -21.997674)
			(xy 364.300752 -21.995637) (xy 364.356189 -22.001737) (xy 364.410146 -22.015843) (xy 364.461475 -22.037655)
			(xy 364.509081 -22.066709) (xy 364.551949 -22.102384) (xy 364.589166 -22.143921) (xy 364.619939 -22.190434)
			(xy 364.643611 -22.240931) (xy 364.659679 -22.294338) (xy 364.667799 -22.349514) (xy 364.668308 -22.3774)
			(xy 364.667799 -22.405286) (xy 364.659679 -22.460462) (xy 364.649211 -22.495256) (xy 369.81385 -22.495256)
			(xy 369.817831 -22.415492) (xy 369.829734 -22.33652) (xy 369.849441 -22.259126) (xy 369.876756 -22.184079)
			(xy 369.911407 -22.112124) (xy 369.953051 -22.043977) (xy 370.001273 -21.980315) (xy 370.055594 -21.921771)
			(xy 370.115475 -21.868926) (xy 370.180319 -21.822306) (xy 370.249483 -21.782374) (xy 370.322279 -21.749527)
			(xy 370.397984 -21.724092) (xy 370.475845 -21.706321) (xy 370.555089 -21.69639) (xy 370.634928 -21.694399)
			(xy 370.714568 -21.700367) (xy 370.793219 -21.714235) (xy 370.870098 -21.735866) (xy 370.944441 -21.765043)
			(xy 371.015509 -21.801478) (xy 371.082597 -21.844808) (xy 371.145036 -21.894602) (xy 371.202208 -21.950366)
			(xy 371.253544 -22.011545) (xy 371.298532 -22.077531) (xy 371.336728 -22.147669) (xy 371.367749 -22.221262)
			(xy 371.39129 -22.297577) (xy 371.407114 -22.375857) (xy 371.415066 -22.455324) (xy 371.415564 -22.495256)
			(xy 371.415066 -22.535188) (xy 371.407114 -22.614655) (xy 371.39129 -22.692935) (xy 371.367749 -22.76925)
			(xy 371.336728 -22.842843) (xy 371.298532 -22.912981) (xy 371.253544 -22.978967) (xy 371.202208 -23.040146)
			(xy 371.145036 -23.09591) (xy 371.082597 -23.145704) (xy 371.015509 -23.189034) (xy 370.944441 -23.225469)
			(xy 370.870098 -23.254646) (xy 370.793219 -23.276277) (xy 370.714568 -23.290145) (xy 370.634928 -23.296113)
			(xy 370.555089 -23.294122) (xy 370.475845 -23.284191) (xy 370.397984 -23.26642) (xy 370.322279 -23.240985)
			(xy 370.249483 -23.208138) (xy 370.180319 -23.168206) (xy 370.115475 -23.121586) (xy 370.055594 -23.068741)
			(xy 370.001273 -23.010197) (xy 369.953051 -22.946535) (xy 369.911407 -22.878388) (xy 369.876756 -22.806433)
			(xy 369.849441 -22.731386) (xy 369.829734 -22.653992) (xy 369.817831 -22.57502) (xy 369.81385 -22.495256)
			(xy 364.649211 -22.495256) (xy 364.643611 -22.513869) (xy 364.619939 -22.564366) (xy 364.589166 -22.610879)
			(xy 364.551949 -22.652416) (xy 364.509081 -22.688091) (xy 364.461475 -22.717145) (xy 364.410146 -22.738957)
			(xy 364.356189 -22.753063) (xy 364.300752 -22.759163) (xy 364.245018 -22.757126) (xy 364.190175 -22.746996)
			(xy 364.137391 -22.728989) (xy 364.087791 -22.703488) (xy 364.042433 -22.671037) (xy 364.002284 -22.632328)
			(xy 363.968198 -22.588185) (xy 363.940902 -22.53955) (xy 363.920979 -22.487459) (xy 363.908853 -22.433022)
			(xy 363.904782 -22.3774) (xy 363.434902 -22.3774) (xy 363.440479 -22.395938) (xy 363.448599 -22.451114)
			(xy 363.449108 -22.479) (xy 363.448599 -22.506886) (xy 363.440479 -22.562062) (xy 363.424411 -22.615469)
			(xy 363.400739 -22.665966) (xy 363.369966 -22.712479) (xy 363.332749 -22.754016) (xy 363.289881 -22.789691)
			(xy 363.242275 -22.818745) (xy 363.190946 -22.840557) (xy 363.136989 -22.854663) (xy 363.081552 -22.860763)
			(xy 363.025818 -22.858726) (xy 362.970975 -22.848596) (xy 362.918191 -22.830589) (xy 362.868591 -22.805088)
			(xy 362.823233 -22.772637) (xy 362.783084 -22.733928) (xy 362.748998 -22.689785) (xy 362.721702 -22.64115)
			(xy 362.701779 -22.589059) (xy 362.689653 -22.534622) (xy 362.685582 -22.479) (xy 357.165453 -22.479)
			(xy 357.165656 -22.495256) (xy 357.165158 -22.535188) (xy 357.157206 -22.614655) (xy 357.141382 -22.692935)
			(xy 357.117841 -22.76925) (xy 357.08682 -22.842843) (xy 357.048624 -22.912981) (xy 357.003636 -22.978967)
			(xy 356.9523 -23.040146) (xy 356.895128 -23.09591) (xy 356.832689 -23.145704) (xy 356.765601 -23.189034)
			(xy 356.694533 -23.225469) (xy 356.62019 -23.254646) (xy 356.543311 -23.276277) (xy 356.46466 -23.290145)
			(xy 356.38502 -23.296113) (xy 356.305181 -23.294122) (xy 356.225937 -23.284191) (xy 356.148076 -23.26642)
			(xy 356.072371 -23.240985) (xy 355.999575 -23.208138) (xy 355.930411 -23.168206) (xy 355.865567 -23.121586)
			(xy 355.805686 -23.068741) (xy 355.751365 -23.010197) (xy 355.703143 -22.946535) (xy 355.661499 -22.878388)
			(xy 355.626848 -22.806433) (xy 355.599533 -22.731386) (xy 355.579826 -22.653992) (xy 355.567923 -22.57502)
			(xy 355.563942 -22.495256) (xy 352.582472 -22.495256) (xy 352.578594 -22.497734) (xy 352.544263 -22.528329)
			(xy 352.515996 -22.564602) (xy 352.494716 -22.605368) (xy 352.481118 -22.649297) (xy 352.475645 -22.694956)
			(xy 352.478476 -22.740855) (xy 352.489518 -22.785496) (xy 352.508411 -22.827421) (xy 352.534539 -22.865264)
			(xy 352.550476 -22.881844) (xy 352.866706 -23.19782) (xy 352.878795 -23.209206) (xy 352.907499 -23.225883)
			(xy 352.939541 -23.234564) (xy 352.972737 -23.234659) (xy 353.004828 -23.226161) (xy 353.033627 -23.20965)
			(xy 353.045776 -23.198328) (xy 353.065823 -23.17921) (xy 353.110437 -23.146375) (xy 353.159331 -23.120337)
			(xy 353.211476 -23.101644) (xy 353.265776 -23.090687) (xy 353.32109 -23.087697) (xy 353.376255 -23.092737)
			(xy 353.430111 -23.105702) (xy 353.481527 -23.126318) (xy 353.529421 -23.154152) (xy 353.572786 -23.188619)
			(xy 353.610712 -23.228995) (xy 353.6424 -23.274431) (xy 353.667185 -23.323971) (xy 353.684546 -23.376575)
			(xy 353.694118 -23.431137) (xy 353.695699 -23.486509) (xy 353.689257 -23.541528) (xy 353.682554 -23.568406)
			(xy 353.678701 -23.584615) (xy 353.678666 -23.617921) (xy 353.687265 -23.650099) (xy 353.703909 -23.678948)
			(xy 353.71532 -23.691088) (xy 354.777548 -24.753062) (xy 354.777548 -25.273) (xy 354.777153 -25.295098)
			(xy 358.632264 -25.295098) (xy 358.63623 -25.210567) (xy 358.648095 -25.12678) (xy 358.667753 -25.044471)
			(xy 358.695033 -24.964365) (xy 358.729694 -24.887166) (xy 358.771432 -24.813551) (xy 358.819879 -24.744168)
			(xy 358.874611 -24.679627) (xy 358.935147 -24.620495) (xy 359.000953 -24.567291) (xy 359.071453 -24.520483)
			(xy 359.146025 -24.480482) (xy 359.224016 -24.44764) (xy 359.30474 -24.422246) (xy 359.387487 -24.404523)
			(xy 359.471529 -24.394625) (xy 359.55613 -24.392642) (xy 359.640544 -24.398589) (xy 359.724031 -24.412414)
			(xy 359.805856 -24.433997) (xy 359.8853 -24.463147) (xy 359.961666 -24.499608) (xy 360.034282 -24.54306)
			(xy 360.10251 -24.593121) (xy 360.16575 -24.649351) (xy 360.223447 -24.711256) (xy 360.275094 -24.778292)
			(xy 360.320236 -24.849869) (xy 360.358478 -24.925359) (xy 360.389482 -25.004098) (xy 360.412977 -25.085395)
			(xy 360.428756 -25.168534) (xy 360.43668 -25.252786) (xy 360.437176 -25.295098) (xy 364.032304 -25.295098)
			(xy 364.03627 -25.210567) (xy 364.048135 -25.12678) (xy 364.067793 -25.044471) (xy 364.095073 -24.964365)
			(xy 364.129734 -24.887166) (xy 364.171472 -24.813551) (xy 364.219919 -24.744168) (xy 364.274651 -24.679627)
			(xy 364.335187 -24.620495) (xy 364.400993 -24.567291) (xy 364.471493 -24.520483) (xy 364.546065 -24.480482)
			(xy 364.624056 -24.44764) (xy 364.70478 -24.422246) (xy 364.787527 -24.404523) (xy 364.871569 -24.394625)
			(xy 364.95617 -24.392642) (xy 365.040584 -24.398589) (xy 365.124071 -24.412414) (xy 365.205896 -24.433997)
			(xy 365.28534 -24.463147) (xy 365.361706 -24.499608) (xy 365.434322 -24.54306) (xy 365.50255 -24.593121)
			(xy 365.56579 -24.649351) (xy 365.623487 -24.711256) (xy 365.675134 -24.778292) (xy 365.720276 -24.849869)
			(xy 365.758518 -24.925359) (xy 365.789522 -25.004098) (xy 365.813017 -25.085395) (xy 365.828796 -25.168534)
			(xy 365.83672 -25.252786) (xy 365.837216 -25.295098) (xy 369.712252 -25.295098) (xy 369.716218 -25.210567)
			(xy 369.728083 -25.12678) (xy 369.747741 -25.044471) (xy 369.775021 -24.964365) (xy 369.809682 -24.887166)
			(xy 369.85142 -24.813551) (xy 369.899867 -24.744168) (xy 369.954599 -24.679627) (xy 370.015135 -24.620495)
			(xy 370.080941 -24.567291) (xy 370.151441 -24.520483) (xy 370.226013 -24.480482) (xy 370.304004 -24.44764)
			(xy 370.384728 -24.422246) (xy 370.467475 -24.404523) (xy 370.551517 -24.394625) (xy 370.636118 -24.392642)
			(xy 370.720532 -24.398589) (xy 370.804019 -24.412414) (xy 370.885844 -24.433997) (xy 370.965288 -24.463147)
			(xy 371.041654 -24.499608) (xy 371.11427 -24.54306) (xy 371.182498 -24.593121) (xy 371.245738 -24.649351)
			(xy 371.303435 -24.711256) (xy 371.355082 -24.778292) (xy 371.400224 -24.849869) (xy 371.438466 -24.925359)
			(xy 371.46947 -25.004098) (xy 371.492965 -25.085395) (xy 371.508744 -25.168534) (xy 371.516668 -25.252786)
			(xy 371.517164 -25.295098) (xy 371.516668 -25.33741) (xy 371.508744 -25.421662) (xy 371.492965 -25.504801)
			(xy 371.46947 -25.586098) (xy 371.438466 -25.664837) (xy 371.400224 -25.740327) (xy 371.355082 -25.811904)
			(xy 371.303435 -25.87894) (xy 371.245738 -25.940845) (xy 371.182498 -25.997075) (xy 371.11427 -26.047136)
			(xy 371.041654 -26.090588) (xy 370.965288 -26.127049) (xy 370.885844 -26.156199) (xy 370.804019 -26.177782)
			(xy 370.720532 -26.191607) (xy 370.636118 -26.197554) (xy 370.551517 -26.195571) (xy 370.467475 -26.185673)
			(xy 370.384728 -26.16795) (xy 370.304004 -26.142556) (xy 370.226013 -26.109714) (xy 370.151441 -26.069713)
			(xy 370.080941 -26.022905) (xy 370.015135 -25.969701) (xy 369.954599 -25.910569) (xy 369.899867 -25.846028)
			(xy 369.85142 -25.776645) (xy 369.809682 -25.70303) (xy 369.775021 -25.625831) (xy 369.747741 -25.545725)
			(xy 369.728083 -25.463416) (xy 369.716218 -25.379629) (xy 369.712252 -25.295098) (xy 365.837216 -25.295098)
			(xy 365.83672 -25.33741) (xy 365.828796 -25.421662) (xy 365.813017 -25.504801) (xy 365.789522 -25.586098)
			(xy 365.758518 -25.664837) (xy 365.720276 -25.740327) (xy 365.675134 -25.811904) (xy 365.623487 -25.87894)
			(xy 365.56579 -25.940845) (xy 365.50255 -25.997075) (xy 365.434322 -26.047136) (xy 365.361706 -26.090588)
			(xy 365.28534 -26.127049) (xy 365.205896 -26.156199) (xy 365.124071 -26.177782) (xy 365.040584 -26.191607)
			(xy 364.95617 -26.197554) (xy 364.871569 -26.195571) (xy 364.787527 -26.185673) (xy 364.70478 -26.16795)
			(xy 364.624056 -26.142556) (xy 364.546065 -26.109714) (xy 364.471493 -26.069713) (xy 364.400993 -26.022905)
			(xy 364.335187 -25.969701) (xy 364.274651 -25.910569) (xy 364.219919 -25.846028) (xy 364.171472 -25.776645)
			(xy 364.129734 -25.70303) (xy 364.095073 -25.625831) (xy 364.067793 -25.545725) (xy 364.048135 -25.463416)
			(xy 364.03627 -25.379629) (xy 364.032304 -25.295098) (xy 360.437176 -25.295098) (xy 360.43668 -25.33741)
			(xy 360.428756 -25.421662) (xy 360.412977 -25.504801) (xy 360.389482 -25.586098) (xy 360.358478 -25.664837)
			(xy 360.320236 -25.740327) (xy 360.275094 -25.811904) (xy 360.223447 -25.87894) (xy 360.16575 -25.940845)
			(xy 360.10251 -25.997075) (xy 360.034282 -26.047136) (xy 359.961666 -26.090588) (xy 359.8853 -26.127049)
			(xy 359.805856 -26.156199) (xy 359.724031 -26.177782) (xy 359.640544 -26.191607) (xy 359.55613 -26.197554)
			(xy 359.471529 -26.195571) (xy 359.387487 -26.185673) (xy 359.30474 -26.16795) (xy 359.224016 -26.142556)
			(xy 359.146025 -26.109714) (xy 359.071453 -26.069713) (xy 359.000953 -26.022905) (xy 358.935147 -25.969701)
			(xy 358.874611 -25.910569) (xy 358.819879 -25.846028) (xy 358.771432 -25.776645) (xy 358.729694 -25.70303)
			(xy 358.695033 -25.625831) (xy 358.667753 -25.545725) (xy 358.648095 -25.463416) (xy 358.63623 -25.379629)
			(xy 358.632264 -25.295098) (xy 354.777153 -25.295098) (xy 354.777042 -25.30134) (xy 354.768976 -25.357443)
			(xy 354.753007 -25.411826) (xy 354.729462 -25.463384) (xy 354.698819 -25.511066) (xy 354.661701 -25.553901)
			(xy 354.618866 -25.591019) (xy 354.571184 -25.621662) (xy 354.519626 -25.645207) (xy 354.465243 -25.661176)
			(xy 354.40914 -25.669242) (xy 354.35246 -25.669242) (xy 354.296357 -25.661176) (xy 354.241974 -25.645207)
			(xy 354.190416 -25.621662) (xy 354.142734 -25.591019) (xy 354.099899 -25.553901) (xy 354.062781 -25.511066)
			(xy 354.032138 -25.463384) (xy 354.008593 -25.411826) (xy 353.992624 -25.357443) (xy 353.984558 -25.30134)
			(xy 353.984052 -25.273) (xy 353.984052 -25.081738) (xy 353.798886 -24.896318) (xy 353.783015 -24.881112)
			(xy 353.747049 -24.85585) (xy 353.707276 -24.837147) (xy 353.664879 -24.825562) (xy 353.621122 -24.821439)
			(xy 353.577308 -24.824901) (xy 353.534741 -24.835845) (xy 353.49469 -24.853945) (xy 353.458347 -24.878661)
			(xy 353.426796 -24.909258) (xy 353.400975 -24.944824) (xy 353.390962 -24.96439) (xy 353.378391 -24.989072)
			(xy 353.347425 -25.034997) (xy 353.31037 -25.076166) (xy 353.267946 -25.111778) (xy 353.220979 -25.141139)
			(xy 353.170383 -25.163679) (xy 353.117143 -25.178959) (xy 353.062295 -25.18668) (xy 353.0346 -25.187148)
			(xy 352.692462 -25.187148) (xy 348.513146 -21.007832) (xy 348.500985 -20.996459) (xy 348.47215 -20.979837)
			(xy 348.439998 -20.971234) (xy 348.406716 -20.971234) (xy 348.374564 -20.979837) (xy 348.345729 -20.996459)
			(xy 348.333568 -21.007832) (xy 347.8276 -21.5138) (xy 347.8276 -21.693124) (xy 347.828146 -21.70977)
			(xy 347.836768 -21.741927) (xy 347.853418 -21.770757) (xy 347.876962 -21.794297) (xy 347.905795 -21.810941)
			(xy 347.937954 -21.819557) (xy 347.9546 -21.820124) (xy 347.98762 -21.820124) (xy 348.045024 -21.78812)
			(xy 348.06255 -21.76018) (xy 348.077642 -21.736874) (xy 348.1135 -21.694485) (xy 348.155125 -21.657742)
			(xy 348.201637 -21.627423) (xy 348.252054 -21.604167) (xy 348.30531 -21.588467) (xy 348.360279 -21.580654)
			(xy 348.4158 -21.580893) (xy 348.4707 -21.589179) (xy 348.523819 -21.605337) (xy 348.574033 -21.629026)
			(xy 348.620283 -21.659744) (xy 348.66159 -21.696844) (xy 348.697082 -21.73954) (xy 348.726009 -21.786931)
			(xy 348.747759 -21.838015) (xy 348.761873 -21.891713) (xy 348.768053 -21.94689) (xy 348.766168 -22.002379)
			(xy 348.756257 -22.05701) (xy 348.738531 -22.109626) (xy 348.713364 -22.159116) (xy 348.681287 -22.204434)
			(xy 348.642979 -22.244623) (xy 348.599249 -22.278833) (xy 348.551021 -22.306342) (xy 348.499315 -22.326568)
			(xy 348.445222 -22.339084) (xy 348.389886 -22.343624) (xy 348.334477 -22.340095) (xy 348.280165 -22.328569)
			(xy 348.228097 -22.30929) (xy 348.20352 -22.296374) (xy 348.184056 -22.286251) (xy 348.142526 -22.272116)
			(xy 348.099186 -22.265324) (xy 348.055323 -22.266075) (xy 348.012241 -22.274349) (xy 347.97122 -22.289899)
			(xy 347.933479 -22.312263) (xy 347.90014 -22.340777) (xy 347.872194 -22.374592) (xy 347.85047 -22.412705)
			(xy 347.835614 -22.453982) (xy 347.828068 -22.497198) (xy 347.8276 -22.519132) (xy 347.8276 -25.666954)
			(xy 349.846646 -27.686) (xy 374.8786 -27.686)
		)
		(stroke
			(width 0)
			(type solid)
		)
		(fill yes)
		(layer "In2.Cu")
		(net "P3V3_BLAD2")
	)
	(gr_poly
		(pts
			(xy 351.323656 -50.5206) (xy 351.346988 -50.520067) (xy 351.392865 -50.511539) (xy 351.436415 -50.494779)
			(xy 351.476173 -50.47035) (xy 351.510804 -50.439074) (xy 351.539143 -50.402002) (xy 351.560239 -50.36038)
			(xy 351.573382 -50.315606) (xy 351.578131 -50.269184) (xy 351.574326 -50.222676) (xy 351.562094 -50.177645)
			(xy 351.55251 -50.156364) (xy 351.527822 -50.104008) (xy 351.484972 -49.996464) (xy 351.449758 -49.886184)
			(xy 351.422354 -49.773709) (xy 351.402893 -49.659591) (xy 351.391472 -49.54439) (xy 351.388147 -49.428672)
			(xy 351.392933 -49.313005) (xy 351.405807 -49.197958) (xy 351.426707 -49.084094) (xy 351.455529 -48.971974)
			(xy 351.492132 -48.862147) (xy 351.536336 -48.755153) (xy 351.587925 -48.651518) (xy 351.646644 -48.551749)
			(xy 351.712206 -48.456338) (xy 351.784289 -48.365752) (xy 351.862538 -48.280436) (xy 351.94657 -48.20081)
			(xy 352.035972 -48.127264) (xy 352.130304 -48.060159) (xy 352.229104 -47.999825) (xy 352.331887 -47.946558)
			(xy 352.438148 -47.900619) (xy 352.547365 -47.862235) (xy 352.659002 -47.831594) (xy 352.77251 -47.808845)
			(xy 352.887333 -47.794101) (xy 353.002907 -47.787435) (xy 353.118664 -47.788878) (xy 353.234035 -47.798424)
			(xy 353.348455 -47.816026) (xy 353.461361 -47.841598) (xy 353.572199 -47.875014) (xy 353.680425 -47.916109)
			(xy 353.785507 -47.964683) (xy 353.88693 -48.020496) (xy 353.984195 -48.083275) (xy 354.076825 -48.152711)
			(xy 354.164365 -48.228463) (xy 354.246386 -48.31016) (xy 354.284788 -48.353472) (xy 354.300393 -48.370548)
			(xy 354.336631 -48.399289) (xy 354.377469 -48.421007) (xy 354.421559 -48.434984) (xy 354.46745 -48.440762)
			(xy 354.513628 -48.438148) (xy 354.558574 -48.42723) (xy 354.600806 -48.408367) (xy 354.638932 -48.38218)
			(xy 354.655628 -48.366172) (xy 354.9396 -48.0822) (xy 371.7544 -48.0822) (xy 374.0658 -50.3936) (xy 379.0696 -50.3936)
			(xy 381.381 -48.0822) (xy 421.1066 -48.0822) (xy 423.418 -45.7708) (xy 423.418 -44.66082) (xy 423.417464 -44.637463)
			(xy 423.408916 -44.591538) (xy 423.392122 -44.547947) (xy 423.367648 -44.508157) (xy 423.336318 -44.473508)
			(xy 423.299185 -44.445164) (xy 423.257499 -44.424081) (xy 423.212664 -44.410968) (xy 423.166187 -44.406266)
			(xy 423.119633 -44.410133) (xy 423.096944 -44.41571) (xy 423.037955 -44.431323) (xy 422.918405 -44.455837)
			(xy 422.797525 -44.472597) (xy 422.675816 -44.481534) (xy 422.553784 -44.482611) (xy 422.431936 -44.475824)
			(xy 422.310779 -44.4612) (xy 422.190815 -44.4388) (xy 422.072544 -44.408717) (xy 421.956457 -44.371077)
			(xy 421.843036 -44.326036) (xy 421.732753 -44.273781) (xy 421.626066 -44.214528) (xy 421.523418 -44.148525)
			(xy 421.425236 -44.076046) (xy 421.331928 -43.997391) (xy 421.243881 -43.912888) (xy 421.161462 -43.822888)
			(xy 421.085013 -43.727765) (xy 421.014851 -43.627913) (xy 420.951268 -43.523749) (xy 420.894529 -43.415704)
			(xy 420.844869 -43.304228) (xy 420.802494 -43.189785) (xy 420.767581 -43.072848) (xy 420.740275 -42.953906)
			(xy 420.720689 -42.833451) (xy 420.708904 -42.711984) (xy 420.70497 -42.590011) (xy 420.708903 -42.468038)
			(xy 420.720686 -42.346571) (xy 420.740271 -42.226116) (xy 420.767575 -42.107173) (xy 420.802487 -41.990236)
			(xy 420.84486 -41.875792) (xy 420.894519 -41.764316) (xy 420.951257 -41.656271) (xy 421.014839 -41.552105)
			(xy 421.084999 -41.452253) (xy 421.161447 -41.357129) (xy 421.243866 -41.267128) (xy 421.331911 -41.182624)
			(xy 421.425219 -41.103968) (xy 421.5234 -41.031487) (xy 421.626047 -40.965483) (xy 421.732734 -40.90623)
			(xy 421.843016 -40.853973) (xy 421.956436 -40.80893) (xy 422.072523 -40.771289) (xy 422.190793 -40.741205)
			(xy 422.310757 -40.718804) (xy 422.431914 -40.704178) (xy 422.553762 -40.697389) (xy 422.675794 -40.698465)
			(xy 422.797503 -40.707401) (xy 422.918384 -40.72416) (xy 423.037933 -40.748672) (xy 423.096944 -40.764206)
			(xy 423.119618 -40.769864) (xy 423.166182 -40.773755) (xy 423.212672 -40.769066) (xy 423.257522 -40.755955)
			(xy 423.299218 -40.734865) (xy 423.336354 -40.706506) (xy 423.367679 -40.671835) (xy 423.392136 -40.63202)
			(xy 423.408901 -40.588405) (xy 423.417408 -40.54246) (xy 423.418 -40.519096) (xy 423.418 -34.724594)
			(xy 423.4175 -34.701913) (xy 423.409447 -34.657272) (xy 423.393596 -34.614769) (xy 423.370452 -34.575755)
			(xy 423.340749 -34.54147) (xy 423.305433 -34.513001) (xy 423.265623 -34.491255) (xy 423.222585 -34.476921)
			(xy 423.177686 -34.470455) (xy 423.132352 -34.472062) (xy 423.088024 -34.481691) (xy 423.046109 -34.499037)
			(xy 423.007939 -34.523547) (xy 422.991026 -34.538666) (xy 422.953379 -34.573035) (xy 422.873525 -34.636412)
			(xy 422.788938 -34.693319) (xy 422.700142 -34.743404) (xy 422.607685 -34.786357) (xy 422.512139 -34.821912)
			(xy 422.414094 -34.84985) (xy 422.314157 -34.869998) (xy 422.212947 -34.882231) (xy 422.111088 -34.886474)
			(xy 422.00921 -34.882701) (xy 421.907944 -34.870934) (xy 421.807916 -34.851247) (xy 421.709743 -34.823761)
			(xy 421.614034 -34.788646) (xy 421.52138 -34.74612) (xy 421.432354 -34.696445) (xy 421.347506 -34.639929)
			(xy 421.267361 -34.57692) (xy 421.192415 -34.50781) (xy 421.12313 -34.433024) (xy 421.059936 -34.353025)
			(xy 421.003223 -34.268308) (xy 420.953342 -34.179397) (xy 420.910602 -34.086842) (xy 420.875265 -33.991214)
			(xy 420.847552 -33.893106) (xy 420.827633 -33.793123) (xy 420.815632 -33.691885) (xy 420.811622 -33.590016)
			(xy 420.815629 -33.488148) (xy 420.827628 -33.386909) (xy 420.847544 -33.286926) (xy 420.875255 -33.188817)
			(xy 420.910589 -33.093188) (xy 420.953328 -33.000632) (xy 421.003206 -32.91172) (xy 421.059917 -32.827002)
			(xy 421.123109 -32.747001) (xy 421.192391 -32.672214) (xy 421.267336 -32.603101) (xy 421.347479 -32.54009)
			(xy 421.432326 -32.483572) (xy 421.521351 -32.433895) (xy 421.614004 -32.391366) (xy 421.709712 -32.356249)
			(xy 421.807884 -32.328761) (xy 421.907912 -32.309071) (xy 422.009177 -32.297302) (xy 422.111055 -32.293526)
			(xy 422.212914 -32.297766) (xy 422.314125 -32.309997) (xy 422.414062 -32.330142) (xy 422.512108 -32.358078)
			(xy 422.607655 -32.393631) (xy 422.700113 -32.436581) (xy 422.788911 -32.486664) (xy 422.873499 -32.543568)
			(xy 422.953354 -32.606944) (xy 422.991026 -32.641286) (xy 423.007971 -32.656364) (xy 423.046136 -32.680866)
			(xy 423.088045 -32.698205) (xy 423.132365 -32.70783) (xy 423.177691 -32.709435) (xy 423.222581 -32.702969)
			(xy 423.265611 -32.688639) (xy 423.305414 -32.666898) (xy 423.340727 -32.638438) (xy 423.370427 -32.604162)
			(xy 423.393571 -32.565159) (xy 423.409426 -32.522666) (xy 423.417486 -32.478035) (xy 423.418 -32.455358)
			(xy 423.418 -29.66085) (xy 423.417466 -29.637491) (xy 423.408922 -29.591561) (xy 423.392131 -29.547965)
			(xy 423.367659 -29.508171) (xy 423.336327 -29.473516) (xy 423.299193 -29.445169) (xy 423.257504 -29.424083)
			(xy 423.212665 -29.410968) (xy 423.166185 -29.406266) (xy 423.119627 -29.410134) (xy 423.096944 -29.41574)
			(xy 423.037954 -29.431353) (xy 422.918403 -29.455867) (xy 422.79752 -29.472627) (xy 422.675809 -29.481564)
			(xy 422.553775 -29.48264) (xy 422.431926 -29.475852) (xy 422.310766 -29.461227) (xy 422.190801 -29.438826)
			(xy 422.072528 -29.408743) (xy 421.95644 -29.371102) (xy 421.843018 -29.326059) (xy 421.732733 -29.273803)
			(xy 421.626044 -29.214549) (xy 421.523395 -29.148545) (xy 421.425212 -29.076064) (xy 421.331903 -28.997407)
			(xy 421.243855 -28.912903) (xy 421.161435 -28.822901) (xy 421.084985 -28.727776) (xy 421.014822 -28.627922)
			(xy 420.951239 -28.523756) (xy 420.894499 -28.41571) (xy 420.844839 -28.304232) (xy 420.802464 -28.189786)
			(xy 420.767551 -28.072848) (xy 420.740245 -27.953904) (xy 420.720659 -27.833447) (xy 420.708875 -27.711978)
			(xy 420.704941 -27.590003) (xy 420.708874 -27.468028) (xy 420.720658 -27.346559) (xy 420.740244 -27.226103)
			(xy 420.767549 -27.107158) (xy 420.802462 -26.99022) (xy 420.844837 -26.875774) (xy 420.894497 -26.764296)
			(xy 420.951236 -26.656249) (xy 421.014819 -26.552083) (xy 421.084981 -26.452229) (xy 421.161431 -26.357104)
			(xy 421.243851 -26.267102) (xy 421.331898 -26.182597) (xy 421.425207 -26.10394) (xy 421.52339 -26.031459)
			(xy 421.626039 -25.965454) (xy 421.732727 -25.9062) (xy 421.843012 -25.853943) (xy 421.956434 -25.8089)
			(xy 422.072522 -25.771259) (xy 422.190795 -25.741175) (xy 422.31076 -25.718774) (xy 422.431919 -25.704149)
			(xy 422.553769 -25.69736) (xy 422.675803 -25.698436) (xy 422.797514 -25.707373) (xy 422.918396 -25.724132)
			(xy 423.037948 -25.748646) (xy 423.096944 -25.764236) (xy 423.119619 -25.769893) (xy 423.166184 -25.773784)
			(xy 423.212676 -25.769095) (xy 423.257527 -25.755984) (xy 423.299225 -25.734894) (xy 423.336364 -25.706536)
			(xy 423.367692 -25.671866) (xy 423.392153 -25.632052) (xy 423.408922 -25.588436) (xy 423.417434 -25.54249)
			(xy 423.418 -25.519126) (xy 423.418 -11.557) (xy 414.147 -2.286) (xy 396.49273 -2.286) (xy 396.431262 -2.324354)
			(xy 396.41526 -2.35712) (xy 396.401728 -2.383913) (xy 396.369956 -2.434842) (xy 396.333122 -2.48224)
			(xy 396.312644 -2.504186) (xy 396.28877 -2.528466) (xy 396.236311 -2.571886) (xy 396.207996 -2.5908)
			(xy 396.189829 -2.603872) (xy 396.157972 -2.635304) (xy 396.132111 -2.671828) (xy 396.113046 -2.712317)
			(xy 396.101366 -2.755518) (xy 396.097432 -2.800098) (xy 396.101365 -2.844677) (xy 396.113045 -2.887879)
			(xy 396.132109 -2.928368) (xy 396.157969 -2.964893) (xy 396.189825 -2.996325) (xy 396.207996 -3.009392)
			(xy 396.236483 -3.028436) (xy 396.28924 -3.072169) (xy 396.336523 -3.121768) (xy 396.377685 -3.176555)
			(xy 396.41216 -3.235777) (xy 396.439477 -3.298623) (xy 396.45926 -3.364231) (xy 396.47124 -3.431702)
			(xy 396.47525 -3.500111) (xy 396.471237 -3.568519) (xy 396.459255 -3.63599) (xy 396.439469 -3.701597)
			(xy 396.41215 -3.764442) (xy 396.377673 -3.823663) (xy 396.336509 -3.878448) (xy 396.289224 -3.928046)
			(xy 396.236466 -3.971777) (xy 396.207996 -3.990848) (xy 396.189657 -4.004068) (xy 396.157541 -4.035877)
			(xy 396.131554 -4.072863) (xy 396.112515 -4.113861) (xy 396.101024 -4.157579) (xy 396.097444 -4.20264)
			(xy 396.101887 -4.247624) (xy 396.114213 -4.291114) (xy 396.134034 -4.331739) (xy 396.160725 -4.368221)
			(xy 396.193445 -4.399408) (xy 396.21206 -4.412234) (xy 396.241404 -4.432227) (xy 396.295495 -4.478232)
			(xy 396.343616 -4.530449) (xy 396.385058 -4.58811) (xy 396.419212 -4.650365) (xy 396.445575 -4.716298)
			(xy 396.463758 -4.78494) (xy 396.473494 -4.855278) (xy 396.474639 -4.926277) (xy 396.471394 -4.961636)
			(xy 396.46946 -4.985223) (xy 396.473342 -5.032385) (xy 396.485884 -5.078014) (xy 396.506651 -5.120535)
			(xy 396.534928 -5.158479) (xy 396.569736 -5.190537) (xy 396.609875 -5.215601) (xy 396.653958 -5.232805)
			(xy 396.700463 -5.241556) (xy 396.724124 -5.242052) (xy 398.052544 -5.242052) (xy 398.365472 -4.929124)
			(xy 398.623536 -4.671314) (xy 398.633188 -4.648962) (xy 398.644573 -4.623898) (xy 398.673491 -4.577055)
			(xy 398.708842 -4.534856) (xy 398.749892 -4.498178) (xy 398.795788 -4.467781) (xy 398.845578 -4.444297)
			(xy 398.898225 -4.428214) (xy 398.952638 -4.419867) (xy 399.007686 -4.419428) (xy 399.062225 -4.426906)
			(xy 399.115123 -4.442147) (xy 399.16528 -4.464834) (xy 399.211655 -4.494495) (xy 399.253285 -4.530515)
			(xy 399.289305 -4.572145) (xy 399.318966 -4.61852) (xy 399.341653 -4.668677) (xy 399.356894 -4.721575)
			(xy 399.364372 -4.776114) (xy 399.363933 -4.831162) (xy 399.355586 -4.885575) (xy 399.339503 -4.938222)
			(xy 399.316019 -4.988012) (xy 399.285622 -5.033908) (xy 399.248944 -5.074958) (xy 399.206745 -5.110309)
			(xy 399.159902 -5.139227) (xy 399.134838 -5.150612) (xy 399.112486 -5.160264) (xy 398.762982 -5.509768)
			(xy 398.339056 -5.933948) (xy 396.721076 -5.933948) (xy 396.697297 -5.934478) (xy 396.650568 -5.943318)
			(xy 396.606301 -5.960703) (xy 396.566045 -5.986026) (xy 396.531208 -6.018401) (xy 396.503007 -6.056695)
			(xy 396.482428 -6.099571) (xy 396.470192 -6.145528) (xy 396.466725 -6.192959) (xy 396.468854 -6.21665)
			(xy 396.474042 -6.25802) (xy 396.474041 -6.341396) (xy 396.468854 -6.382766) (xy 396.463665 -6.415875)
			(xy 396.446673 -6.480705) (xy 396.422364 -6.543161) (xy 396.407132 -6.573012) (xy 396.3924 -6.600952)
			(xy 396.3924 -7.39902) (xy 396.407132 -7.42696) (xy 396.423255 -7.458618) (xy 396.448571 -7.525001)
			(xy 396.465658 -7.593962) (xy 396.474265 -7.664486) (xy 396.474263 -7.735532) (xy 396.465655 -7.806055)
			(xy 396.448566 -7.875016) (xy 396.423248 -7.941398) (xy 396.407132 -7.97306) (xy 396.3924 -8.001)
			(xy 396.3924 -8.4074) (xy 396.371826 -8.4074) (xy 396.305786 -8.454898) (xy 396.261336 -8.58647)
			(xy 396.30223 -8.684768) (xy 396.317978 -8.701532) (xy 396.340272 -8.72615) (xy 396.379741 -8.779569)
			(xy 396.412899 -8.837119) (xy 396.43932 -8.898056) (xy 396.458662 -8.961596) (xy 396.470677 -9.026918)
			(xy 396.475209 -9.093182) (xy 396.4722 -9.159532) (xy 396.461689 -9.225114) (xy 396.443811 -9.289081)
			(xy 396.418797 -9.350609) (xy 396.386969 -9.408905) (xy 396.36827 -9.436354) (xy 396.359245 -9.450062)
			(xy 396.347831 -9.48082) (xy 396.344649 -9.513474) (xy 396.349911 -9.545857) (xy 396.356078 -9.561068)
			(xy 396.401036 -9.661906) (xy 396.4686 -9.705848) (xy 396.4686 -10.415778) (xy 396.469616 -10.42416)
			(xy 396.469616 -10.425938) (xy 396.471394 -10.44194) (xy 396.473872 -10.470205) (xy 396.474 -10.526948)
			(xy 396.471648 -10.555224) (xy 396.47114 -10.560558) (xy 396.470378 -10.568686) (xy 396.4686 -10.584434)
			(xy 396.4686 -11.815826) (xy 396.469616 -11.824208) (xy 396.469616 -11.825986) (xy 396.471394 -11.841988)
			(xy 396.473869 -11.870253) (xy 396.473993 -11.926996) (xy 396.471648 -11.955272) (xy 396.47114 -11.960606)
			(xy 396.470378 -11.968734) (xy 396.4686 -11.984482) (xy 396.4686 -12.5984) (xy 396.402306 -12.5984)
			(xy 396.386312 -12.598823) (xy 396.355316 -12.606718) (xy 396.327266 -12.622088) (xy 396.30393 -12.643962)
			(xy 396.28678 -12.670962) (xy 396.281402 -12.68603) (xy 396.250414 -12.781534) (xy 396.268194 -12.8524)
			(xy 396.29461 -12.8778) (xy 396.318758 -12.901621) (xy 396.361968 -12.95391) (xy 396.398838 -13.010847)
			(xy 396.428872 -13.071668) (xy 396.451667 -13.135556) (xy 396.466916 -13.201653) (xy 396.474414 -13.269069)
			(xy 396.474062 -13.336901) (xy 396.465863 -13.404236) (xy 396.449927 -13.47017) (xy 396.42647 -13.533818)
			(xy 396.395805 -13.594323) (xy 396.358345 -13.650874) (xy 396.314593 -13.702711) (xy 396.265137 -13.749137)
			(xy 396.210641 -13.789528) (xy 396.151838 -13.823343) (xy 396.089517 -13.850126) (xy 396.024515 -13.869518)
			(xy 395.957707 -13.881258) (xy 395.889988 -13.88519) (xy 395.822269 -13.881258) (xy 395.755461 -13.869518)
			(xy 395.690459 -13.850126) (xy 395.628138 -13.823343) (xy 395.569335 -13.789528) (xy 395.514839 -13.749137)
			(xy 395.465383 -13.702711) (xy 395.421631 -13.650874) (xy 395.384171 -13.594323) (xy 395.353506 -13.533818)
			(xy 395.330049 -13.47017) (xy 395.314113 -13.404236) (xy 395.305914 -13.336901) (xy 395.305562 -13.269069)
			(xy 395.31306 -13.201653) (xy 395.328309 -13.135556) (xy 395.351104 -13.071668) (xy 395.381138 -13.010847)
			(xy 395.418008 -12.95391) (xy 395.461218 -12.901621) (xy 395.485366 -12.8778) (xy 395.511782 -12.8524)
			(xy 395.529562 -12.781534) (xy 395.498574 -12.68603) (xy 395.493138 -12.67099) (xy 395.475975 -12.644018)
			(xy 395.452649 -12.622157) (xy 395.424623 -12.606776) (xy 395.393655 -12.59884) (xy 395.37767 -12.5984)
			(xy 395.351 -12.5984) (xy 395.351 -12.127992) (xy 395.342872 -12.106402) (xy 395.330967 -12.073335)
			(xy 395.314244 -12.005073) (xy 395.305824 -11.935298) (xy 395.305829 -11.865016) (xy 395.314259 -11.795243)
			(xy 395.330993 -11.726982) (xy 395.342872 -11.693906) (xy 395.351 -11.672316) (xy 395.351 -10.727944)
			(xy 395.342872 -10.706354) (xy 395.330964 -10.673287) (xy 395.314234 -10.605024) (xy 395.305808 -10.535247)
			(xy 395.305808 -10.464964) (xy 395.314232 -10.395187) (xy 395.330961 -10.326924) (xy 395.342872 -10.293858)
			(xy 395.351 -10.272268) (xy 395.351 -9.7028) (xy 395.360652 -9.7028) (xy 395.423898 -9.561068) (xy 395.430082 -9.545868)
			(xy 395.435305 -9.513482) (xy 395.43211 -9.480834) (xy 395.420707 -9.450076) (xy 395.411706 -9.436354)
			(xy 395.392545 -9.408243) (xy 395.360138 -9.348425) (xy 395.334891 -9.28525) (xy 395.317145 -9.219573)
			(xy 395.307141 -9.152279) (xy 395.305012 -9.08428) (xy 395.310789 -9.016493) (xy 395.324393 -8.949834)
			(xy 395.345639 -8.885204) (xy 395.374242 -8.823476) (xy 395.39164 -8.794242) (xy 395.403082 -8.774652)
			(xy 395.419575 -8.732395) (xy 395.428301 -8.68788) (xy 395.428982 -8.642523) (xy 395.421595 -8.597766)
			(xy 395.406377 -8.555033) (xy 395.383811 -8.515682) (xy 395.354615 -8.480965) (xy 395.319717 -8.451985)
			(xy 395.3002 -8.44042) (xy 395.3002 -6.060948) (xy 395.299711 -6.044289) (xy 395.291098 -6.012104)
			(xy 395.274447 -5.983246) (xy 395.250892 -5.959683) (xy 395.22204 -5.94302) (xy 395.189859 -5.934395)
			(xy 395.1732 -5.933948) (xy 395.156944 -5.933948) (xy 395.052804 -5.829808) (xy 394.720572 -5.829808)
			(xy 394.698849 -5.830246) (xy 394.656034 -5.837627) (xy 394.615099 -5.852187) (xy 394.57724 -5.8735)
			(xy 394.543559 -5.900945) (xy 394.51504 -5.933721) (xy 394.492514 -5.970872) (xy 394.476639 -6.011314)
			(xy 394.467878 -6.053868) (xy 394.466486 -6.097293) (xy 394.469112 -6.11886) (xy 394.473388 -6.15282)
			(xy 394.474921 -6.221252) (xy 394.468444 -6.289394) (xy 394.454046 -6.356312) (xy 394.443458 -6.388862)
			(xy 394.4366 -6.408928) (xy 394.4366 -7.3914) (xy 394.443458 -7.411466) (xy 394.453388 -7.441927)
			(xy 394.467314 -7.504466) (xy 394.47432 -7.568153) (xy 394.474321 -7.632224) (xy 394.467318 -7.695911)
			(xy 394.453394 -7.758451) (xy 394.443458 -7.78891) (xy 394.4366 -7.808976) (xy 394.4366 -8.791194)
			(xy 394.443458 -8.81126) (xy 394.453388 -8.841721) (xy 394.467315 -8.90426) (xy 394.474321 -8.967947)
			(xy 394.474323 -9.032019) (xy 394.46732 -9.095706) (xy 394.453397 -9.158246) (xy 394.443458 -9.188704)
			(xy 394.4366 -9.20877) (xy 394.4366 -9.4996) (xy 394.195554 -9.4996) (xy 394.167106 -9.51484) (xy 394.139563 -9.529214)
			(xy 394.082048 -9.552716) (xy 394.022364 -9.569981) (xy 393.991846 -9.5758) (xy 393.976417 -9.579611)
			(xy 393.947965 -9.593748) (xy 393.923891 -9.61448) (xy 393.905688 -9.640519) (xy 393.894486 -9.670249)
			(xy 393.89098 -9.701826) (xy 393.895389 -9.73329) (xy 393.907437 -9.762687) (xy 393.926378 -9.788194)
			(xy 393.951036 -9.808228) (xy 393.979881 -9.821545) (xy 393.995402 -9.824974) (xy 394.028264 -9.831473)
			(xy 394.092342 -9.851007) (xy 394.153768 -9.877736) (xy 394.211739 -9.911308) (xy 394.265493 -9.951284)
			(xy 394.314327 -9.997141) (xy 394.357602 -10.048277) (xy 394.394751 -10.104023) (xy 394.425287 -10.163648)
			(xy 394.448809 -10.226372) (xy 394.465011 -10.291373) (xy 394.473679 -10.3578) (xy 394.4747 -10.424782)
			(xy 394.468061 -10.491442) (xy 394.453849 -10.556907) (xy 394.443458 -10.588752) (xy 394.4366 -10.608818)
			(xy 394.4366 -10.9982) (xy 394.6144 -11.176) (xy 394.6144 -14.3764) (xy 394.3858 -14.605) (xy 393.573 -14.605)
			(xy 393.2428 -14.2748) (xy 393.2428 -13.7922) (xy 393.2174 -13.7668) (xy 393.2174 -11.0998) (xy 393.3698 -10.9474)
			(xy 393.3952 -10.9474) (xy 393.3952 -10.713212) (xy 393.379198 -10.68451) (xy 393.36275 -10.65397)
			(xy 393.336399 -10.589801) (xy 393.317827 -10.522964) (xy 393.307295 -10.4544) (xy 393.304951 -10.385071)
			(xy 393.310829 -10.315952) (xy 393.324844 -10.248013) (xy 393.346802 -10.182212) (xy 393.376392 -10.11947)
			(xy 393.413199 -10.060672) (xy 393.456705 -10.006642) (xy 393.5063 -9.958141) (xy 393.561287 -9.91585)
			(xy 393.620891 -9.880364) (xy 393.684277 -9.85218) (xy 393.750552 -9.831696) (xy 393.784582 -9.824974)
			(xy 393.800123 -9.821607) (xy 393.828986 -9.808285) (xy 393.853659 -9.788242) (xy 393.872612 -9.762721)
			(xy 393.884668 -9.733308) (xy 393.88908 -9.701827) (xy 393.885572 -9.670233) (xy 393.874363 -9.640486)
			(xy 393.856148 -9.614433) (xy 393.832059 -9.593692) (xy 393.80359 -9.579549) (xy 393.788138 -9.5758)
			(xy 393.757622 -9.569971) (xy 393.697941 -9.5527) (xy 393.640425 -9.529205) (xy 393.612878 -9.51484)
			(xy 393.58443 -9.4996) (xy 393.3952 -9.4996) (xy 393.3952 -9.313164) (xy 393.379198 -9.284462) (xy 393.36353 -9.255392)
			(xy 393.338105 -9.194442) (xy 393.31971 -9.131015) (xy 393.308579 -9.06592) (xy 393.304854 -8.999984)
			(xy 393.308582 -8.934049) (xy 393.319717 -8.868954) (xy 393.338115 -8.805528) (xy 393.363544 -8.74458)
			(xy 393.379198 -8.715502) (xy 393.3952 -8.6868) (xy 393.3952 -7.91337) (xy 393.379198 -7.884668)
			(xy 393.36353 -7.855598) (xy 393.338104 -7.794648) (xy 393.319708 -7.731221) (xy 393.308577 -7.666125)
			(xy 393.304851 -7.60019) (xy 393.308579 -7.534254) (xy 393.319713 -7.469159) (xy 393.338111 -7.405732)
			(xy 393.363539 -7.344783) (xy 393.379198 -7.315708) (xy 393.3952 -7.287006) (xy 393.3952 -6.513322)
			(xy 393.379198 -6.48462) (xy 393.362144 -6.452899) (xy 393.335061 -6.386163) (xy 393.316381 -6.316606)
			(xy 393.306387 -6.245282) (xy 393.305284 -6.209284) (xy 393.304473 -6.187335) (xy 393.296239 -6.144195)
			(xy 393.280711 -6.103113) (xy 393.258351 -6.065312) (xy 393.229825 -6.031918) (xy 393.195983 -6.003926)
			(xy 393.157832 -5.982169) (xy 393.116509 -5.967295) (xy 393.073243 -5.959747) (xy 393.051284 -5.959348)
			(xy 392.724132 -5.959348) (xy 392.700491 -5.95986) (xy 392.654021 -5.968588) (xy 392.609971 -5.985766)
			(xy 392.569861 -6.010802) (xy 392.535078 -6.04283) (xy 392.506826 -6.080742) (xy 392.486079 -6.123229)
			(xy 392.473555 -6.168823) (xy 392.469687 -6.215946) (xy 392.471656 -6.23951) (xy 392.473869 -6.263767)
			(xy 392.474755 -6.312471) (xy 392.473434 -6.336792) (xy 392.470971 -6.368978) (xy 392.45983 -6.432563)
			(xy 392.441748 -6.494532) (xy 392.429746 -6.524498) (xy 392.420856 -6.545326) (xy 392.4046 -6.579108)
			(xy 392.4046 -7.420864) (xy 392.421618 -7.456932) (xy 392.427206 -7.469886) (xy 392.440071 -7.501145)
			(xy 392.459341 -7.565939) (xy 392.471006 -7.632523) (xy 392.474912 -7.700009) (xy 392.471004 -7.767495)
			(xy 392.459337 -7.834079) (xy 392.440065 -7.898872) (xy 392.427206 -7.930134) (xy 392.421618 -7.943088)
			(xy 392.4046 -7.979156) (xy 392.4046 -8.339836) (xy 392.385601 -8.351333) (xy 392.351591 -8.379881)
			(xy 392.32306 -8.413906) (xy 392.300876 -8.452371) (xy 392.285716 -8.494107) (xy 392.278041 -8.537843)
			(xy 392.278084 -8.582247) (xy 392.285844 -8.625967) (xy 392.301084 -8.667674) (xy 392.323342 -8.706097)
			(xy 392.33729 -8.723376) (xy 392.358112 -8.748795) (xy 392.394536 -8.803485) (xy 392.4246 -8.861913)
			(xy 392.447927 -8.923343) (xy 392.464222 -8.987) (xy 392.47328 -9.052082) (xy 392.474986 -9.11777)
			(xy 392.469319 -9.183235) (xy 392.45635 -9.247652) (xy 392.436244 -9.31021) (xy 392.423142 -9.340342)
			(xy 392.5824 -9.4996) (xy 392.5824 -12.5476) (xy 392.272774 -12.857226) (xy 392.298537 -12.880154)
			(xy 392.345054 -12.931074) (xy 392.385257 -12.987112) (xy 392.418591 -13.04749) (xy 392.44459 -13.11137)
			(xy 392.462896 -13.177865) (xy 392.473252 -13.246051) (xy 392.475517 -13.314983) (xy 392.469657 -13.383702)
			(xy 392.455755 -13.451255) (xy 392.434004 -13.516703) (xy 392.404705 -13.579139) (xy 392.368265 -13.637695)
			(xy 392.32519 -13.691558) (xy 392.276079 -13.73998) (xy 392.221613 -13.78229) (xy 392.162549 -13.817899)
			(xy 392.099706 -13.846313) (xy 392.033956 -13.867139) (xy 391.966214 -13.880086) (xy 391.897419 -13.884974)
			(xy 391.828527 -13.881737) (xy 391.760493 -13.870418) (xy 391.694264 -13.851176) (xy 391.630757 -13.824277)
			(xy 391.570856 -13.790094) (xy 391.515391 -13.749103) (xy 391.465132 -13.701872) (xy 391.420779 -13.649058)
			(xy 391.382945 -13.591393) (xy 391.352157 -13.529678) (xy 391.328842 -13.46477) (xy 391.313324 -13.39757)
			(xy 391.305818 -13.329011) (xy 391.306429 -13.260045) (xy 391.315147 -13.19163) (xy 391.331852 -13.124715)
			(xy 391.356313 -13.06023) (xy 391.388188 -12.99907) (xy 391.407142 -12.970256) (xy 391.419661 -12.951047)
			(xy 391.438303 -12.909162) (xy 391.449138 -12.864615) (xy 391.451817 -12.818848) (xy 391.446253 -12.773341)
			(xy 391.439908 -12.751308) (xy 391.3124 -12.6238) (xy 391.287 -12.6238) (xy 391.16 -12.4968) (xy 391.16 -9.525)
			(xy 391.353294 -9.331706) (xy 391.339524 -9.298458) (xy 391.319297 -9.229394) (xy 391.307702 -9.158369)
			(xy 391.304915 -9.086457) (xy 391.310978 -9.014748) (xy 391.3258 -8.944326) (xy 391.349155 -8.876256)
			(xy 391.380692 -8.811568) (xy 391.419932 -8.751242) (xy 391.442702 -8.723376) (xy 391.457075 -8.705546)
			(xy 391.479813 -8.665796) (xy 391.49506 -8.622615) (xy 391.502324 -8.577401) (xy 391.501368 -8.531617)
			(xy 391.492224 -8.486746) (xy 391.475188 -8.444239) (xy 391.450811 -8.405473) (xy 391.419882 -8.371702)
			(xy 391.383403 -8.344019) (xy 391.3632 -8.333232) (xy 391.3632 -7.955534) (xy 391.352786 -7.931404)
			(xy 391.339789 -7.899987) (xy 391.320313 -7.834846) (xy 391.308521 -7.767885) (xy 391.304571 -7.700009)
			(xy 391.308519 -7.632133) (xy 391.320309 -7.565172) (xy 391.339783 -7.50003) (xy 391.352786 -7.468616)
			(xy 391.3632 -7.444486) (xy 391.3632 -6.55574) (xy 391.352786 -6.53161) (xy 391.33923 -6.498837)
			(xy 391.319253 -6.430785) (xy 391.307661 -6.360815) (xy 391.304625 -6.289957) (xy 391.310189 -6.219252)
			(xy 391.316718 -6.184392) (xy 391.319893 -6.169234) (xy 391.327645 -6.139246) (xy 391.332212 -6.124448)
			(xy 391.338054 -6.105906) (xy 391.338054 -6.086348) (xy 391.337565 -6.069691) (xy 391.328951 -6.037511)
			(xy 391.312298 -6.008659) (xy 391.288743 -5.985103) (xy 391.259891 -5.96845) (xy 391.227711 -5.959835)
			(xy 391.211054 -5.959348) (xy 391.118344 -5.959348) (xy 390.416796 -5.2578) (xy 390.255252 -5.2578)
			(xy 390.222232 -5.281168) (xy 390.208008 -5.29082) (xy 390.189675 -5.304039) (xy 390.157569 -5.335845)
			(xy 390.131593 -5.372826) (xy 390.112565 -5.413818) (xy 390.101083 -5.457528) (xy 390.097511 -5.502579)
			(xy 390.10196 -5.547553) (xy 390.11429 -5.591031) (xy 390.134114 -5.631644) (xy 390.160805 -5.668112)
			(xy 390.193524 -5.699287) (xy 390.212072 -5.712206) (xy 390.239714 -5.730991) (xy 390.290945 -5.773915)
			(xy 390.336948 -5.8224) (xy 390.377122 -5.875814) (xy 390.410944 -5.933461) (xy 390.437972 -5.994588)
			(xy 390.457855 -6.058398) (xy 390.470332 -6.124059) (xy 390.475241 -6.190715) (xy 390.472518 -6.257495)
			(xy 390.462198 -6.32353) (xy 390.444416 -6.387957) (xy 390.419404 -6.449936) (xy 390.387489 -6.50866)
			(xy 390.349086 -6.563361) (xy 390.304696 -6.613327) (xy 390.280144 -6.636004) (xy 390.261094 -6.653276)
			(xy 390.212072 -6.756654) (xy 390.235948 -6.841744) (xy 390.240937 -6.857446) (xy 390.257728 -6.88578)
			(xy 390.28121 -6.908874) (xy 390.309821 -6.925188) (xy 390.341655 -6.933637) (xy 390.358122 -6.9342)
			(xy 390.4234 -6.9342) (xy 390.4234 -7.359396) (xy 390.432544 -7.382256) (xy 390.444044 -7.412027)
			(xy 390.461243 -7.47349) (xy 390.471645 -7.53646) (xy 390.475127 -7.600189) (xy 390.471647 -7.663918)
			(xy 390.461247 -7.726889) (xy 390.444051 -7.788352) (xy 390.432544 -7.81812) (xy 390.4234 -7.84098)
			(xy 390.4234 -8.75919) (xy 390.432544 -8.78205) (xy 390.444044 -8.811821) (xy 390.461244 -8.873284)
			(xy 390.471647 -8.936254) (xy 390.475129 -8.999983) (xy 390.47165 -9.063712) (xy 390.461251 -9.126684)
			(xy 390.444055 -9.188147) (xy 390.432544 -9.217914) (xy 390.4234 -9.240774) (xy 390.4234 -9.4996)
			(xy 390.195562 -9.4996) (xy 390.167114 -9.51484) (xy 390.139571 -9.529215) (xy 390.082057 -9.552717)
			(xy 390.022373 -9.569983) (xy 389.991854 -9.5758) (xy 389.976433 -9.579619) (xy 389.948 -9.593768)
			(xy 389.923943 -9.614503) (xy 389.905755 -9.640539) (xy 389.894563 -9.670261) (xy 389.891061 -9.701826)
			(xy 389.895466 -9.733278) (xy 389.907504 -9.762668) (xy 389.92643 -9.788172) (xy 389.95107 -9.808209)
			(xy 389.979897 -9.821539) (xy 389.99541 -9.824974) (xy 390.029828 -9.831815) (xy 390.09684 -9.852648)
			(xy 390.160877 -9.881352) (xy 390.221017 -9.917514) (xy 390.276398 -9.960615) (xy 390.326221 -10.010034)
			(xy 390.369771 -10.065061) (xy 390.406422 -10.124905) (xy 390.435647 -10.188705) (xy 390.457026 -10.255545)
			(xy 390.470251 -10.324463) (xy 390.475132 -10.394469) (xy 390.471598 -10.464556) (xy 390.459702 -10.533715)
			(xy 390.439614 -10.600954) (xy 390.411622 -10.665305) (xy 390.376129 -10.725843) (xy 390.355328 -10.754106)
			(xy 390.3345 -10.781284) (xy 390.326118 -10.849102) (xy 390.381998 -10.981182) (xy 390.4488 -11.025632)
			(xy 390.4488 -11.627104) (xy 390.454896 -11.649456) (xy 390.457182 -11.6586) (xy 390.465311 -11.693403)
			(xy 390.474028 -11.764342) (xy 390.474031 -11.835815) (xy 390.465319 -11.906755) (xy 390.457182 -11.941556)
			(xy 390.454896 -11.9507) (xy 390.4488 -11.973052) (xy 390.4488 -13.027152) (xy 390.454896 -13.049504)
			(xy 390.457182 -13.058648) (xy 390.465309 -13.093451) (xy 390.474019 -13.16439) (xy 390.474016 -13.235861)
			(xy 390.465299 -13.306798) (xy 390.457182 -13.341604) (xy 390.454896 -13.350748) (xy 390.4488 -13.3731)
			(xy 390.4488 -13.7668) (xy 390.391142 -13.7668) (xy 390.374484 -13.76729) (xy 390.3423 -13.775904)
			(xy 390.313443 -13.792556) (xy 390.289881 -13.81611) (xy 390.27322 -13.844961) (xy 390.264595 -13.877142)
			(xy 390.264142 -13.8938) (xy 390.264142 -13.9319) (xy 390.28497 -13.96365) (xy 390.299952 -13.987341)
			(xy 390.323556 -14.03818) (xy 390.339467 -14.091926) (xy 390.347342 -14.147422) (xy 390.347012 -14.203473)
			(xy 390.338483 -14.258872) (xy 390.321939 -14.312426) (xy 390.297736 -14.362984) (xy 390.266396 -14.409455)
			(xy 390.228593 -14.45084) (xy 390.185141 -14.486248) (xy 390.136975 -14.514916) (xy 390.085132 -14.536228)
			(xy 390.03073 -14.549723) (xy 389.974938 -14.555113) (xy 389.918957 -14.552281) (xy 389.863994 -14.541287)
			(xy 389.811232 -14.522369) (xy 389.761805 -14.495933) (xy 389.716779 -14.46255) (xy 389.677123 -14.422937)
			(xy 389.64369 -14.377947) (xy 389.617201 -14.32855) (xy 389.598225 -14.275808) (xy 389.587171 -14.220856)
			(xy 389.584278 -14.164879) (xy 389.589606 -14.109081) (xy 389.595868 -14.08176) (xy 389.600913 -14.059266)
			(xy 389.603724 -14.013256) (xy 389.598192 -13.967495) (xy 389.584497 -13.923481) (xy 389.563089 -13.882659)
			(xy 389.534669 -13.846367) (xy 389.50017 -13.815796) (xy 389.460724 -13.791948) (xy 389.417623 -13.775605)
			(xy 389.372282 -13.767304) (xy 389.349234 -13.7668) (xy 389.3312 -13.7668) (xy 389.3312 -13.3731)
			(xy 389.325104 -13.350748) (xy 389.322818 -13.341604) (xy 389.314688 -13.306801) (xy 389.305971 -13.235862)
			(xy 389.305968 -13.164389) (xy 389.314679 -13.093449) (xy 389.322818 -13.058648) (xy 389.325104 -13.049504)
			(xy 389.3312 -13.027152) (xy 389.3312 -11.973052) (xy 389.325104 -11.9507) (xy 389.322818 -11.941556)
			(xy 389.314691 -11.906753) (xy 389.30598 -11.835814) (xy 389.305983 -11.764343) (xy 389.314699 -11.693405)
			(xy 389.322818 -11.6586) (xy 389.325104 -11.649456) (xy 389.3312 -11.627104) (xy 389.3312 -11.0236)
			(xy 389.334248 -11.0236) (xy 389.397748 -10.981436) (xy 389.424672 -10.917682) (xy 389.424672 -10.756138)
			(xy 389.403336 -10.724134) (xy 389.384891 -10.695555) (xy 389.354004 -10.634952) (xy 389.330358 -10.571173)
			(xy 389.314274 -10.505081) (xy 389.305969 -10.437569) (xy 389.305554 -10.369549) (xy 389.313037 -10.301941)
			(xy 389.328314 -10.235658) (xy 389.351181 -10.171596) (xy 389.381327 -10.11062) (xy 389.418346 -10.053555)
			(xy 389.461738 -10.001172) (xy 389.510915 -9.954178) (xy 389.565214 -9.913209) (xy 389.6239 -9.878818)
			(xy 389.686181 -9.85147) (xy 389.751215 -9.831534) (xy 389.78459 -9.824974) (xy 389.80013 -9.821606)
			(xy 389.828991 -9.808283) (xy 389.853663 -9.78824) (xy 389.872615 -9.76272) (xy 389.88467 -9.733307)
			(xy 389.889081 -9.701827) (xy 389.885574 -9.670234) (xy 389.874365 -9.640488) (xy 389.856152 -9.614436)
			(xy 389.832064 -9.593694) (xy 389.803597 -9.57955) (xy 389.788146 -9.5758) (xy 389.75763 -9.569971)
			(xy 389.697949 -9.552701) (xy 389.640432 -9.529207) (xy 389.612886 -9.51484) (xy 389.584438 -9.4996)
			(xy 389.3566 -9.4996) (xy 389.3566 -9.240774) (xy 389.347456 -9.217914) (xy 389.335958 -9.188143)
			(xy 389.318762 -9.126681) (xy 389.308363 -9.063711) (xy 389.304884 -8.999983) (xy 389.308367 -8.936256)
			(xy 389.31877 -8.873287) (xy 389.335969 -8.811825) (xy 389.347456 -8.78205) (xy 389.3566 -8.75919)
			(xy 389.3566 -7.84098) (xy 389.347456 -7.81812) (xy 389.335958 -7.788349) (xy 389.318761 -7.726887)
			(xy 389.308362 -7.663917) (xy 389.304882 -7.600189) (xy 389.308364 -7.536461) (xy 389.318766 -7.473492)
			(xy 389.335965 -7.41203) (xy 389.347456 -7.382256) (xy 389.3566 -7.359396) (xy 389.3566 -6.9342)
			(xy 389.421878 -6.9342) (xy 389.438351 -6.933681) (xy 389.470197 -6.925242) (xy 389.498815 -6.908921)
			(xy 389.522294 -6.88581) (xy 389.539065 -6.857453) (xy 389.544052 -6.841744) (xy 389.567928 -6.756654)
			(xy 389.518906 -6.653276) (xy 389.499856 -6.636004) (xy 389.475287 -6.613353) (xy 389.43092 -6.563379)
			(xy 389.392538 -6.508673) (xy 389.360643 -6.449949) (xy 389.335648 -6.387972) (xy 389.317881 -6.32355)
			(xy 389.307574 -6.257523) (xy 389.304859 -6.190751) (xy 389.309773 -6.124105) (xy 389.322252 -6.058453)
			(xy 389.342133 -5.994652) (xy 389.369157 -5.933532) (xy 389.402971 -5.875892) (xy 389.443136 -5.822481)
			(xy 389.489126 -5.773996) (xy 389.540343 -5.73107) (xy 389.567928 -5.712206) (xy 389.586526 -5.699347)
			(xy 389.619267 -5.668169) (xy 389.645976 -5.631692) (xy 389.665814 -5.591065) (xy 389.678153 -5.547571)
			(xy 389.682605 -5.50258) (xy 389.67903 -5.457511) (xy 389.667541 -5.413785) (xy 389.648498 -5.37278)
			(xy 389.622504 -5.335789) (xy 389.590378 -5.303979) (xy 389.571992 -5.29082) (xy 389.543504 -5.271776)
			(xy 389.490747 -5.228042) (xy 389.443464 -5.178442) (xy 389.402302 -5.123655) (xy 389.367826 -5.064432)
			(xy 389.340509 -5.001585) (xy 389.320724 -4.935977) (xy 389.308745 -4.868505) (xy 389.304733 -4.800096)
			(xy 389.308746 -4.731686) (xy 389.320726 -4.664215) (xy 389.340512 -4.598606) (xy 389.36783 -4.53576)
			(xy 389.402307 -4.476538) (xy 389.443469 -4.421751) (xy 389.490754 -4.372152) (xy 389.543511 -4.328419)
			(xy 389.571992 -4.309364) (xy 389.590157 -4.296292) (xy 389.622009 -4.264863) (xy 389.647865 -4.228341)
			(xy 389.666925 -4.187855) (xy 389.678601 -4.144657) (xy 389.682531 -4.100082) (xy 389.678595 -4.055507)
			(xy 389.666913 -4.012311) (xy 389.647847 -3.971828) (xy 389.621985 -3.93531) (xy 389.590129 -3.903884)
			(xy 389.571992 -3.890772) (xy 389.543501 -3.871728) (xy 389.490738 -3.827993) (xy 389.443449 -3.778392)
			(xy 389.402281 -3.723603) (xy 389.3678 -3.664377) (xy 389.340477 -3.601527) (xy 389.320689 -3.535914)
			(xy 389.308704 -3.468438) (xy 389.30469 -3.400024) (xy 389.308699 -3.331609) (xy 389.320677 -3.264132)
			(xy 389.340461 -3.198518) (xy 389.367778 -3.135666) (xy 389.402255 -3.076437) (xy 389.443418 -3.021645)
			(xy 389.490703 -2.972039) (xy 389.543463 -2.928301) (xy 389.571992 -2.909316) (xy 389.590328 -2.896097)
			(xy 389.62244 -2.86429) (xy 389.648422 -2.827306) (xy 389.667456 -2.786311) (xy 389.678943 -2.742597)
			(xy 389.682519 -2.69754) (xy 389.678073 -2.652562) (xy 389.665744 -2.609077) (xy 389.645922 -2.568458)
			(xy 389.61923 -2.531983) (xy 389.58651 -2.500802) (xy 389.567928 -2.48793) (xy 389.534007 -2.464653)
			(xy 389.472436 -2.410091) (xy 389.445246 -2.379218) (xy 389.441944 -2.375154) (xy 389.440928 -2.374138)
			(xy 389.437372 -2.36982) (xy 389.433816 -2.365756) (xy 389.429498 -2.360422) (xy 389.412226 -2.338578)
			(xy 389.310372 -2.286) (xy 388.6454 -2.286) (xy 388.628752 -2.286543) (xy 388.596589 -2.295161) (xy 388.567754 -2.311809)
			(xy 388.544209 -2.335354) (xy 388.527561 -2.364189) (xy 388.518943 -2.396352) (xy 388.5184 -2.413)
			(xy 388.5184 -4.172458) (xy 388.496626 -4.17814) (xy 388.455375 -4.196113) (xy 388.417936 -4.221073)
			(xy 388.385482 -4.25224) (xy 388.359027 -4.288637) (xy 388.339399 -4.329127) (xy 388.327213 -4.372442)
			(xy 388.32285 -4.417226) (xy 388.326447 -4.462078) (xy 388.337891 -4.505595) (xy 388.356823 -4.546414)
			(xy 388.369302 -4.565142) (xy 388.38795 -4.592636) (xy 388.419593 -4.651052) (xy 388.444413 -4.712678)
			(xy 388.46209 -4.776719) (xy 388.472397 -4.842351) (xy 388.4752 -4.908728) (xy 388.470464 -4.974995)
			(xy 388.45825 -5.040298) (xy 388.438714 -5.103797) (xy 388.412109 -5.164674) (xy 388.378778 -5.222143)
			(xy 388.339149 -5.275466) (xy 388.293733 -5.323955) (xy 388.243115 -5.366985) (xy 388.187947 -5.404002)
			(xy 388.128941 -5.43453) (xy 388.066855 -5.458175) (xy 388.034784 -5.466842) (xy 387.994906 -5.477002)
			(xy 387.960108 -5.518404) (xy 387.950965 -5.529985) (xy 387.937744 -5.556354) (xy 387.930952 -5.585059)
			(xy 387.930954 -5.614557) (xy 387.93775 -5.643262) (xy 387.950975 -5.669629) (xy 387.960108 -5.681218)
			(xy 387.994906 -5.723128) (xy 388.035038 -5.733288) (xy 388.042658 -5.73532) (xy 388.05993 -5.7404)
			(xy 388.4422 -5.7404) (xy 388.4422 -6.106414) (xy 388.448042 -6.124956) (xy 388.458183 -6.159042)
			(xy 388.471083 -6.228979) (xy 388.475407 -6.299964) (xy 388.471092 -6.370949) (xy 388.458201 -6.440888)
			(xy 388.448042 -6.474968) (xy 388.4422 -6.49351) (xy 388.4422 -7.506462) (xy 388.448042 -7.525004)
			(xy 388.45818 -7.55909) (xy 388.471074 -7.629026) (xy 388.475393 -7.70001) (xy 388.471072 -7.770993)
			(xy 388.458176 -7.840929) (xy 388.448042 -7.875016) (xy 388.4422 -7.893558) (xy 388.4422 -8.356092)
			(xy 388.421948 -8.36634) (xy 388.385143 -8.392894) (xy 388.353643 -8.425565) (xy 388.328449 -8.463314)
			(xy 388.310363 -8.504938) (xy 388.299962 -8.549114) (xy 388.297575 -8.594435) (xy 388.303279 -8.639459)
			(xy 388.316893 -8.682753) (xy 388.337982 -8.722939) (xy 388.351522 -8.741156) (xy 388.371322 -8.767318)
			(xy 388.405571 -8.823284) (xy 388.433337 -8.882734) (xy 388.454272 -8.944918) (xy 388.468112 -9.009056)
			(xy 388.474683 -9.07434) (xy 388.473903 -9.139949) (xy 388.465781 -9.205059) (xy 388.45042 -9.268849)
			(xy 388.428013 -9.330518) (xy 388.398841 -9.389291) (xy 388.363272 -9.444427) (xy 388.342886 -9.470136)
			(xy 388.339331 -9.474635) (xy 388.332969 -9.484174) (xy 388.330186 -9.489186) (xy 388.5692 -9.7282)
			(xy 388.568946 -12.5222) (xy 388.568946 -12.5476) (xy 388.568946 -13.207746) (xy 388.5692 -13.208)
			(xy 388.5692 -13.2588) (xy 388.568692 -13.259308) (xy 388.5692 -13.259308) (xy 388.5692 -13.5128)
			(xy 388.2136 -13.8684) (xy 388.028688 -13.8684) (xy 387.994366 -13.876282) (xy 387.924453 -13.884736)
			(xy 387.854031 -13.884736) (xy 387.784118 -13.876282) (xy 387.749796 -13.8684) (xy 387.35 -13.8684)
			(xy 387.223 -13.7414) (xy 387.223508 -12.5476) (xy 387.223 -12.5476) (xy 387.223 -8.9662) (xy 387.386576 -8.802624)
			(xy 387.396184 -8.786682) (xy 387.417155 -8.755924) (xy 387.428486 -8.741156) (xy 387.441922 -8.723096)
			(xy 387.462868 -8.683258) (xy 387.476468 -8.640352) (xy 387.482298 -8.595722) (xy 387.480175 -8.550763)
			(xy 387.470166 -8.506881) (xy 387.452583 -8.465448) (xy 387.427977 -8.427761) (xy 387.397117 -8.394996)
			(xy 387.360968 -8.368181) (xy 387.320661 -8.348152) (xy 387.2992 -8.34136) (xy 387.2992 -5.7404)
			(xy 387.720078 -5.7404) (xy 387.73735 -5.73532) (xy 387.74497 -5.733288) (xy 387.785102 -5.723128)
			(xy 387.8199 -5.681726) (xy 387.829002 -5.670126) (xy 387.842157 -5.643746) (xy 387.848915 -5.615053)
			(xy 387.848919 -5.585576) (xy 387.842167 -5.556882) (xy 387.829018 -5.530498) (xy 387.8199 -5.518912)
			(xy 387.785102 -5.477002) (xy 387.745224 -5.466842) (xy 387.713152 -5.458171) (xy 387.651056 -5.434541)
			(xy 387.592039 -5.404025) (xy 387.536862 -5.367016) (xy 387.486234 -5.323991) (xy 387.44081 -5.275504)
			(xy 387.401175 -5.222181) (xy 387.36784 -5.16471) (xy 387.341233 -5.10383) (xy 387.321699 -5.040326)
			(xy 387.309489 -4.975018) (xy 387.30476 -4.908747) (xy 387.307574 -4.842366) (xy 387.317894 -4.776733)
			(xy 387.335587 -4.712692) (xy 387.360425 -4.651069) (xy 387.392088 -4.592659) (xy 387.410706 -4.565142)
			(xy 387.423867 -4.545398) (xy 387.44337 -4.502149) (xy 387.454507 -4.45603) (xy 387.456892 -4.408647)
			(xy 387.450441 -4.361643) (xy 387.435379 -4.316654) (xy 387.41223 -4.275241) (xy 387.381797 -4.238844)
			(xy 387.345137 -4.208727) (xy 387.3246 -4.196842) (xy 387.3246 -3.650488) (xy 387.321044 -3.635756)
			(xy 387.313579 -3.602345) (xy 387.305584 -3.534351) (xy 387.305581 -3.465888) (xy 387.313572 -3.397893)
			(xy 387.321044 -3.364484) (xy 387.3246 -3.349752) (xy 387.3246 -2.413) (xy 387.324057 -2.396352)
			(xy 387.315439 -2.364189) (xy 387.298791 -2.335354) (xy 387.275246 -2.311809) (xy 387.246411 -2.295161)
			(xy 387.214248 -2.286543) (xy 387.1976 -2.286) (xy 386.588 -2.286) (xy 386.571352 -2.286543) (xy 386.539189 -2.295161)
			(xy 386.510354 -2.311809) (xy 386.486809 -2.335354) (xy 386.470161 -2.364189) (xy 386.461543 -2.396352)
			(xy 386.461 -2.413) (xy 386.461 -3.273044) (xy 386.46354 -3.28549) (xy 386.47047 -3.323313) (xy 386.475514 -3.400043)
			(xy 386.470459 -3.476773) (xy 386.46354 -3.514598) (xy 386.461 -3.527044) (xy 386.461 -4.673092)
			(xy 386.46354 -4.685538) (xy 386.470474 -4.723361) (xy 386.475524 -4.800092) (xy 386.470476 -4.876823)
			(xy 386.46354 -4.914646) (xy 386.461 -4.927092) (xy 386.461 -5.3594) (xy 386.061458 -5.3594) (xy 386.045202 -5.363972)
			(xy 386.008372 -5.372608) (xy 385.991862 -5.37591) (xy 385.976441 -5.379729) (xy 385.948009 -5.393876)
			(xy 385.923953 -5.414609) (xy 385.905766 -5.440644) (xy 385.894574 -5.470364) (xy 385.891072 -5.501928)
			(xy 385.895477 -5.533379) (xy 385.907516 -5.562766) (xy 385.926443 -5.588268) (xy 385.951083 -5.608304)
			(xy 385.979909 -5.62163) (xy 385.995418 -5.625084) (xy 386.028089 -5.631548) (xy 386.091811 -5.650918)
			(xy 386.152919 -5.677406) (xy 386.21062 -5.710668) (xy 386.264166 -5.750274) (xy 386.312862 -5.79571)
			(xy 386.356079 -5.846386) (xy 386.393254 -5.901647) (xy 386.423907 -5.960775) (xy 386.447641 -6.023005)
			(xy 386.464146 -6.087529) (xy 386.47321 -6.153511) (xy 386.474715 -6.220095) (xy 386.468642 -6.286419)
			(xy 386.455068 -6.351623) (xy 386.434171 -6.414861) (xy 386.406221 -6.475314) (xy 386.37158 -6.532198)
			(xy 386.351526 -6.558788) (xy 386.344414 -6.567932) (xy 386.330952 -6.58495) (xy 386.295646 -6.679184)
			(xy 386.33273 -6.776466) (xy 386.338636 -6.790616) (xy 386.356109 -6.815801) (xy 386.379092 -6.836083)
			(xy 386.406253 -6.85029) (xy 386.436022 -6.857599) (xy 386.451348 -6.858) (xy 386.461 -6.858) (xy 386.461 -7.473188)
			(xy 386.46354 -7.485634) (xy 386.470474 -7.523457) (xy 386.475525 -7.600188) (xy 386.470477 -7.67692)
			(xy 386.46354 -7.714742) (xy 386.461 -7.727188) (xy 386.461 -8.872982) (xy 386.46354 -8.885428) (xy 386.470474 -8.923251)
			(xy 386.475526 -8.999982) (xy 386.470479 -9.076714) (xy 386.46354 -9.114536) (xy 386.461 -9.126982)
			(xy 386.461 -9.642094) (xy 386.440682 -9.650015) (xy 386.402898 -9.671782) (xy 386.369386 -9.699682)
			(xy 386.341133 -9.732896) (xy 386.318967 -9.770448) (xy 386.30354 -9.811233) (xy 386.295306 -9.854055)
			(xy 386.294507 -9.897653) (xy 386.301165 -9.940747) (xy 386.315086 -9.982071) (xy 386.335861 -10.02041)
			(xy 386.348986 -10.037826) (xy 386.368933 -10.063836) (xy 386.403534 -10.119508) (xy 386.431688 -10.178703)
			(xy 386.45304 -10.240677) (xy 386.467324 -10.304651) (xy 386.474358 -10.369821) (xy 386.474056 -10.435369)
			(xy 386.46642 -10.500472) (xy 386.451547 -10.564312) (xy 386.429623 -10.626085) (xy 386.400924 -10.685018)
			(xy 386.383784 -10.712958) (xy 386.380228 -10.718546) (xy 386.37083 -10.733278) (xy 386.343398 -10.820908)
			(xy 386.423408 -10.9982) (xy 386.4356 -10.9982) (xy 386.4356 -11.59002) (xy 386.442458 -11.610086)
			(xy 386.452544 -11.640733) (xy 386.466679 -11.703688) (xy 386.47379 -11.767818) (xy 386.473793 -11.83234)
			(xy 386.466686 -11.89647) (xy 386.452555 -11.959427) (xy 386.442458 -11.99007) (xy 386.4356 -12.010136)
			(xy 386.4356 -12.990068) (xy 386.442458 -13.010134) (xy 386.452541 -13.040781) (xy 386.466671 -13.103736)
			(xy 386.473777 -13.167864) (xy 386.473775 -13.232385) (xy 386.466663 -13.296513) (xy 386.452528 -13.359466)
			(xy 386.442458 -13.390118) (xy 386.4356 -13.410184) (xy 386.4356 -13.8176) (xy 386.256276 -13.8176)
			(xy 386.232961 -13.818127) (xy 386.187114 -13.826635) (xy 386.143586 -13.843359) (xy 386.103839 -13.867741)
			(xy 386.069203 -13.898962) (xy 386.040841 -13.935975) (xy 386.019704 -13.977539) (xy 386.006501 -14.02226)
			(xy 386.001674 -14.06864) (xy 386.003038 -14.09192) (xy 386.004778 -14.119456) (xy 386.001261 -14.174516)
			(xy 385.989849 -14.228495) (xy 385.97078 -14.280268) (xy 385.944452 -14.328753) (xy 385.911413 -14.37294)
			(xy 385.872354 -14.411906) (xy 385.828089 -14.44484) (xy 385.779542 -14.471053) (xy 385.727724 -14.489999)
			(xy 385.673718 -14.501283) (xy 385.618649 -14.504669) (xy 385.563668 -14.500087) (xy 385.509919 -14.487632)
			(xy 385.458526 -14.467565) (xy 385.410559 -14.440303) (xy 385.36702 -14.406415) (xy 385.328817 -14.366609)
			(xy 385.296747 -14.321715) (xy 385.271478 -14.272669) (xy 385.253539 -14.220494) (xy 385.243302 -14.16628)
			(xy 385.240983 -14.111156) (xy 385.246628 -14.056273) (xy 385.260121 -14.002776) (xy 385.270248 -13.977112)
			(xy 385.275074 -13.965428) (xy 385.2926 -13.929106) (xy 385.2926 -10.9982) (xy 385.312158 -10.9982)
			(xy 385.374896 -10.957814) (xy 385.420362 -10.85723) (xy 385.42666 -10.842079) (xy 385.432114 -10.809735)
			(xy 385.429129 -10.777072) (xy 385.417904 -10.746252) (xy 385.408932 -10.732516) (xy 385.390083 -10.704403)
			(xy 385.358277 -10.644655) (xy 385.333585 -10.581633) (xy 385.316339 -10.516181) (xy 385.306768 -10.449174)
			(xy 385.305002 -10.381511) (xy 385.311063 -10.314096) (xy 385.32487 -10.247833) (xy 385.34624 -10.183609)
			(xy 385.374884 -10.122282) (xy 385.410421 -10.064675) (xy 385.43103 -10.037826) (xy 385.445031 -10.019222)
			(xy 385.466712 -9.978024) (xy 385.480525 -9.933565) (xy 385.486008 -9.887334) (xy 385.482978 -9.840877)
			(xy 385.471536 -9.79575) (xy 385.452065 -9.753462) (xy 385.425216 -9.715429) (xy 385.391889 -9.682922)
			(xy 385.353197 -9.657031) (xy 385.310437 -9.638621) (xy 385.265038 -9.628309) (xy 385.2418 -9.626854)
			(xy 385.2418 -6.84276) (xy 385.262253 -6.834839) (xy 385.300289 -6.813007) (xy 385.334011 -6.784967)
			(xy 385.362416 -6.751552) (xy 385.38466 -6.713756) (xy 385.400082 -6.6727) (xy 385.408223 -6.629606)
			(xy 385.408843 -6.585754) (xy 385.401922 -6.542447) (xy 385.387665 -6.500972) (xy 385.377436 -6.481572)
			(xy 385.361235 -6.45102) (xy 385.335325 -6.386901) (xy 385.317161 -6.320172) (xy 385.306995 -6.251767)
			(xy 385.30497 -6.18264) (xy 385.311114 -6.113758) (xy 385.325342 -6.046081) (xy 385.347454 -5.980554)
			(xy 385.377142 -5.918095) (xy 385.413991 -5.859573) (xy 385.457487 -5.805808) (xy 385.507021 -5.757549)
			(xy 385.561903 -5.71547) (xy 385.621366 -5.68016) (xy 385.684579 -5.652112) (xy 385.750659 -5.631717)
			(xy 385.784598 -5.625084) (xy 385.800139 -5.621715) (xy 385.829 -5.608391) (xy 385.853673 -5.588346)
			(xy 385.872625 -5.562824) (xy 385.884681 -5.53341) (xy 385.889092 -5.501929) (xy 385.885585 -5.470334)
			(xy 385.874378 -5.440587) (xy 385.856165 -5.414533) (xy 385.832077 -5.393789) (xy 385.803609 -5.379643)
			(xy 385.788154 -5.37591) (xy 385.771644 -5.372608) (xy 385.734814 -5.363972) (xy 385.718558 -5.3594)
			(xy 385.2926 -5.3594) (xy 385.2926 -2.413) (xy 385.292057 -2.396352) (xy 385.283439 -2.364189) (xy 385.266791 -2.335354)
			(xy 385.243246 -2.311809) (xy 385.214411 -2.295161) (xy 385.182248 -2.286543) (xy 385.1656 -2.286)
			(xy 378.3584 -2.286) (xy 378.222764 -2.421636) (xy 378.206403 -2.438737) (xy 378.179711 -2.477814)
			(xy 378.160716 -2.521156) (xy 378.150073 -2.567267) (xy 378.148151 -2.61455) (xy 378.155016 -2.661372)
			(xy 378.170431 -2.706114) (xy 378.193863 -2.747228) (xy 378.224502 -2.783293) (xy 378.242576 -2.798572)
			(xy 378.301298 -2.846778) (xy 378.414086 -2.948593) (xy 378.521253 -3.056309) (xy 378.622491 -3.169615)
			(xy 378.71751 -3.288185) (xy 378.806035 -3.411679) (xy 378.887812 -3.539741) (xy 378.962606 -3.672004)
			(xy 379.030202 -3.808085) (xy 379.090405 -3.947595) (xy 379.143042 -4.090132) (xy 379.187962 -4.235286)
			(xy 379.225036 -4.382639) (xy 379.254157 -4.531768) (xy 379.275241 -4.682244) (xy 379.288227 -4.833633)
			(xy 379.293079 -4.985501) (xy 379.289782 -5.137411) (xy 379.278345 -5.288926) (xy 379.258803 -5.439609)
			(xy 379.23121 -5.589028) (xy 379.195646 -5.736753) (xy 379.152214 -5.882359) (xy 379.101038 -6.025427)
			(xy 379.042266 -6.165546) (xy 378.976066 -6.302312) (xy 378.90263 -6.435333) (xy 378.822168 -6.564226)
			(xy 378.734911 -6.688619) (xy 378.641112 -6.808156) (xy 378.541038 -6.922492) (xy 378.434979 -7.031299)
			(xy 378.323239 -7.134263) (xy 378.20614 -7.231089) (xy 378.084018 -7.321498) (xy 377.957226 -7.405229)
			(xy 377.826126 -7.482043) (xy 377.691097 -7.551718) (xy 377.622054 -7.583424) (xy 377.60178 -7.593053)
			(xy 377.56471 -7.618349) (xy 377.532665 -7.649769) (xy 377.506644 -7.686333) (xy 377.487456 -7.726903)
			(xy 377.475701 -7.770215) (xy 377.471743 -7.814918) (xy 377.475707 -7.859622) (xy 377.487469 -7.902931)
			(xy 377.506662 -7.943498) (xy 377.532689 -7.980059) (xy 377.564739 -8.011474) (xy 377.601812 -8.036765)
			(xy 377.622054 -8.046466) (xy 377.689957 -8.077544) (xy 377.822749 -8.145897) (xy 377.951754 -8.221153)
			(xy 378.076614 -8.303103) (xy 378.196982 -8.391519) (xy 378.312524 -8.486155) (xy 378.422917 -8.586749)
			(xy 378.527856 -8.693021) (xy 378.627049 -8.804675) (xy 378.720219 -8.921401) (xy 378.807109 -9.042875)
			(xy 378.887477 -9.168759) (xy 378.961099 -9.298704) (xy 379.027771 -9.432348) (xy 379.087308 -9.569319)
			(xy 379.139543 -9.709238) (xy 379.184333 -9.851715) (xy 379.221552 -9.996355) (xy 379.251096 -10.142755)
			(xy 379.272885 -10.290508) (xy 379.286857 -10.439204) (xy 379.292973 -10.58843) (xy 379.291217 -10.737771)
			(xy 379.281593 -10.886812) (xy 379.264129 -11.035139) (xy 379.238872 -11.182339) (xy 379.205892 -11.328004)
			(xy 379.165283 -11.471728) (xy 379.117155 -11.613113) (xy 379.061644 -11.751764) (xy 378.998903 -11.887298)
			(xy 378.929107 -12.019337) (xy 378.852449 -12.147515) (xy 378.769144 -12.271474) (xy 378.679421 -12.390871)
			(xy 378.583531 -12.505374) (xy 378.48174 -12.614665) (xy 378.374332 -12.71844) (xy 378.261603 -12.81641)
			(xy 378.143868 -12.908303) (xy 378.021455 -12.993864) (xy 377.894702 -13.072855) (xy 377.763963 -13.145057)
			(xy 377.629601 -13.210268) (xy 377.491988 -13.268309) (xy 377.351508 -13.319016) (xy 377.28017 -13.341096)
			(xy 377.264751 -13.346265) (xy 377.237018 -13.36323) (xy 377.214484 -13.386663) (xy 377.198618 -13.415038)
			(xy 377.190452 -13.446506) (xy 377.19 -13.462762) (xy 377.19 -14.261338) (xy 377.241308 -14.329156)
			(xy 377.282456 -14.34084) (xy 377.357683 -14.362633) (xy 377.506003 -14.412996) (xy 377.651515 -14.470973)
			(xy 377.79383 -14.536407) (xy 377.932565 -14.609124) (xy 378.067348 -14.688928) (xy 378.197817 -14.775605)
			(xy 378.323622 -14.868922) (xy 378.444426 -14.968629) (xy 378.559905 -15.074459) (xy 378.669747 -15.186127)
			(xy 378.77366 -15.303333) (xy 378.871363 -15.425764) (xy 378.962594 -15.55309) (xy 379.04711 -15.684969)
			(xy 379.124682 -15.821049) (xy 379.195103 -15.960963) (xy 379.258183 -16.104337) (xy 379.313754 -16.250785)
			(xy 379.361667 -16.399914) (xy 379.401792 -16.551325) (xy 379.434021 -16.70461) (xy 379.45827 -16.859359)
			(xy 379.474472 -17.015155) (xy 379.482584 -17.171582) (xy 379.482583 -17.328219) (xy 379.474472 -17.484646)
			(xy 379.45827 -17.640443) (xy 379.434021 -17.795191) (xy 379.401791 -17.948476) (xy 379.361666 -18.099887)
			(xy 379.313754 -18.249016) (xy 379.258183 -18.395464) (xy 379.195102 -18.538837) (xy 379.142373 -18.6436)
			(xy 388.0358 -18.6436) (xy 388.0358 -18.3388) (xy 388.2898 -18.0848) (xy 389.89 -18.0848) (xy 390.1948 -18.3896)
			(xy 390.1948 -18.6436) (xy 390.144 -18.6944) (xy 412.8516 -18.6944) (xy 412.8516 -18.3388) (xy 413.1056 -18.0848)
			(xy 414.7058 -18.0848) (xy 414.9598 -18.3388) (xy 414.9598 -18.669) (xy 414.6804 -18.9484) (xy 413.1056 -18.9484)
			(xy 412.8516 -18.6944) (xy 390.144 -18.6944) (xy 389.9154 -18.923) (xy 388.3152 -18.923) (xy 388.0358 -18.6436)
			(xy 379.142373 -18.6436) (xy 379.124681 -18.678752) (xy 379.047109 -18.814832) (xy 378.962594 -18.946711)
			(xy 378.871362 -19.074037) (xy 378.773659 -19.196468) (xy 378.669747 -19.313674) (xy 378.559904 -19.425342)
			(xy 378.444426 -19.531172) (xy 378.323622 -19.630879) (xy 378.197816 -19.724196) (xy 378.067347 -19.810873)
			(xy 377.932564 -19.890677) (xy 377.793829 -19.963393) (xy 377.651514 -20.028828) (xy 377.506002 -20.086804)
			(xy 377.357682 -20.137167) (xy 377.282456 -20.158964) (xy 377.282202 -20.158964) (xy 377.266521 -20.16397)
			(xy 377.238235 -20.180782) (xy 377.215192 -20.204271) (xy 377.198925 -20.232873) (xy 377.190516 -20.264685)
			(xy 377.19 -20.281138) (xy 377.19 -22.126194) (xy 377.361196 -22.29739) (xy 378.282708 -23.218648)
			(xy 378.282708 -24.8412) (xy 386.7912 -24.8412) (xy 386.7912 -23.2156) (xy 387.0452 -22.9616) (xy 387.35 -22.9616)
			(xy 387.6548 -23.2664) (xy 387.6548 -23.876) (xy 391.414 -23.876) (xy 391.414 -23.495) (xy 391.668 -23.241)
			(xy 393.2682 -23.241) (xy 393.5222 -23.495) (xy 393.5222 -23.8506) (xy 393.2174 -24.1554) (xy 391.6934 -24.1554)
			(xy 391.414 -23.876) (xy 387.6548 -23.876) (xy 387.6548 -24.8412) (xy 398.8054 -24.8412) (xy 398.8054 -23.2156)
			(xy 399.034 -22.987) (xy 399.3896 -22.987) (xy 399.6182 -23.2156) (xy 399.6182 -23.7236) (xy 410.3878 -23.7236)
			(xy 410.3878 -23.4188) (xy 410.6926 -23.114) (xy 412.2674 -23.114) (xy 412.5722 -23.4188) (xy 412.5722 -23.749)
			(xy 412.2928 -24.0284) (xy 410.6926 -24.0284) (xy 410.3878 -23.7236) (xy 399.6182 -23.7236) (xy 399.6182 -24.8412)
			(xy 399.542 -24.9174) (xy 418.2618 -24.9174) (xy 418.2618 -23.2156) (xy 418.4904 -22.987) (xy 418.846 -22.987)
			(xy 419.0746 -23.2156) (xy 419.0746 -24.8412) (xy 418.8206 -25.0952) (xy 418.4396 -25.0952) (xy 418.2618 -24.9174)
			(xy 399.542 -24.9174) (xy 399.3896 -25.0698) (xy 399.034 -25.0698) (xy 398.8054 -24.8412) (xy 387.6548 -24.8412)
			(xy 387.4262 -25.0698) (xy 387.0198 -25.0698) (xy 386.7912 -24.8412) (xy 378.282708 -24.8412) (xy 378.282708 -27.0256)
			(xy 404.5966 -27.0256) (xy 404.5966 -26.67) (xy 404.8506 -26.416) (xy 406.4508 -26.416) (xy 406.7048 -26.67)
			(xy 406.7048 -26.9748) (xy 406.4254 -27.2542) (xy 404.8252 -27.2542) (xy 404.5966 -27.0256) (xy 378.282708 -27.0256)
			(xy 378.282708 -28.41498) (xy 379.357128 -29.4894) (xy 404.8252 -29.4894) (xy 404.8252 -29.1338)
			(xy 405.0538 -28.9052) (xy 406.6794 -28.9052) (xy 406.908 -29.1338) (xy 406.908 -29.464) (xy 406.654 -29.718)
			(xy 405.0538 -29.718) (xy 404.8252 -29.4894) (xy 379.357128 -29.4894) (xy 379.38583 -29.518102) (xy 379.408323 -29.541321)
			(xy 379.447535 -29.592718) (xy 379.479541 -29.648886) (xy 379.50377 -29.70882) (xy 379.519789 -29.771451)
			(xy 379.527311 -29.835659) (xy 379.526202 -29.900296) (xy 379.516482 -29.964208) (xy 379.498324 -30.026252)
			(xy 379.472054 -30.08532) (xy 379.438139 -30.140357) (xy 379.397187 -30.190378) (xy 379.373892 -30.212792)
			(xy 379.357699 -30.228626) (xy 379.330643 -30.26494) (xy 379.310453 -30.305475) (xy 379.297768 -30.348947)
			(xy 379.292991 -30.393979) (xy 379.296272 -30.439145) (xy 379.307507 -30.483013) (xy 379.326341 -30.524196)
			(xy 379.352177 -30.561387) (xy 379.367796 -30.57779) (xy 379.461776 -30.67177) (xy 379.461776 -30.9118)
			(xy 388.6454 -30.9118) (xy 388.6454 -30.5816) (xy 388.9248 -30.3022) (xy 390.4742 -30.3022) (xy 390.7282 -30.5562)
			(xy 390.7282 -30.8864) (xy 390.4742 -31.1404) (xy 388.874 -31.1404) (xy 388.6454 -30.9118) (xy 379.461776 -30.9118)
			(xy 379.461776 -31.1658) (xy 395.8336 -31.1658) (xy 395.8336 -30.8356) (xy 396.0876 -30.5816) (xy 397.6878 -30.5816)
			(xy 397.8656 -30.7594) (xy 410.0576 -30.7594) (xy 410.0576 -30.4292) (xy 410.2862 -30.2006) (xy 411.9118 -30.2006)
			(xy 412.1404 -30.4292) (xy 412.1404 -30.7086) (xy 414.8328 -30.7086) (xy 414.8328 -30.4038) (xy 415.0868 -30.1498)
			(xy 416.687 -30.1498) (xy 416.941 -30.4038) (xy 416.941 -30.734) (xy 416.687 -30.988) (xy 415.1122 -30.988)
			(xy 414.8328 -30.7086) (xy 412.1404 -30.7086) (xy 412.1404 -30.7594) (xy 411.8864 -31.0134) (xy 410.3116 -31.0134)
			(xy 410.0576 -30.7594) (xy 397.8656 -30.7594) (xy 397.9164 -30.8102) (xy 397.9164 -31.1658) (xy 397.6624 -31.4198)
			(xy 396.0876 -31.4198) (xy 395.8336 -31.1658) (xy 379.461776 -31.1658) (xy 379.461776 -32.094932)
			(xy 379.461259 -32.126563) (xy 379.460675 -32.131) (xy 391.033 -32.131) (xy 391.033 -31.8262) (xy 391.287 -31.5722)
			(xy 392.8872 -31.5722) (xy 393.1158 -31.8008) (xy 393.1158 -31.8262) (xy 412.4198 -31.8262) (xy 412.4198 -31.5214)
			(xy 412.6738 -31.2674) (xy 414.2994 -31.2674) (xy 414.5534 -31.5214) (xy 414.5534 -31.8516) (xy 414.2994 -32.1056)
			(xy 412.6992 -32.1056) (xy 412.4198 -31.8262) (xy 393.1158 -31.8262) (xy 393.1158 -32.1564) (xy 392.8618 -32.4104)
			(xy 391.3124 -32.4104) (xy 391.033 -32.131) (xy 379.460675 -32.131) (xy 379.453002 -32.189283) (xy 379.436629 -32.250389)
			(xy 379.412419 -32.308835) (xy 379.380789 -32.36362) (xy 379.342278 -32.413809) (xy 379.297545 -32.458542)
			(xy 379.247356 -32.497053) (xy 379.192571 -32.528683) (xy 379.134125 -32.552893) (xy 379.073019 -32.569266)
			(xy 379.010299 -32.577523) (xy 378.947037 -32.577523) (xy 378.884317 -32.569266) (xy 378.823211 -32.552893)
			(xy 378.764765 -32.528683) (xy 378.70998 -32.497053) (xy 378.659791 -32.458542) (xy 378.615058 -32.413809)
			(xy 378.576547 -32.36362) (xy 378.544917 -32.308835) (xy 378.520707 -32.250389) (xy 378.504334 -32.189283)
			(xy 378.496077 -32.126563) (xy 378.49556 -32.094932) (xy 378.49556 -31.072074) (xy 376.460004 -29.036264)
			(xy 376.163332 -28.739846) (xy 376.151161 -28.728493) (xy 376.122322 -28.711904) (xy 376.090178 -28.703319)
			(xy 376.056908 -28.703319) (xy 376.024764 -28.711904) (xy 375.995925 -28.728493) (xy 375.983754 -28.739846)
			(xy 375.158 -29.5656) (xy 357.418894 -29.5656) (xy 357.395851 -29.566094) (xy 357.35052 -29.574393)
			(xy 357.30743 -29.590736) (xy 357.267996 -29.614586) (xy 357.233514 -29.64516) (xy 357.205114 -29.681455)
			(xy 357.18373 -29.722278) (xy 357.170063 -29.76629) (xy 357.164563 -29.812046) (xy 357.167409 -29.858043)
			(xy 357.178509 -29.902771) (xy 357.1875 -29.923994) (xy 357.204763 -29.963508) (xy 357.232542 -30.045147)
			(xy 357.252405 -30.129064) (xy 357.26417 -30.214493) (xy 357.26773 -30.300655) (xy 357.263052 -30.386764)
			(xy 357.25018 -30.472033) (xy 357.229231 -30.555685) (xy 357.200395 -30.636957) (xy 357.163936 -30.715106)
			(xy 357.120187 -30.78942) (xy 357.069546 -30.85922) (xy 357.012477 -30.92387) (xy 356.949499 -30.98278)
			(xy 356.881188 -31.035412) (xy 356.808166 -31.081286) (xy 356.7311 -31.119982) (xy 356.650694 -31.151149)
			(xy 356.567681 -31.174502) (xy 356.482818 -31.189828) (xy 356.39688 -31.196986) (xy 356.310651 -31.195911)
			(xy 356.224918 -31.186614) (xy 356.140464 -31.169179) (xy 356.058058 -31.143765) (xy 355.978453 -31.110605)
			(xy 355.902376 -31.07) (xy 355.83052 -31.022321) (xy 355.763541 -30.968003) (xy 355.70205 -30.907543)
			(xy 355.64661 -30.841491) (xy 355.597724 -30.77045) (xy 355.576378 -30.732984) (xy 355.5645 -30.712691)
			(xy 355.534473 -30.676512) (xy 355.498308 -30.646468) (xy 355.457238 -30.623582) (xy 355.412661 -30.608633)
			(xy 355.366097 -30.602131) (xy 355.31913 -30.604297) (xy 355.273362 -30.615058) (xy 355.23035 -30.634046)
			(xy 355.191561 -30.660616) (xy 355.17455 -30.67685) (xy 353.06 -32.7914) (xy 353.06 -33.639119) (xy 386.265407 -33.639119)
			(xy 386.265407 -33.540833) (xy 386.273316 -33.442866) (xy 386.289082 -33.345853) (xy 386.312603 -33.250424)
			(xy 386.343727 -33.157196) (xy 386.382252 -33.066775) (xy 386.427927 -32.979748) (xy 386.480458 -32.896677)
			(xy 386.539502 -32.818104) (xy 386.604677 -32.744536) (xy 386.675561 -32.676451) (xy 386.751694 -32.61429)
			(xy 386.832581 -32.558458) (xy 386.917699 -32.509315) (xy 387.006496 -32.467181) (xy 387.098394 -32.432328)
			(xy 387.1928 -32.404983) (xy 387.289099 -32.385324) (xy 387.386668 -32.373477) (xy 387.484874 -32.369519)
			(xy 387.58308 -32.373477) (xy 387.680649 -32.385324) (xy 387.776948 -32.404983) (xy 387.871354 -32.432328)
			(xy 387.963252 -32.467181) (xy 388.052049 -32.509315) (xy 388.137167 -32.558458) (xy 388.218054 -32.61429)
			(xy 388.294187 -32.676451) (xy 388.365071 -32.744536) (xy 388.430246 -32.818104) (xy 388.48929 -32.896677)
			(xy 388.541821 -32.979748) (xy 388.587496 -33.066775) (xy 388.589211 -33.0708) (xy 393.446 -33.0708)
			(xy 393.446 -32.7406) (xy 393.6746 -32.512) (xy 395.3002 -32.512) (xy 395.5542 -32.766) (xy 395.5542 -33.0708)
			(xy 395.3002 -33.3248) (xy 393.7 -33.3248) (xy 393.446 -33.0708) (xy 388.589211 -33.0708) (xy 388.626021 -33.157196)
			(xy 388.657145 -33.250424) (xy 388.680666 -33.345853) (xy 388.696432 -33.442866) (xy 388.704341 -33.540833)
			(xy 388.704836 -33.589976) (xy 388.704341 -33.639119) (xy 388.704338 -33.63915) (xy 398.264621 -33.63915)
			(xy 398.264621 -33.540802) (xy 398.272535 -33.442774) (xy 398.288311 -33.345701) (xy 398.311847 -33.250211)
			(xy 398.34299 -33.156926) (xy 398.381539 -33.066448) (xy 398.427243 -32.979366) (xy 398.479806 -32.896244)
			(xy 398.538887 -32.817621) (xy 398.604104 -32.744008) (xy 398.675032 -32.67588) (xy 398.751212 -32.613681)
			(xy 398.83215 -32.557813) (xy 398.917321 -32.50864) (xy 399.006173 -32.466479) (xy 399.098129 -32.431605)
			(xy 399.192593 -32.404243) (xy 399.288953 -32.384571) (xy 399.386583 -32.372717) (xy 399.48485 -32.368757)
			(xy 399.583117 -32.372717) (xy 399.680747 -32.384571) (xy 399.777107 -32.404243) (xy 399.871571 -32.431605)
			(xy 399.963527 -32.466479) (xy 400.052379 -32.50864) (xy 400.13755 -32.557813) (xy 400.218488 -32.613681)
			(xy 400.294668 -32.67588) (xy 400.365596 -32.744008) (xy 400.430813 -32.817621) (xy 400.489894 -32.896244)
			(xy 400.542457 -32.979366) (xy 400.588161 -33.066448) (xy 400.62671 -33.156926) (xy 400.657853 -33.250211)
			(xy 400.681389 -33.345701) (xy 400.697165 -33.442774) (xy 400.705079 -33.540802) (xy 400.705574 -33.589976)
			(xy 400.705079 -33.639119) (xy 405.275529 -33.639119) (xy 405.275529 -33.540833) (xy 405.283438 -33.442866)
			(xy 405.299204 -33.345853) (xy 405.322725 -33.250424) (xy 405.353849 -33.157196) (xy 405.392374 -33.066775)
			(xy 405.438049 -32.979748) (xy 405.49058 -32.896677) (xy 405.549624 -32.818104) (xy 405.614799 -32.744536)
			(xy 405.685683 -32.676451) (xy 405.761816 -32.61429) (xy 405.842703 -32.558458) (xy 405.927821 -32.509315)
			(xy 406.016618 -32.467181) (xy 406.108516 -32.432328) (xy 406.202922 -32.404983) (xy 406.299221 -32.385324)
			(xy 406.39679 -32.373477) (xy 406.494996 -32.369519) (xy 406.593202 -32.373477) (xy 406.690771 -32.385324)
			(xy 406.78707 -32.404983) (xy 406.881476 -32.432328) (xy 406.973374 -32.467181) (xy 407.062171 -32.509315)
			(xy 407.147289 -32.558458) (xy 407.228176 -32.61429) (xy 407.304309 -32.676451) (xy 407.375193 -32.744536)
			(xy 407.440368 -32.818104) (xy 407.499412 -32.896677) (xy 407.551943 -32.979748) (xy 407.597618 -33.066775)
			(xy 407.636143 -33.157196) (xy 407.667267 -33.250424) (xy 407.690788 -33.345853) (xy 407.706554 -33.442866)
			(xy 407.714463 -33.540833) (xy 407.714958 -33.589976) (xy 407.714463 -33.639119) (xy 407.71446 -33.63915)
			(xy 417.274743 -33.63915) (xy 417.274743 -33.540802) (xy 417.282657 -33.442774) (xy 417.298433 -33.345701)
			(xy 417.321969 -33.250211) (xy 417.353112 -33.156926) (xy 417.391661 -33.066448) (xy 417.437365 -32.979366)
			(xy 417.489928 -32.896244) (xy 417.549009 -32.817621) (xy 417.614226 -32.744008) (xy 417.685154 -32.67588)
			(xy 417.761334 -32.613681) (xy 417.842272 -32.557813) (xy 417.927443 -32.50864) (xy 418.016295 -32.466479)
			(xy 418.108251 -32.431605) (xy 418.202715 -32.404243) (xy 418.299075 -32.384571) (xy 418.396705 -32.372717)
			(xy 418.494972 -32.368757) (xy 418.593239 -32.372717) (xy 418.690869 -32.384571) (xy 418.787229 -32.404243)
			(xy 418.881693 -32.431605) (xy 418.973649 -32.466479) (xy 419.062501 -32.50864) (xy 419.147672 -32.557813)
			(xy 419.22861 -32.613681) (xy 419.30479 -32.67588) (xy 419.375718 -32.744008) (xy 419.440935 -32.817621)
			(xy 419.500016 -32.896244) (xy 419.552579 -32.979366) (xy 419.598283 -33.066448) (xy 419.636832 -33.156926)
			(xy 419.667975 -33.250211) (xy 419.691511 -33.345701) (xy 419.707287 -33.442774) (xy 419.715201 -33.540802)
			(xy 419.715696 -33.589976) (xy 419.715201 -33.63915) (xy 419.707287 -33.737178) (xy 419.691511 -33.834251)
			(xy 419.667975 -33.929741) (xy 419.636832 -34.023026) (xy 419.598283 -34.113504) (xy 419.552579 -34.200586)
			(xy 419.500016 -34.283708) (xy 419.440935 -34.362331) (xy 419.375718 -34.435944) (xy 419.30479 -34.504072)
			(xy 419.22861 -34.566271) (xy 419.147672 -34.622139) (xy 419.062501 -34.671312) (xy 418.973649 -34.713473)
			(xy 418.881693 -34.748347) (xy 418.787229 -34.775709) (xy 418.690869 -34.795381) (xy 418.593239 -34.807235)
			(xy 418.494972 -34.811196) (xy 418.396705 -34.807235) (xy 418.299075 -34.795381) (xy 418.202715 -34.775709)
			(xy 418.108251 -34.748347) (xy 418.016295 -34.713473) (xy 417.927443 -34.671312) (xy 417.842272 -34.622139)
			(xy 417.761334 -34.566271) (xy 417.685154 -34.504072) (xy 417.614226 -34.435944) (xy 417.549009 -34.362331)
			(xy 417.489928 -34.283708) (xy 417.437365 -34.200586) (xy 417.391661 -34.113504) (xy 417.353112 -34.023026)
			(xy 417.321969 -33.929741) (xy 417.298433 -33.834251) (xy 417.282657 -33.737178) (xy 417.274743 -33.63915)
			(xy 407.71446 -33.63915) (xy 407.706554 -33.737086) (xy 407.690788 -33.834099) (xy 407.667267 -33.929528)
			(xy 407.636143 -34.022756) (xy 407.597618 -34.113177) (xy 407.551943 -34.200205) (xy 407.499412 -34.283275)
			(xy 407.440368 -34.361848) (xy 407.375193 -34.435416) (xy 407.304309 -34.503501) (xy 407.228176 -34.565662)
			(xy 407.147289 -34.621494) (xy 407.062171 -34.670637) (xy 406.973374 -34.712771) (xy 406.881476 -34.747624)
			(xy 406.78707 -34.774969) (xy 406.690771 -34.794628) (xy 406.593202 -34.806475) (xy 406.494996 -34.810433)
			(xy 406.39679 -34.806475) (xy 406.299221 -34.794628) (xy 406.202922 -34.774969) (xy 406.108516 -34.747624)
			(xy 406.016618 -34.712771) (xy 405.927821 -34.670637) (xy 405.842703 -34.621494) (xy 405.761816 -34.565662)
			(xy 405.685683 -34.503501) (xy 405.614799 -34.435416) (xy 405.549624 -34.361848) (xy 405.49058 -34.283275)
			(xy 405.438049 -34.200205) (xy 405.392374 -34.113177) (xy 405.353849 -34.022756) (xy 405.322725 -33.929528)
			(xy 405.299204 -33.834099) (xy 405.283438 -33.737086) (xy 405.275529 -33.639119) (xy 400.705079 -33.639119)
			(xy 400.705079 -33.63915) (xy 400.697165 -33.737178) (xy 400.681389 -33.834251) (xy 400.657853 -33.929741)
			(xy 400.62671 -34.023026) (xy 400.588161 -34.113504) (xy 400.542457 -34.200586) (xy 400.489894 -34.283708)
			(xy 400.430813 -34.362331) (xy 400.365596 -34.435944) (xy 400.294668 -34.504072) (xy 400.218488 -34.566271)
			(xy 400.13755 -34.622139) (xy 400.052379 -34.671312) (xy 399.963527 -34.713473) (xy 399.871571 -34.748347)
			(xy 399.777107 -34.775709) (xy 399.680747 -34.795381) (xy 399.583117 -34.807235) (xy 399.48485 -34.811196)
			(xy 399.386583 -34.807235) (xy 399.288953 -34.795381) (xy 399.192593 -34.775709) (xy 399.098129 -34.748347)
			(xy 399.006173 -34.713473) (xy 398.917321 -34.671312) (xy 398.83215 -34.622139) (xy 398.751212 -34.566271)
			(xy 398.675032 -34.504072) (xy 398.604104 -34.435944) (xy 398.538887 -34.362331) (xy 398.479806 -34.283708)
			(xy 398.427243 -34.200586) (xy 398.381539 -34.113504) (xy 398.34299 -34.023026) (xy 398.311847 -33.929741)
			(xy 398.288311 -33.834251) (xy 398.272535 -33.737178) (xy 398.264621 -33.63915) (xy 388.704338 -33.63915)
			(xy 388.696432 -33.737086) (xy 388.680666 -33.834099) (xy 388.657145 -33.929528) (xy 388.626021 -34.022756)
			(xy 388.587496 -34.113177) (xy 388.541821 -34.200205) (xy 388.48929 -34.283275) (xy 388.430246 -34.361848)
			(xy 388.365071 -34.435416) (xy 388.294187 -34.503501) (xy 388.218054 -34.565662) (xy 388.137167 -34.621494)
			(xy 388.052049 -34.670637) (xy 387.963252 -34.712771) (xy 387.871354 -34.747624) (xy 387.776948 -34.774969)
			(xy 387.680649 -34.794628) (xy 387.58308 -34.806475) (xy 387.484874 -34.810433) (xy 387.386668 -34.806475)
			(xy 387.289099 -34.794628) (xy 387.1928 -34.774969) (xy 387.098394 -34.747624) (xy 387.006496 -34.712771)
			(xy 386.917699 -34.670637) (xy 386.832581 -34.621494) (xy 386.751694 -34.565662) (xy 386.675561 -34.503501)
			(xy 386.604677 -34.435416) (xy 386.539502 -34.361848) (xy 386.480458 -34.283275) (xy 386.427927 -34.200205)
			(xy 386.382252 -34.113177) (xy 386.343727 -34.022756) (xy 386.312603 -33.929528) (xy 386.289082 -33.834099)
			(xy 386.273316 -33.737086) (xy 386.265407 -33.639119) (xy 353.06 -33.639119) (xy 353.06 -34.199068)
			(xy 353.121976 -34.30778) (xy 353.149408 -34.324798) (xy 353.19838 -34.355696) (xy 353.29234 -34.423389)
			(xy 353.381327 -34.497499) (xy 353.464904 -34.577659) (xy 353.54266 -34.663478) (xy 353.614214 -34.754533)
			(xy 353.679213 -34.850376) (xy 353.737339 -34.950537) (xy 353.788305 -35.054524) (xy 353.831862 -35.161826)
			(xy 353.867795 -35.271915) (xy 353.895929 -35.384251) (xy 353.916123 -35.498282) (xy 353.928281 -35.613447)
			(xy 353.932341 -35.729181) (xy 353.928283 -35.844915) (xy 353.916129 -35.960081) (xy 353.895937 -36.074112)
			(xy 353.867806 -36.186449) (xy 353.831875 -36.296539) (xy 353.788321 -36.403841) (xy 353.737357 -36.507829)
			(xy 353.679233 -36.607992) (xy 353.614236 -36.703837) (xy 353.542685 -36.794893) (xy 353.46493 -36.880713)
			(xy 353.381355 -36.960876) (xy 353.29237 -37.034987) (xy 353.198412 -37.102683) (xy 353.149408 -37.13353)
			(xy 353.121976 -37.150548) (xy 353.06 -37.25926) (xy 353.06 -37.338) (xy 377.468382 -37.338) (xy 377.472453 -37.282378)
			(xy 377.484579 -37.227941) (xy 377.504502 -37.17585) (xy 377.531798 -37.127215) (xy 377.565884 -37.083072)
			(xy 377.606033 -37.044363) (xy 377.651391 -37.011912) (xy 377.700991 -36.986411) (xy 377.753775 -36.968404)
			(xy 377.808618 -36.958274) (xy 377.864352 -36.956237) (xy 377.919789 -36.962337) (xy 377.973746 -36.976443)
			(xy 378.025075 -36.998255) (xy 378.072681 -37.027309) (xy 378.115549 -37.062984) (xy 378.152766 -37.104521)
			(xy 378.183539 -37.151034) (xy 378.207211 -37.201531) (xy 378.223279 -37.254938) (xy 378.231399 -37.310114)
			(xy 378.231908 -37.338) (xy 378.231399 -37.365886) (xy 378.223279 -37.421062) (xy 378.207211 -37.474469)
			(xy 378.183539 -37.524966) (xy 378.172799 -37.5412) (xy 379.551182 -37.5412) (xy 379.555253 -37.485578)
			(xy 379.567379 -37.431141) (xy 379.587302 -37.37905) (xy 379.614598 -37.330415) (xy 379.648684 -37.286272)
			(xy 379.688833 -37.247563) (xy 379.734191 -37.215112) (xy 379.783791 -37.189611) (xy 379.836575 -37.171604)
			(xy 379.891418 -37.161474) (xy 379.947152 -37.159437) (xy 380.002589 -37.165537) (xy 380.056546 -37.179643)
			(xy 380.107875 -37.201455) (xy 380.155481 -37.230509) (xy 380.198349 -37.266184) (xy 380.235566 -37.307721)
			(xy 380.266339 -37.354234) (xy 380.290011 -37.404731) (xy 380.306079 -37.458138) (xy 380.314199 -37.513314)
			(xy 380.314708 -37.5412) (xy 380.314199 -37.569086) (xy 380.306079 -37.624262) (xy 380.290011 -37.677669)
			(xy 380.266339 -37.728166) (xy 380.235566 -37.774679) (xy 380.198349 -37.816216) (xy 380.155481 -37.851891)
			(xy 380.107875 -37.880945) (xy 380.056546 -37.902757) (xy 380.002589 -37.916863) (xy 379.947152 -37.922963)
			(xy 379.891418 -37.920926) (xy 379.836575 -37.910796) (xy 379.783791 -37.892789) (xy 379.734191 -37.867288)
			(xy 379.688833 -37.834837) (xy 379.648684 -37.796128) (xy 379.614598 -37.751985) (xy 379.587302 -37.70335)
			(xy 379.567379 -37.651259) (xy 379.555253 -37.596822) (xy 379.551182 -37.5412) (xy 378.172799 -37.5412)
			(xy 378.152766 -37.571479) (xy 378.115549 -37.613016) (xy 378.072681 -37.648691) (xy 378.025075 -37.677745)
			(xy 377.973746 -37.699557) (xy 377.919789 -37.713663) (xy 377.864352 -37.719763) (xy 377.808618 -37.717726)
			(xy 377.753775 -37.707596) (xy 377.700991 -37.689589) (xy 377.651391 -37.664088) (xy 377.606033 -37.631637)
			(xy 377.565884 -37.592928) (xy 377.531798 -37.548785) (xy 377.504502 -37.50015) (xy 377.484579 -37.448059)
			(xy 377.472453 -37.393622) (xy 377.468382 -37.338) (xy 353.06 -37.338) (xy 353.06 -38.5572) (xy 349.9612 -41.656)
			(xy 340.106 -41.656) (xy 338.472018 -40.022018) (xy 338.456471 -40.007125) (xy 338.421326 -39.982264)
			(xy 338.382495 -39.963681) (xy 338.341088 -39.951905) (xy 338.298288 -39.947274) (xy 338.255321 -39.949921)
			(xy 338.213413 -39.959769) (xy 338.173764 -39.976537) (xy 338.137507 -39.999745) (xy 338.105678 -40.028731)
			(xy 338.092034 -40.045386) (xy 338.056529 -40.090078) (xy 337.980235 -40.174991) (xy 337.898258 -40.254433)
			(xy 337.810991 -40.328023) (xy 337.71885 -40.395411) (xy 337.622276 -40.456275) (xy 337.521728 -40.510324)
			(xy 337.417688 -40.5573) (xy 337.310653 -40.596979) (xy 337.201132 -40.629172) (xy 337.08965 -40.653723)
			(xy 336.976738 -40.670518) (xy 336.862937 -40.679474) (xy 336.748788 -40.68055) (xy 336.634838 -40.673741)
			(xy 336.52163 -40.659078) (xy 336.409704 -40.636632) (xy 336.299596 -40.60651) (xy 336.191832 -40.568856)
			(xy 336.086925 -40.523849) (xy 335.985376 -40.471705) (xy 335.887671 -40.412673) (xy 335.794277 -40.347034)
			(xy 335.705638 -40.275102) (xy 335.622178 -40.19722) (xy 335.544297 -40.11376) (xy 335.472365 -40.025121)
			(xy 335.406726 -39.931726) (xy 335.347693 -39.834021) (xy 335.29555 -39.732473) (xy 335.250543 -39.627566)
			(xy 335.212889 -39.519801) (xy 335.182767 -39.409693) (xy 335.160322 -39.297768) (xy 335.145659 -39.18456)
			(xy 335.138849 -39.070609) (xy 335.139926 -38.956461) (xy 335.148882 -38.842659) (xy 335.165677 -38.729747)
			(xy 335.190229 -38.618265) (xy 335.222422 -38.508745) (xy 335.262101 -38.401709) (xy 335.309077 -38.297669)
			(xy 335.363126 -38.197122) (xy 335.42399 -38.100547) (xy 335.491379 -38.008407) (xy 335.564969 -37.92114)
			(xy 335.644411 -37.839163) (xy 335.729324 -37.762869) (xy 335.77403 -37.727382) (xy 335.790737 -37.713791)
			(xy 335.819758 -37.681972) (xy 335.842994 -37.645714) (xy 335.85978 -37.606055) (xy 335.869635 -37.564132)
			(xy 335.872276 -37.521148) (xy 335.867627 -37.478335) (xy 335.855821 -37.436919) (xy 335.837198 -37.398089)
			(xy 335.812291 -37.362958) (xy 335.797398 -37.347398) (xy 333.960978 -35.510978) (xy 333.944224 -35.494955)
			(xy 333.90604 -35.468674) (xy 333.863721 -35.449758) (xy 333.818672 -35.438835) (xy 333.772389 -35.436268)
			(xy 333.726408 -35.442142) (xy 333.682257 -35.456261) (xy 333.6414 -35.478158) (xy 333.605196 -35.507105)
			(xy 333.574844 -35.542141) (xy 333.551354 -35.582103) (xy 333.542894 -35.603688) (xy 333.528074 -35.643001)
			(xy 333.492122 -35.718944) (xy 333.449265 -35.791216) (xy 333.399876 -35.85919) (xy 333.34438 -35.922278)
			(xy 333.28326 -35.979933) (xy 333.217045 -36.031657) (xy 333.146307 -36.077001) (xy 333.071661 -36.115572)
			(xy 332.993752 -36.147036) (xy 332.913255 -36.17112) (xy 332.830867 -36.187617) (xy 332.747303 -36.196383)
			(xy 332.663286 -36.197342) (xy 332.579543 -36.190486) (xy 332.496801 -36.175875) (xy 332.415775 -36.153634)
			(xy 332.337168 -36.123956) (xy 332.26166 -36.0871) (xy 332.189906 -36.043383) (xy 332.122527 -35.993184)
			(xy 332.060106 -35.936939) (xy 332.003185 -35.875134) (xy 331.952257 -35.808305) (xy 331.907762 -35.737031)
			(xy 331.870086 -35.661929) (xy 331.839555 -35.583649) (xy 331.816434 -35.50287) (xy 331.800923 -35.420291)
			(xy 331.793156 -35.336628) (xy 331.793201 -35.252605) (xy 331.801057 -35.168951) (xy 331.816657 -35.086389)
			(xy 331.827886 -35.045904) (xy 331.833885 -35.023157) (xy 331.838327 -34.976328) (xy 331.83408 -34.929481)
			(xy 331.821287 -34.884214) (xy 331.800386 -34.842074) (xy 331.77209 -34.804497) (xy 331.737364 -34.772766)
			(xy 331.697395 -34.747965) (xy 331.653545 -34.730939) (xy 331.607311 -34.722269) (xy 331.583792 -34.7218)
			(xy 310.2356 -34.7218) (xy 308.4195 -32.9057) (xy 308.4195 -26.6573) (xy 308.66969 -26.40711) (xy 308.678072 -26.315416)
			(xy 308.65191 -26.27757) (xy 308.636347 -26.254209) (xy 308.611508 -26.203871) (xy 308.594312 -26.150437)
			(xy 308.585129 -26.095061) (xy 308.584157 -26.038936) (xy 308.591418 -25.983275) (xy 308.606753 -25.929278)
			(xy 308.629834 -25.87811) (xy 308.660161 -25.830875) (xy 308.697081 -25.788593) (xy 308.739796 -25.752175)
			(xy 308.787385 -25.722407) (xy 308.838822 -25.699932) (xy 308.865778 -25.6921) (xy 308.887187 -25.685822)
			(xy 308.927551 -25.666826) (xy 308.963979 -25.641075) (xy 308.995351 -25.60936) (xy 309.020705 -25.572655)
			(xy 309.039261 -25.532087) (xy 309.05045 -25.488902) (xy 309.053927 -25.444427) (xy 309.049586 -25.400028)
			(xy 309.037561 -25.357069) (xy 309.028338 -25.336754) (xy 309.016714 -25.311415) (xy 309.000119 -25.258196)
			(xy 308.991447 -25.203128) (xy 308.990882 -25.147385) (xy 308.998438 -25.092153) (xy 309.013952 -25.038609)
			(xy 309.037094 -24.987893) (xy 309.067372 -24.941086) (xy 309.104141 -24.899184) (xy 309.146617 -24.863081)
			(xy 309.193895 -24.833544) (xy 309.244969 -24.811204) (xy 309.298751 -24.796535) (xy 309.354095 -24.789851)
			(xy 309.409823 -24.791294) (xy 309.464748 -24.800833) (xy 309.517698 -24.818264) (xy 309.567548 -24.843218)
			(xy 309.613235 -24.875161) (xy 309.653786 -24.913414) (xy 309.688337 -24.957162) (xy 309.716152 -25.005473)
			(xy 309.736639 -25.057319) (xy 309.749362 -25.111594) (xy 309.75405 -25.167143) (xy 309.750602 -25.222782)
			(xy 309.739092 -25.277328) (xy 309.719765 -25.329617) (xy 309.706772 -25.35428) (xy 309.696649 -25.373744)
			(xy 309.682514 -25.415274) (xy 309.675722 -25.458614) (xy 309.676474 -25.502477) (xy 309.684748 -25.545559)
			(xy 309.700298 -25.58658) (xy 309.722661 -25.624321) (xy 309.751175 -25.65766) (xy 309.78499 -25.685607)
			(xy 309.823103 -25.707331) (xy 309.86438 -25.722187) (xy 309.907595 -25.729733) (xy 309.92953 -25.7302)
			(xy 310.149748 -25.7302) (xy 310.172188 -25.729745) (xy 310.216376 -25.721906) (xy 310.258501 -25.706427)
			(xy 310.297253 -25.683791) (xy 310.331426 -25.654699) (xy 310.359957 -25.620058) (xy 310.381961 -25.580944)
			(xy 310.396753 -25.538573) (xy 310.403872 -25.494262) (xy 310.403098 -25.44939) (xy 310.394454 -25.405352)
			(xy 310.37821 -25.363516) (xy 310.366918 -25.34412) (xy 310.352882 -25.320056) (xy 310.331176 -25.268751)
			(xy 310.317165 -25.214835) (xy 310.311147 -25.159453) (xy 310.313251 -25.103785) (xy 310.32343 -25.049016)
			(xy 310.34147 -24.99631) (xy 310.366986 -24.94679) (xy 310.399434 -24.901508) (xy 310.438125 -24.861429)
			(xy 310.482236 -24.827405) (xy 310.530826 -24.800161) (xy 310.582864 -24.780276) (xy 310.637241 -24.768173)
			(xy 310.6928 -24.76411) (xy 310.748359 -24.768173) (xy 310.802736 -24.780276) (xy 310.854774 -24.800161)
			(xy 310.903364 -24.827405) (xy 310.947475 -24.861429) (xy 310.986166 -24.901508) (xy 311.018614 -24.94679)
			(xy 311.04413 -24.99631) (xy 311.06217 -25.049016) (xy 311.072349 -25.103785) (xy 311.074453 -25.159453)
			(xy 311.068435 -25.214835) (xy 311.054424 -25.268751) (xy 311.032718 -25.320056) (xy 311.018682 -25.34412)
			(xy 311.007421 -25.363532) (xy 310.991179 -25.405362) (xy 310.982537 -25.449394) (xy 310.981762 -25.49426)
			(xy 310.988881 -25.538564) (xy 311.00367 -25.580929) (xy 311.025671 -25.620038) (xy 311.054199 -25.654675)
			(xy 311.088367 -25.683762) (xy 311.127113 -25.706396) (xy 311.169233 -25.721873) (xy 311.213415 -25.72971)
			(xy 311.235852 -25.7302) (xy 312.945018 -25.7302) (xy 316.06998 -22.605238) (xy 316.06998 -7.974838)
			(xy 316.3189 -7.725918) (xy 316.3189 -3.1623) (xy 314.9346 -1.778) (xy 175.725836 -1.778) (xy 175.702834 -1.778511)
			(xy 175.657583 -1.786811) (xy 175.614562 -1.803112) (xy 175.575173 -1.826881) (xy 175.540699 -1.857345)
			(xy 175.512264 -1.893511) (xy 175.490794 -1.934199) (xy 175.476989 -1.978085) (xy 175.471299 -2.023737)
			(xy 175.47209 -2.046732) (xy 175.474824 -2.081959) (xy 175.472782 -2.152588) (xy 175.462238 -2.222455)
			(xy 175.443347 -2.290541) (xy 175.416384 -2.355852) (xy 175.381742 -2.417435) (xy 175.339928 -2.474392)
			(xy 175.29155 -2.525892) (xy 175.237316 -2.571182) (xy 175.20793 -2.5908) (xy 175.189761 -2.603871)
			(xy 175.1579 -2.6353) (xy 175.132036 -2.671824) (xy 175.112968 -2.712314) (xy 175.101286 -2.755517)
			(xy 175.097351 -2.800098) (xy 175.101285 -2.844679) (xy 175.112966 -2.887882) (xy 175.132033 -2.928372)
			(xy 175.157897 -2.964896) (xy 175.189757 -2.996326) (xy 175.20793 -3.009392) (xy 175.236416 -3.028437)
			(xy 175.28917 -3.072171) (xy 175.33645 -3.121772) (xy 175.377609 -3.176559) (xy 175.412083 -3.235781)
			(xy 175.439398 -3.298626) (xy 175.45918 -3.364234) (xy 175.471158 -3.431703) (xy 175.475169 -3.500111)
			(xy 175.471156 -3.568518) (xy 175.459175 -3.635988) (xy 175.43939 -3.701594) (xy 175.412073 -3.764439)
			(xy 175.377597 -3.823659) (xy 175.336436 -3.878445) (xy 175.289154 -3.928044) (xy 175.236398 -3.971776)
			(xy 175.20793 -3.990848) (xy 175.189589 -4.004066) (xy 175.157468 -4.035874) (xy 175.131478 -4.072859)
			(xy 175.112436 -4.113858) (xy 175.100944 -4.157577) (xy 175.097364 -4.20264) (xy 175.101807 -4.247625)
			(xy 175.114135 -4.291116) (xy 175.133958 -4.331743) (xy 175.160653 -4.368223) (xy 175.193377 -4.39941)
			(xy 175.211994 -4.412234) (xy 175.239152 -4.430696) (xy 175.289559 -4.472789) (xy 175.334935 -4.520263)
			(xy 175.374709 -4.57252) (xy 175.408379 -4.628903) (xy 175.435523 -4.688703) (xy 175.455799 -4.751166)
			(xy 175.468951 -4.815507) (xy 175.474815 -4.880916) (xy 175.473316 -4.946571) (xy 175.469296 -4.979162)
			(xy 175.466801 -5.000712) (xy 175.468321 -5.044065) (xy 175.477182 -5.086529) (xy 175.493124 -5.126873)
			(xy 175.515687 -5.163923) (xy 175.544213 -5.196603) (xy 175.577874 -5.223965) (xy 175.615693 -5.245213)
			(xy 175.656571 -5.259731) (xy 175.69932 -5.267095) (xy 175.72101 -5.267452) (xy 176.615344 -5.267452)
			(xy 177.22088 -4.66217) (xy 177.719736 -4.163314) (xy 177.729388 -4.140962) (xy 177.740773 -4.115898)
			(xy 177.769691 -4.069055) (xy 177.805042 -4.026856) (xy 177.846092 -3.990178) (xy 177.891988 -3.959781)
			(xy 177.941778 -3.936297) (xy 177.994425 -3.920214) (xy 178.048838 -3.911867) (xy 178.103886 -3.911428)
			(xy 178.158425 -3.918906) (xy 178.211323 -3.934147) (xy 178.26148 -3.956834) (xy 178.307855 -3.986495)
			(xy 178.349485 -4.022515) (xy 178.385505 -4.064145) (xy 178.415166 -4.11052) (xy 178.437853 -4.160677)
			(xy 178.453094 -4.213575) (xy 178.460572 -4.268114) (xy 178.460133 -4.323162) (xy 178.451786 -4.377575)
			(xy 178.435703 -4.430222) (xy 178.412219 -4.480012) (xy 178.381822 -4.525908) (xy 178.345144 -4.566958)
			(xy 178.302945 -4.602309) (xy 178.256102 -4.631227) (xy 178.231038 -4.642612) (xy 178.208686 -4.652264)
			(xy 177.61839 -5.242814) (xy 176.901856 -5.959348) (xy 175.724058 -5.959348) (xy 175.700415 -5.959858)
			(xy 175.653942 -5.968582) (xy 175.609887 -5.985758) (xy 175.569773 -6.010793) (xy 175.534986 -6.042821)
			(xy 175.50673 -6.080735) (xy 175.485981 -6.123224) (xy 175.473455 -6.16882) (xy 175.469587 -6.215947)
			(xy 175.471582 -6.23951) (xy 175.474953 -6.277733) (xy 175.472837 -6.354436) (xy 175.460693 -6.430202)
			(xy 175.43873 -6.503724) (xy 175.423576 -6.538976) (xy 175.4124 -6.563868) (xy 175.4124 -7.436104)
			(xy 175.423576 -7.460996) (xy 175.437479 -7.493323) (xy 175.458326 -7.560536) (xy 175.470955 -7.629765)
			(xy 175.475185 -7.700009) (xy 175.470953 -7.770253) (xy 175.458322 -7.839482) (xy 175.437473 -7.906694)
			(xy 175.423576 -7.939024) (xy 175.4124 -7.963916) (xy 175.4124 -8.3566) (xy 175.26508 -8.3566) (xy 175.248433 -8.357146)
			(xy 175.216276 -8.365767) (xy 175.187445 -8.382416) (xy 175.163905 -8.40596) (xy 175.147259 -8.434793)
			(xy 175.138643 -8.466952) (xy 175.138643 -8.500245) (xy 175.147258 -8.532404) (xy 175.155098 -8.5471)
			(xy 175.18126 -8.592312) (xy 175.206914 -8.608822) (xy 175.235646 -8.627971) (xy 175.288844 -8.671991)
			(xy 175.336489 -8.721969) (xy 175.377917 -8.777209) (xy 175.412553 -8.836943) (xy 175.439914 -8.90034)
			(xy 175.45962 -8.966518) (xy 175.471396 -9.034556) (xy 175.475079 -9.103507) (xy 175.470617 -9.172412)
			(xy 175.458073 -9.240312) (xy 175.437621 -9.306263) (xy 175.409545 -9.369347) (xy 175.374237 -9.428686)
			(xy 175.332187 -9.483455) (xy 175.283981 -9.532891) (xy 175.230289 -9.576307) (xy 175.201326 -9.595104)
			(xy 175.173386 -9.61263) (xy 175.14189 -9.66978) (xy 175.14189 -9.7028) (xy 175.142433 -9.719449)
			(xy 175.151051 -9.751612) (xy 175.167699 -9.780449) (xy 175.191243 -9.803995) (xy 175.220079 -9.820645)
			(xy 175.252241 -9.829266) (xy 175.26889 -9.8298) (xy 175.4378 -9.8298) (xy 175.4378 -10.29462) (xy 175.444404 -10.314432)
			(xy 175.454008 -10.344434) (xy 175.467473 -10.405975) (xy 175.474244 -10.468607) (xy 175.474243 -10.531604)
			(xy 175.467471 -10.594236) (xy 175.454005 -10.655777) (xy 175.444404 -10.68578) (xy 175.4378 -10.705592)
			(xy 175.4378 -10.775444) (xy 195.541561 -10.775444) (xy 195.541951 -10.608177) (xy 195.550312 -10.441119)
			(xy 195.566624 -10.274649) (xy 195.590851 -10.109145) (xy 195.622936 -9.944984) (xy 195.662808 -9.782538)
			(xy 195.710375 -9.622177) (xy 195.765531 -9.464265) (xy 195.828148 -9.30916) (xy 195.898085 -9.157216)
			(xy 195.975184 -9.008776) (xy 196.059268 -8.86418) (xy 196.150147 -8.723754) (xy 196.247615 -8.587819)
			(xy 196.35145 -8.456682) (xy 196.461415 -8.330643) (xy 196.577262 -8.209987) (xy 196.637656 -8.15213)
			(xy 196.661438 -8.128824) (xy 196.703154 -8.076926) (xy 196.737476 -8.019868) (xy 196.763776 -7.958696)
			(xy 196.781571 -7.894533) (xy 196.790534 -7.828553) (xy 196.791072 -7.79526) (xy 196.791072 -4.700016)
			(xy 196.791568 -4.633065) (xy 196.799501 -4.499398) (xy 196.815338 -4.366435) (xy 196.839024 -4.234645)
			(xy 196.870475 -4.104489) (xy 196.909583 -3.976425) (xy 196.956207 -3.850902) (xy 197.010187 -3.728362)
			(xy 197.07133 -3.609235) (xy 197.139424 -3.493939) (xy 197.214228 -3.38288) (xy 197.29548 -3.276447)
			(xy 197.382894 -3.175015) (xy 197.476164 -3.078939) (xy 197.574961 -2.988557) (xy 197.67894 -2.904187)
			(xy 197.787733 -2.826125) (xy 197.90096 -2.754645) (xy 198.018223 -2.689998) (xy 198.13911 -2.632411)
			(xy 198.263196 -2.582087) (xy 198.390045 -2.539202) (xy 198.519212 -2.503907) (xy 198.650243 -2.476326)
			(xy 198.782677 -2.456556) (xy 198.916051 -2.444666) (xy 199.049894 -2.440698) (xy 199.183737 -2.444666)
			(xy 199.317111 -2.456556) (xy 199.449545 -2.476326) (xy 199.580576 -2.503907) (xy 199.709743 -2.539202)
			(xy 199.836592 -2.582087) (xy 199.960678 -2.632411) (xy 200.081565 -2.689998) (xy 200.198828 -2.754645)
			(xy 200.312055 -2.826125) (xy 200.420848 -2.904187) (xy 200.524827 -2.988557) (xy 200.623624 -3.078939)
			(xy 200.716894 -3.175015) (xy 200.804308 -3.276447) (xy 200.88556 -3.38288) (xy 200.960364 -3.493939)
			(xy 201.028458 -3.609235) (xy 201.089601 -3.728362) (xy 201.143581 -3.850902) (xy 201.169938 -3.921861)
			(xy 269.544792 -3.921861) (xy 269.544792 -3.850539) (xy 269.552778 -3.779665) (xy 269.568648 -3.71013)
			(xy 269.592205 -3.64281) (xy 269.62315 -3.578551) (xy 269.661096 -3.51816) (xy 269.705565 -3.462398)
			(xy 269.755998 -3.411965) (xy 269.81176 -3.367496) (xy 269.872151 -3.32955) (xy 269.93641 -3.298605)
			(xy 270.00373 -3.275048) (xy 270.073265 -3.259178) (xy 270.144139 -3.251192) (xy 270.215461 -3.251192)
			(xy 270.286335 -3.259178) (xy 270.35587 -3.275048) (xy 270.42319 -3.298605) (xy 270.487449 -3.32955)
			(xy 270.54784 -3.367496) (xy 270.603602 -3.411965) (xy 270.654035 -3.462398) (xy 270.698504 -3.51816)
			(xy 270.73645 -3.578551) (xy 270.767395 -3.64281) (xy 270.790952 -3.71013) (xy 270.806822 -3.779665)
			(xy 270.814808 -3.850539) (xy 270.815308 -3.8862) (xy 270.814808 -3.921861) (xy 270.806822 -3.992735)
			(xy 270.790952 -4.06227) (xy 270.767395 -4.12959) (xy 270.73645 -4.193849) (xy 270.698504 -4.25424)
			(xy 270.654035 -4.310002) (xy 270.603602 -4.360435) (xy 270.54784 -4.404904) (xy 270.487449 -4.44285)
			(xy 270.42319 -4.473795) (xy 270.35587 -4.497352) (xy 270.286335 -4.513222) (xy 270.215461 -4.521208)
			(xy 270.144139 -4.521208) (xy 270.073265 -4.513222) (xy 270.00373 -4.497352) (xy 269.93641 -4.473795)
			(xy 269.872151 -4.44285) (xy 269.81176 -4.404904) (xy 269.755998 -4.360435) (xy 269.705565 -4.310002)
			(xy 269.661096 -4.25424) (xy 269.62315 -4.193849) (xy 269.592205 -4.12959) (xy 269.568648 -4.06227)
			(xy 269.552778 -3.992735) (xy 269.544792 -3.921861) (xy 201.169938 -3.921861) (xy 201.190205 -3.976425)
			(xy 201.229313 -4.104489) (xy 201.260764 -4.234645) (xy 201.28445 -4.366435) (xy 201.300287 -4.499398)
			(xy 201.306712 -4.607661) (xy 242.950992 -4.607661) (xy 242.950992 -4.536339) (xy 242.958978 -4.465465)
			(xy 242.974848 -4.39593) (xy 242.998405 -4.32861) (xy 243.02935 -4.264351) (xy 243.067296 -4.20396)
			(xy 243.111765 -4.148198) (xy 243.162198 -4.097765) (xy 243.21796 -4.053296) (xy 243.278351 -4.01535)
			(xy 243.34261 -3.984405) (xy 243.40993 -3.960848) (xy 243.479465 -3.944978) (xy 243.550339 -3.936992)
			(xy 243.621661 -3.936992) (xy 243.692535 -3.944978) (xy 243.76207 -3.960848) (xy 243.82939 -3.984405)
			(xy 243.893649 -4.01535) (xy 243.95404 -4.053296) (xy 244.009802 -4.097765) (xy 244.060235 -4.148198)
			(xy 244.104704 -4.20396) (xy 244.14265 -4.264351) (xy 244.173595 -4.32861) (xy 244.197152 -4.39593)
			(xy 244.213022 -4.465465) (xy 244.221008 -4.536339) (xy 244.221508 -4.572) (xy 244.221008 -4.607661)
			(xy 244.213022 -4.678535) (xy 244.197152 -4.74807) (xy 244.173595 -4.81539) (xy 244.14265 -4.879649)
			(xy 244.104704 -4.94004) (xy 244.060235 -4.995802) (xy 244.009802 -5.046235) (xy 243.95404 -5.090704)
			(xy 243.893649 -5.12865) (xy 243.82939 -5.159595) (xy 243.76207 -5.183152) (xy 243.692535 -5.199022)
			(xy 243.621661 -5.207008) (xy 243.550339 -5.207008) (xy 243.479465 -5.199022) (xy 243.40993 -5.183152)
			(xy 243.34261 -5.159595) (xy 243.278351 -5.12865) (xy 243.21796 -5.090704) (xy 243.162198 -5.046235)
			(xy 243.111765 -4.995802) (xy 243.067296 -4.94004) (xy 243.02935 -4.879649) (xy 242.998405 -4.81539)
			(xy 242.974848 -4.74807) (xy 242.958978 -4.678535) (xy 242.950992 -4.607661) (xy 201.306712 -4.607661)
			(xy 201.30822 -4.633065) (xy 201.308716 -4.700016) (xy 201.308716 -7.79526) (xy 201.309274 -7.828552)
			(xy 201.318236 -7.894531) (xy 201.336026 -7.958695) (xy 201.362321 -8.019868) (xy 201.396636 -8.076928)
			(xy 201.438345 -8.128831) (xy 201.462132 -8.15213) (xy 201.522526 -8.209987) (xy 201.638373 -8.330643)
			(xy 201.748338 -8.456682) (xy 201.852173 -8.587819) (xy 201.949641 -8.723754) (xy 202.04052 -8.86418)
			(xy 202.124604 -9.008776) (xy 202.201703 -9.157216) (xy 202.27164 -9.30916) (xy 202.334257 -9.464265)
			(xy 202.389413 -9.622177) (xy 202.43698 -9.782538) (xy 202.476852 -9.944984) (xy 202.508937 -10.109145)
			(xy 202.533164 -10.274649) (xy 202.549476 -10.441119) (xy 202.557837 -10.608177) (xy 202.558227 -10.775444)
			(xy 202.550647 -10.94254) (xy 202.535112 -11.109084) (xy 202.524183 -11.186261) (xy 206.044792 -11.186261)
			(xy 206.044792 -11.114939) (xy 206.052778 -11.044065) (xy 206.068648 -10.97453) (xy 206.092205 -10.90721)
			(xy 206.12315 -10.842951) (xy 206.161096 -10.78256) (xy 206.205565 -10.726798) (xy 206.255998 -10.676365)
			(xy 206.31176 -10.631896) (xy 206.372151 -10.59395) (xy 206.43641 -10.563005) (xy 206.50373 -10.539448)
			(xy 206.573265 -10.523578) (xy 206.644139 -10.515592) (xy 206.715461 -10.515592) (xy 206.786335 -10.523578)
			(xy 206.85587 -10.539448) (xy 206.92319 -10.563005) (xy 206.987449 -10.59395) (xy 207.04784 -10.631896)
			(xy 207.103602 -10.676365) (xy 207.154035 -10.726798) (xy 207.192829 -10.775444) (xy 276.301877 -10.775444)
			(xy 276.302267 -10.608177) (xy 276.310628 -10.441119) (xy 276.32694 -10.274649) (xy 276.351167 -10.109145)
			(xy 276.383252 -9.944984) (xy 276.423124 -9.782538) (xy 276.470691 -9.622177) (xy 276.525847 -9.464265)
			(xy 276.588464 -9.30916) (xy 276.658401 -9.157216) (xy 276.7355 -9.008776) (xy 276.819584 -8.86418)
			(xy 276.910463 -8.723754) (xy 277.007931 -8.587819) (xy 277.111766 -8.456682) (xy 277.221731 -8.330643)
			(xy 277.337578 -8.209987) (xy 277.397972 -8.15213) (xy 277.421756 -8.128827) (xy 277.463472 -8.076928)
			(xy 277.497794 -8.019869) (xy 277.524093 -7.958697) (xy 277.541887 -7.894533) (xy 277.55085 -7.828553)
			(xy 277.551388 -7.79526) (xy 277.551388 -4.700016) (xy 277.551884 -4.633065) (xy 277.559817 -4.499398)
			(xy 277.575654 -4.366435) (xy 277.59934 -4.234645) (xy 277.630791 -4.104489) (xy 277.669899 -3.976425)
			(xy 277.716523 -3.850902) (xy 277.770503 -3.728362) (xy 277.831646 -3.609235) (xy 277.89974 -3.493939)
			(xy 277.974544 -3.38288) (xy 278.055796 -3.276447) (xy 278.14321 -3.175015) (xy 278.23648 -3.078939)
			(xy 278.335277 -2.988557) (xy 278.439256 -2.904187) (xy 278.548049 -2.826125) (xy 278.661276 -2.754645)
			(xy 278.778539 -2.689998) (xy 278.899426 -2.632411) (xy 279.023512 -2.582087) (xy 279.150361 -2.539202)
			(xy 279.279528 -2.503907) (xy 279.410559 -2.476326) (xy 279.542993 -2.456556) (xy 279.676367 -2.444666)
			(xy 279.81021 -2.440698) (xy 279.944053 -2.444666) (xy 280.077427 -2.456556) (xy 280.209861 -2.476326)
			(xy 280.340892 -2.503907) (xy 280.470059 -2.539202) (xy 280.596908 -2.582087) (xy 280.720994 -2.632411)
			(xy 280.841881 -2.689998) (xy 280.959144 -2.754645) (xy 281.072371 -2.826125) (xy 281.181164 -2.904187)
			(xy 281.285143 -2.988557) (xy 281.297367 -2.99974) (xy 311.607711 -2.99974) (xy 311.611746 -2.924036)
			(xy 311.623805 -2.849191) (xy 311.643751 -2.77605) (xy 311.671358 -2.705445) (xy 311.706314 -2.638174)
			(xy 311.748222 -2.574999) (xy 311.796608 -2.516637) (xy 311.850924 -2.463749) (xy 311.910553 -2.416934)
			(xy 311.974821 -2.376722) (xy 312.042998 -2.34357) (xy 312.114314 -2.317852) (xy 312.187959 -2.29986)
			(xy 312.263099 -2.289798) (xy 312.338883 -2.287779) (xy 312.414453 -2.293828) (xy 312.488951 -2.307875)
			(xy 312.561534 -2.329761) (xy 312.63138 -2.359238) (xy 312.697697 -2.395973) (xy 312.759733 -2.439548)
			(xy 312.816786 -2.48947) (xy 312.86821 -2.545174) (xy 312.913421 -2.606029) (xy 312.951908 -2.671344)
			(xy 312.983234 -2.74038) (xy 313.007044 -2.812355) (xy 313.023069 -2.886453) (xy 313.031128 -2.961834)
			(xy 313.031632 -2.99974) (xy 313.607707 -2.99974) (xy 313.611742 -2.924036) (xy 313.623801 -2.849191)
			(xy 313.643747 -2.77605) (xy 313.671354 -2.705445) (xy 313.70631 -2.638174) (xy 313.748218 -2.574999)
			(xy 313.796604 -2.516637) (xy 313.85092 -2.463749) (xy 313.910549 -2.416934) (xy 313.974817 -2.376722)
			(xy 314.042994 -2.34357) (xy 314.11431 -2.317852) (xy 314.187955 -2.29986) (xy 314.263095 -2.289798)
			(xy 314.338879 -2.287779) (xy 314.414449 -2.293828) (xy 314.488947 -2.307875) (xy 314.56153 -2.329761)
			(xy 314.631376 -2.359238) (xy 314.697693 -2.395973) (xy 314.759729 -2.439548) (xy 314.816782 -2.48947)
			(xy 314.868206 -2.545174) (xy 314.913417 -2.606029) (xy 314.951904 -2.671344) (xy 314.98323 -2.74038)
			(xy 315.00704 -2.812355) (xy 315.023065 -2.886453) (xy 315.031124 -2.961834) (xy 315.031628 -2.99974)
			(xy 315.031124 -3.037646) (xy 315.023065 -3.113027) (xy 315.00704 -3.187125) (xy 314.98323 -3.2591)
			(xy 314.951904 -3.328136) (xy 314.913417 -3.393451) (xy 314.868206 -3.454306) (xy 314.816782 -3.51001)
			(xy 314.759729 -3.559932) (xy 314.697693 -3.603507) (xy 314.631376 -3.640242) (xy 314.56153 -3.669719)
			(xy 314.488947 -3.691605) (xy 314.414449 -3.705652) (xy 314.338879 -3.711701) (xy 314.263095 -3.709682)
			(xy 314.187955 -3.69962) (xy 314.11431 -3.681628) (xy 314.042994 -3.65591) (xy 313.974817 -3.622758)
			(xy 313.910549 -3.582546) (xy 313.85092 -3.535731) (xy 313.796604 -3.482843) (xy 313.748218 -3.424481)
			(xy 313.70631 -3.361306) (xy 313.671354 -3.294035) (xy 313.643747 -3.22343) (xy 313.623801 -3.150289)
			(xy 313.611742 -3.075444) (xy 313.607707 -2.99974) (xy 313.031632 -2.99974) (xy 313.031128 -3.037646)
			(xy 313.023069 -3.113027) (xy 313.007044 -3.187125) (xy 312.983234 -3.2591) (xy 312.951908 -3.328136)
			(xy 312.913421 -3.393451) (xy 312.86821 -3.454306) (xy 312.816786 -3.51001) (xy 312.759733 -3.559932)
			(xy 312.697697 -3.603507) (xy 312.63138 -3.640242) (xy 312.561534 -3.669719) (xy 312.488951 -3.691605)
			(xy 312.414453 -3.705652) (xy 312.338883 -3.711701) (xy 312.263099 -3.709682) (xy 312.187959 -3.69962)
			(xy 312.114314 -3.681628) (xy 312.042998 -3.65591) (xy 311.974821 -3.622758) (xy 311.910553 -3.582546)
			(xy 311.850924 -3.535731) (xy 311.796608 -3.482843) (xy 311.748222 -3.424481) (xy 311.706314 -3.361306)
			(xy 311.671358 -3.294035) (xy 311.643751 -3.22343) (xy 311.623805 -3.150289) (xy 311.611746 -3.075444)
			(xy 311.607711 -2.99974) (xy 281.297367 -2.99974) (xy 281.38394 -3.078939) (xy 281.47721 -3.175015)
			(xy 281.564624 -3.276447) (xy 281.645876 -3.38288) (xy 281.72068 -3.493939) (xy 281.788774 -3.609235)
			(xy 281.849917 -3.728362) (xy 281.903897 -3.850902) (xy 281.950521 -3.976425) (xy 281.989629 -4.104489)
			(xy 282.02108 -4.234645) (xy 282.044766 -4.366435) (xy 282.060603 -4.499398) (xy 282.068536 -4.633065)
			(xy 282.069032 -4.700016) (xy 282.069032 -4.999736) (xy 311.607711 -4.999736) (xy 311.611746 -4.924032)
			(xy 311.623805 -4.849187) (xy 311.643751 -4.776046) (xy 311.671358 -4.705441) (xy 311.706314 -4.63817)
			(xy 311.748222 -4.574995) (xy 311.796608 -4.516633) (xy 311.850924 -4.463745) (xy 311.910553 -4.41693)
			(xy 311.974821 -4.376718) (xy 312.042998 -4.343566) (xy 312.114314 -4.317848) (xy 312.187959 -4.299856)
			(xy 312.263099 -4.289794) (xy 312.338883 -4.287775) (xy 312.414453 -4.293824) (xy 312.488951 -4.307871)
			(xy 312.561534 -4.329757) (xy 312.63138 -4.359234) (xy 312.697697 -4.395969) (xy 312.759733 -4.439544)
			(xy 312.816786 -4.489466) (xy 312.86821 -4.54517) (xy 312.913421 -4.606025) (xy 312.951908 -4.67134)
			(xy 312.983234 -4.740376) (xy 313.007044 -4.812351) (xy 313.023069 -4.886449) (xy 313.031128 -4.96183)
			(xy 313.031632 -4.999736) (xy 313.607707 -4.999736) (xy 313.611742 -4.924032) (xy 313.623801 -4.849187)
			(xy 313.643747 -4.776046) (xy 313.671354 -4.705441) (xy 313.70631 -4.63817) (xy 313.748218 -4.574995)
			(xy 313.796604 -4.516633) (xy 313.85092 -4.463745) (xy 313.910549 -4.41693) (xy 313.974817 -4.376718)
			(xy 314.042994 -4.343566) (xy 314.11431 -4.317848) (xy 314.187955 -4.299856) (xy 314.263095 -4.289794)
			(xy 314.338879 -4.287775) (xy 314.414449 -4.293824) (xy 314.488947 -4.307871) (xy 314.56153 -4.329757)
			(xy 314.631376 -4.359234) (xy 314.697693 -4.395969) (xy 314.759729 -4.439544) (xy 314.816782 -4.489466)
			(xy 314.868206 -4.54517) (xy 314.913417 -4.606025) (xy 314.951904 -4.67134) (xy 314.98323 -4.740376)
			(xy 315.00704 -4.812351) (xy 315.023065 -4.886449) (xy 315.031124 -4.96183) (xy 315.031628 -4.999736)
			(xy 315.031124 -5.037642) (xy 315.023065 -5.113023) (xy 315.00704 -5.187121) (xy 314.98323 -5.259096)
			(xy 314.951904 -5.328132) (xy 314.913417 -5.393447) (xy 314.868206 -5.454302) (xy 314.816782 -5.510006)
			(xy 314.759729 -5.559928) (xy 314.697693 -5.603503) (xy 314.631376 -5.640238) (xy 314.56153 -5.669715)
			(xy 314.488947 -5.691601) (xy 314.414449 -5.705648) (xy 314.338879 -5.711697) (xy 314.263095 -5.709678)
			(xy 314.187955 -5.699616) (xy 314.11431 -5.681624) (xy 314.042994 -5.655906) (xy 313.974817 -5.622754)
			(xy 313.910549 -5.582542) (xy 313.85092 -5.535727) (xy 313.796604 -5.482839) (xy 313.748218 -5.424477)
			(xy 313.70631 -5.361302) (xy 313.671354 -5.294031) (xy 313.643747 -5.223426) (xy 313.623801 -5.150285)
			(xy 313.611742 -5.07544) (xy 313.607707 -4.999736) (xy 313.031632 -4.999736) (xy 313.031128 -5.037642)
			(xy 313.023069 -5.113023) (xy 313.007044 -5.187121) (xy 312.983234 -5.259096) (xy 312.951908 -5.328132)
			(xy 312.913421 -5.393447) (xy 312.86821 -5.454302) (xy 312.816786 -5.510006) (xy 312.759733 -5.559928)
			(xy 312.697697 -5.603503) (xy 312.63138 -5.640238) (xy 312.561534 -5.669715) (xy 312.488951 -5.691601)
			(xy 312.414453 -5.705648) (xy 312.338883 -5.711697) (xy 312.263099 -5.709678) (xy 312.187959 -5.699616)
			(xy 312.114314 -5.681624) (xy 312.042998 -5.655906) (xy 311.974821 -5.622754) (xy 311.910553 -5.582542)
			(xy 311.850924 -5.535727) (xy 311.796608 -5.482839) (xy 311.748222 -5.424477) (xy 311.706314 -5.361302)
			(xy 311.671358 -5.294031) (xy 311.643751 -5.223426) (xy 311.623805 -5.150285) (xy 311.611746 -5.07544)
			(xy 311.607711 -4.999736) (xy 282.069032 -4.999736) (xy 282.069032 -6.999732) (xy 311.607711 -6.999732)
			(xy 311.611746 -6.924028) (xy 311.623805 -6.849183) (xy 311.643751 -6.776042) (xy 311.671358 -6.705437)
			(xy 311.706314 -6.638166) (xy 311.748222 -6.574991) (xy 311.796608 -6.516629) (xy 311.850924 -6.463741)
			(xy 311.910553 -6.416926) (xy 311.974821 -6.376714) (xy 312.042998 -6.343562) (xy 312.114314 -6.317844)
			(xy 312.187959 -6.299852) (xy 312.263099 -6.28979) (xy 312.338883 -6.287771) (xy 312.414453 -6.29382)
			(xy 312.488951 -6.307867) (xy 312.561534 -6.329753) (xy 312.63138 -6.35923) (xy 312.697697 -6.395965)
			(xy 312.759733 -6.43954) (xy 312.816786 -6.489462) (xy 312.86821 -6.545166) (xy 312.913421 -6.606021)
			(xy 312.951908 -6.671336) (xy 312.983234 -6.740372) (xy 313.007044 -6.812347) (xy 313.023069 -6.886445)
			(xy 313.031128 -6.961826) (xy 313.031632 -6.999732) (xy 313.607707 -6.999732) (xy 313.611742 -6.924028)
			(xy 313.623801 -6.849183) (xy 313.643747 -6.776042) (xy 313.671354 -6.705437) (xy 313.70631 -6.638166)
			(xy 313.748218 -6.574991) (xy 313.796604 -6.516629) (xy 313.85092 -6.463741) (xy 313.910549 -6.416926)
			(xy 313.974817 -6.376714) (xy 314.042994 -6.343562) (xy 314.11431 -6.317844) (xy 314.187955 -6.299852)
			(xy 314.263095 -6.28979) (xy 314.338879 -6.287771) (xy 314.414449 -6.29382) (xy 314.488947 -6.307867)
			(xy 314.56153 -6.329753) (xy 314.631376 -6.35923) (xy 314.697693 -6.395965) (xy 314.759729 -6.43954)
			(xy 314.816782 -6.489462) (xy 314.868206 -6.545166) (xy 314.913417 -6.606021) (xy 314.951904 -6.671336)
			(xy 314.98323 -6.740372) (xy 315.00704 -6.812347) (xy 315.023065 -6.886445) (xy 315.031124 -6.961826)
			(xy 315.031628 -6.999732) (xy 315.031124 -7.037638) (xy 315.023065 -7.113019) (xy 315.00704 -7.187117)
			(xy 314.98323 -7.259092) (xy 314.951904 -7.328128) (xy 314.913417 -7.393443) (xy 314.868206 -7.454298)
			(xy 314.816782 -7.510002) (xy 314.759729 -7.559924) (xy 314.697693 -7.603499) (xy 314.631376 -7.640234)
			(xy 314.56153 -7.669711) (xy 314.488947 -7.691597) (xy 314.414449 -7.705644) (xy 314.338879 -7.711693)
			(xy 314.263095 -7.709674) (xy 314.187955 -7.699612) (xy 314.11431 -7.68162) (xy 314.042994 -7.655902)
			(xy 313.974817 -7.62275) (xy 313.910549 -7.582538) (xy 313.85092 -7.535723) (xy 313.796604 -7.482835)
			(xy 313.748218 -7.424473) (xy 313.70631 -7.361298) (xy 313.671354 -7.294027) (xy 313.643747 -7.223422)
			(xy 313.623801 -7.150281) (xy 313.611742 -7.075436) (xy 313.607707 -6.999732) (xy 313.031632 -6.999732)
			(xy 313.031128 -7.037638) (xy 313.023069 -7.113019) (xy 313.007044 -7.187117) (xy 312.983234 -7.259092)
			(xy 312.951908 -7.328128) (xy 312.913421 -7.393443) (xy 312.86821 -7.454298) (xy 312.816786 -7.510002)
			(xy 312.759733 -7.559924) (xy 312.697697 -7.603499) (xy 312.63138 -7.640234) (xy 312.561534 -7.669711)
			(xy 312.488951 -7.691597) (xy 312.414453 -7.705644) (xy 312.338883 -7.711693) (xy 312.263099 -7.709674)
			(xy 312.187959 -7.699612) (xy 312.114314 -7.68162) (xy 312.042998 -7.655902) (xy 311.974821 -7.62275)
			(xy 311.910553 -7.582538) (xy 311.850924 -7.535723) (xy 311.796608 -7.482835) (xy 311.748222 -7.424473)
			(xy 311.706314 -7.361298) (xy 311.671358 -7.294027) (xy 311.643751 -7.223422) (xy 311.623805 -7.150281)
			(xy 311.611746 -7.075436) (xy 311.607711 -6.999732) (xy 282.069032 -6.999732) (xy 282.069032 -7.79526)
			(xy 282.069585 -7.828553) (xy 282.078547 -7.894532) (xy 282.096338 -7.958696) (xy 282.122633 -8.019869)
			(xy 282.15695 -8.076929) (xy 282.19866 -8.128831) (xy 282.222448 -8.15213) (xy 282.282842 -8.209987)
			(xy 282.398689 -8.330643) (xy 282.508654 -8.456682) (xy 282.612489 -8.587819) (xy 282.709957 -8.723754)
			(xy 282.800836 -8.86418) (xy 282.88492 -9.008776) (xy 282.962019 -9.157216) (xy 283.031956 -9.30916)
			(xy 283.094573 -9.464265) (xy 283.125886 -9.553914) (xy 308.833762 -9.553914) (xy 308.833762 -9.445286)
			(xy 308.841691 -9.336948) (xy 308.857508 -9.229477) (xy 308.881127 -9.123448) (xy 308.912423 -9.019426)
			(xy 308.951228 -8.917965) (xy 308.997336 -8.819608) (xy 309.0505 -8.724879) (xy 309.110438 -8.634284)
			(xy 309.176828 -8.548305) (xy 309.249318 -8.467402) (xy 309.327519 -8.392006) (xy 309.411016 -8.32252)
			(xy 309.499362 -8.259313) (xy 309.592086 -8.202725) (xy 309.688694 -8.153055) (xy 309.788669 -8.11057)
			(xy 309.891479 -8.075497) (xy 309.996575 -8.048021) (xy 310.103396 -8.02829) (xy 310.211372 -8.016409)
			(xy 310.319928 -8.012442) (xy 310.428484 -8.016409) (xy 310.53646 -8.02829) (xy 310.643281 -8.048021)
			(xy 310.748377 -8.075497) (xy 310.851187 -8.11057) (xy 310.951162 -8.153055) (xy 311.04777 -8.202725)
			(xy 311.140494 -8.259313) (xy 311.22884 -8.32252) (xy 311.312337 -8.392006) (xy 311.390538 -8.467402)
			(xy 311.463028 -8.548305) (xy 311.529418 -8.634284) (xy 311.589356 -8.724879) (xy 311.64252 -8.819608)
			(xy 311.688628 -8.917965) (xy 311.727433 -9.019426) (xy 311.758729 -9.123448) (xy 311.782348 -9.229477)
			(xy 311.798165 -9.336948) (xy 311.806094 -9.445286) (xy 311.80659 -9.4996) (xy 311.806094 -9.553914)
			(xy 311.798165 -9.662252) (xy 311.782348 -9.769723) (xy 311.758729 -9.875752) (xy 311.727433 -9.979774)
			(xy 311.688628 -10.081235) (xy 311.64252 -10.179592) (xy 311.589356 -10.274321) (xy 311.529418 -10.364916)
			(xy 311.463028 -10.450895) (xy 311.390538 -10.531798) (xy 311.312337 -10.607194) (xy 311.22884 -10.67668)
			(xy 311.140494 -10.739887) (xy 311.04777 -10.796475) (xy 310.951162 -10.846145) (xy 310.851187 -10.88863)
			(xy 310.748377 -10.923703) (xy 310.643281 -10.951179) (xy 310.53646 -10.97091) (xy 310.428484 -10.982791)
			(xy 310.319928 -10.986758) (xy 310.211372 -10.982791) (xy 310.103396 -10.97091) (xy 309.996575 -10.951179)
			(xy 309.891479 -10.923703) (xy 309.788669 -10.88863) (xy 309.688694 -10.846145) (xy 309.592086 -10.796475)
			(xy 309.499362 -10.739887) (xy 309.411016 -10.67668) (xy 309.327519 -10.607194) (xy 309.249318 -10.531798)
			(xy 309.176828 -10.450895) (xy 309.110438 -10.364916) (xy 309.0505 -10.274321) (xy 308.997336 -10.179592)
			(xy 308.951228 -10.081235) (xy 308.912423 -9.979774) (xy 308.881127 -9.875752) (xy 308.857508 -9.769723)
			(xy 308.841691 -9.662252) (xy 308.833762 -9.553914) (xy 283.125886 -9.553914) (xy 283.149729 -9.622177)
			(xy 283.197296 -9.782538) (xy 283.237168 -9.944984) (xy 283.269253 -10.109145) (xy 283.29348 -10.274649)
			(xy 283.309792 -10.441119) (xy 283.318153 -10.608177) (xy 283.318543 -10.775444) (xy 283.310963 -10.94254)
			(xy 283.305629 -10.999724) (xy 311.607711 -10.999724) (xy 311.611746 -10.92402) (xy 311.623805 -10.849175)
			(xy 311.643751 -10.776034) (xy 311.671358 -10.705429) (xy 311.706314 -10.638158) (xy 311.748222 -10.574983)
			(xy 311.796608 -10.516621) (xy 311.850924 -10.463733) (xy 311.910553 -10.416918) (xy 311.974821 -10.376706)
			(xy 312.042998 -10.343554) (xy 312.114314 -10.317836) (xy 312.187959 -10.299844) (xy 312.263099 -10.289782)
			(xy 312.338883 -10.287763) (xy 312.414453 -10.293812) (xy 312.488951 -10.307859) (xy 312.561534 -10.329745)
			(xy 312.63138 -10.359222) (xy 312.697697 -10.395957) (xy 312.759733 -10.439532) (xy 312.816786 -10.489454)
			(xy 312.86821 -10.545158) (xy 312.913421 -10.606013) (xy 312.951908 -10.671328) (xy 312.983234 -10.740364)
			(xy 313.007044 -10.812339) (xy 313.023069 -10.886437) (xy 313.031128 -10.961818) (xy 313.031632 -10.999724)
			(xy 313.607707 -10.999724) (xy 313.611742 -10.92402) (xy 313.623801 -10.849175) (xy 313.643747 -10.776034)
			(xy 313.671354 -10.705429) (xy 313.70631 -10.638158) (xy 313.748218 -10.574983) (xy 313.796604 -10.516621)
			(xy 313.85092 -10.463733) (xy 313.910549 -10.416918) (xy 313.974817 -10.376706) (xy 314.042994 -10.343554)
			(xy 314.11431 -10.317836) (xy 314.187955 -10.299844) (xy 314.263095 -10.289782) (xy 314.338879 -10.287763)
			(xy 314.414449 -10.293812) (xy 314.488947 -10.307859) (xy 314.56153 -10.329745) (xy 314.631376 -10.359222)
			(xy 314.697693 -10.395957) (xy 314.759729 -10.439532) (xy 314.816782 -10.489454) (xy 314.868206 -10.545158)
			(xy 314.913417 -10.606013) (xy 314.951904 -10.671328) (xy 314.98323 -10.740364) (xy 315.00704 -10.812339)
			(xy 315.023065 -10.886437) (xy 315.031124 -10.961818) (xy 315.031628 -10.999724) (xy 315.031124 -11.03763)
			(xy 315.023065 -11.113011) (xy 315.00704 -11.187109) (xy 314.98323 -11.259084) (xy 314.951904 -11.32812)
			(xy 314.913417 -11.393435) (xy 314.868206 -11.45429) (xy 314.816782 -11.509994) (xy 314.759729 -11.559916)
			(xy 314.697693 -11.603491) (xy 314.631376 -11.640226) (xy 314.56153 -11.669703) (xy 314.488947 -11.691589)
			(xy 314.414449 -11.705636) (xy 314.338879 -11.711685) (xy 314.263095 -11.709666) (xy 314.187955 -11.699604)
			(xy 314.11431 -11.681612) (xy 314.042994 -11.655894) (xy 313.974817 -11.622742) (xy 313.910549 -11.58253)
			(xy 313.85092 -11.535715) (xy 313.796604 -11.482827) (xy 313.748218 -11.424465) (xy 313.70631 -11.36129)
			(xy 313.671354 -11.294019) (xy 313.643747 -11.223414) (xy 313.623801 -11.150273) (xy 313.611742 -11.075428)
			(xy 313.607707 -10.999724) (xy 313.031632 -10.999724) (xy 313.031128 -11.03763) (xy 313.023069 -11.113011)
			(xy 313.007044 -11.187109) (xy 312.983234 -11.259084) (xy 312.951908 -11.32812) (xy 312.913421 -11.393435)
			(xy 312.86821 -11.45429) (xy 312.816786 -11.509994) (xy 312.759733 -11.559916) (xy 312.697697 -11.603491)
			(xy 312.63138 -11.640226) (xy 312.561534 -11.669703) (xy 312.488951 -11.691589) (xy 312.414453 -11.705636)
			(xy 312.338883 -11.711685) (xy 312.263099 -11.709666) (xy 312.187959 -11.699604) (xy 312.114314 -11.681612)
			(xy 312.042998 -11.655894) (xy 311.974821 -11.622742) (xy 311.910553 -11.58253) (xy 311.850924 -11.535715)
			(xy 311.796608 -11.482827) (xy 311.748222 -11.424465) (xy 311.706314 -11.36129) (xy 311.671358 -11.294019)
			(xy 311.643751 -11.223414) (xy 311.623805 -11.150273) (xy 311.611746 -11.075428) (xy 311.607711 -10.999724)
			(xy 283.305629 -10.999724) (xy 283.295428 -11.109084) (xy 283.271975 -11.274699) (xy 283.240657 -11.439009)
			(xy 283.201544 -11.601639) (xy 283.154727 -11.76222) (xy 283.10031 -11.920389) (xy 283.038417 -12.075784)
			(xy 282.969191 -12.228054) (xy 282.892786 -12.376851) (xy 282.809378 -12.521839) (xy 282.719156 -12.662688)
			(xy 282.622324 -12.799077) (xy 282.519103 -12.930697) (xy 282.459449 -12.99972) (xy 311.607711 -12.99972)
			(xy 311.611746 -12.924016) (xy 311.623805 -12.849171) (xy 311.643751 -12.77603) (xy 311.671358 -12.705425)
			(xy 311.706314 -12.638154) (xy 311.748222 -12.574979) (xy 311.796608 -12.516617) (xy 311.850924 -12.463729)
			(xy 311.910553 -12.416914) (xy 311.974821 -12.376702) (xy 312.042998 -12.34355) (xy 312.114314 -12.317832)
			(xy 312.187959 -12.29984) (xy 312.263099 -12.289778) (xy 312.338883 -12.287759) (xy 312.414453 -12.293808)
			(xy 312.488951 -12.307855) (xy 312.561534 -12.329741) (xy 312.63138 -12.359218) (xy 312.697697 -12.395953)
			(xy 312.759733 -12.439528) (xy 312.816786 -12.48945) (xy 312.86821 -12.545154) (xy 312.913421 -12.606009)
			(xy 312.951908 -12.671324) (xy 312.983234 -12.74036) (xy 313.007044 -12.812335) (xy 313.023069 -12.886433)
			(xy 313.031128 -12.961814) (xy 313.031632 -12.99972) (xy 313.607707 -12.99972) (xy 313.611742 -12.924016)
			(xy 313.623801 -12.849171) (xy 313.643747 -12.77603) (xy 313.671354 -12.705425) (xy 313.70631 -12.638154)
			(xy 313.748218 -12.574979) (xy 313.796604 -12.516617) (xy 313.85092 -12.463729) (xy 313.910549 -12.416914)
			(xy 313.974817 -12.376702) (xy 314.042994 -12.34355) (xy 314.11431 -12.317832) (xy 314.187955 -12.29984)
			(xy 314.263095 -12.289778) (xy 314.338879 -12.287759) (xy 314.414449 -12.293808) (xy 314.488947 -12.307855)
			(xy 314.56153 -12.329741) (xy 314.631376 -12.359218) (xy 314.697693 -12.395953) (xy 314.759729 -12.439528)
			(xy 314.816782 -12.48945) (xy 314.868206 -12.545154) (xy 314.913417 -12.606009) (xy 314.951904 -12.671324)
			(xy 314.98323 -12.74036) (xy 315.00704 -12.812335) (xy 315.023065 -12.886433) (xy 315.031124 -12.961814)
			(xy 315.031628 -12.99972) (xy 315.031124 -13.037626) (xy 315.023065 -13.113007) (xy 315.00704 -13.187105)
			(xy 314.98323 -13.25908) (xy 314.951904 -13.328116) (xy 314.913417 -13.393431) (xy 314.868206 -13.454286)
			(xy 314.816782 -13.50999) (xy 314.759729 -13.559912) (xy 314.697693 -13.603487) (xy 314.631376 -13.640222)
			(xy 314.56153 -13.669699) (xy 314.488947 -13.691585) (xy 314.414449 -13.705632) (xy 314.338879 -13.711681)
			(xy 314.263095 -13.709662) (xy 314.187955 -13.6996) (xy 314.11431 -13.681608) (xy 314.042994 -13.65589)
			(xy 313.974817 -13.622738) (xy 313.910549 -13.582526) (xy 313.85092 -13.535711) (xy 313.796604 -13.482823)
			(xy 313.748218 -13.424461) (xy 313.70631 -13.361286) (xy 313.671354 -13.294015) (xy 313.643747 -13.22341)
			(xy 313.623801 -13.150269) (xy 313.611742 -13.075424) (xy 313.607707 -12.99972) (xy 313.031632 -12.99972)
			(xy 313.031128 -13.037626) (xy 313.023069 -13.113007) (xy 313.007044 -13.187105) (xy 312.983234 -13.25908)
			(xy 312.951908 -13.328116) (xy 312.913421 -13.393431) (xy 312.86821 -13.454286) (xy 312.816786 -13.50999)
			(xy 312.759733 -13.559912) (xy 312.697697 -13.603487) (xy 312.63138 -13.640222) (xy 312.561534 -13.669699)
			(xy 312.488951 -13.691585) (xy 312.414453 -13.705632) (xy 312.338883 -13.711681) (xy 312.263099 -13.709662)
			(xy 312.187959 -13.6996) (xy 312.114314 -13.681608) (xy 312.042998 -13.65589) (xy 311.974821 -13.622738)
			(xy 311.910553 -13.582526) (xy 311.850924 -13.535711) (xy 311.796608 -13.482823) (xy 311.748222 -13.424461)
			(xy 311.706314 -13.361286) (xy 311.671358 -13.294015) (xy 311.643751 -13.22341) (xy 311.623805 -13.150269)
			(xy 311.611746 -13.075424) (xy 311.607711 -12.99972) (xy 282.459449 -12.99972) (xy 282.409728 -13.057249)
			(xy 282.294446 -13.178445) (xy 282.173519 -13.294009) (xy 282.047223 -13.40368) (xy 281.915845 -13.507208)
			(xy 281.779682 -13.604358) (xy 281.639045 -13.694909) (xy 281.494252 -13.778656) (xy 281.345633 -13.855407)
			(xy 281.193526 -13.92499) (xy 281.038275 -13.987245) (xy 280.880235 -14.042031) (xy 280.719763 -14.089223)
			(xy 280.557224 -14.128716) (xy 280.392989 -14.160418) (xy 280.227429 -14.184258) (xy 280.060921 -14.200181)
			(xy 279.893844 -14.208152) (xy 279.726576 -14.208152) (xy 279.559499 -14.200181) (xy 279.392991 -14.184258)
			(xy 279.227431 -14.160418) (xy 279.063196 -14.128716) (xy 278.900657 -14.089223) (xy 278.740185 -14.042031)
			(xy 278.582145 -13.987245) (xy 278.426894 -13.92499) (xy 278.274787 -13.855407) (xy 278.126168 -13.778656)
			(xy 277.981375 -13.694909) (xy 277.840738 -13.604358) (xy 277.704575 -13.507208) (xy 277.573197 -13.40368)
			(xy 277.446901 -13.294009) (xy 277.325974 -13.178445) (xy 277.210692 -13.057249) (xy 277.101317 -12.930697)
			(xy 276.998096 -12.799077) (xy 276.901264 -12.662688) (xy 276.811042 -12.521839) (xy 276.727634 -12.376851)
			(xy 276.651229 -12.228054) (xy 276.582003 -12.075784) (xy 276.52011 -11.920389) (xy 276.465693 -11.76222)
			(xy 276.418876 -11.601639) (xy 276.379763 -11.439009) (xy 276.348445 -11.274699) (xy 276.324992 -11.109084)
			(xy 276.309457 -10.94254) (xy 276.301877 -10.775444) (xy 207.192829 -10.775444) (xy 207.198504 -10.78256)
			(xy 207.23645 -10.842951) (xy 207.267395 -10.90721) (xy 207.290952 -10.97453) (xy 207.306822 -11.044065)
			(xy 207.314808 -11.114939) (xy 207.315308 -11.1506) (xy 207.314808 -11.186261) (xy 207.306822 -11.257135)
			(xy 207.290952 -11.32667) (xy 207.267395 -11.39399) (xy 207.23645 -11.458249) (xy 207.198504 -11.51864)
			(xy 207.154035 -11.574402) (xy 207.135776 -11.592661) (xy 264.286992 -11.592661) (xy 264.286992 -11.521339)
			(xy 264.294978 -11.450465) (xy 264.310848 -11.38093) (xy 264.334405 -11.31361) (xy 264.36535 -11.249351)
			(xy 264.403296 -11.18896) (xy 264.447765 -11.133198) (xy 264.498198 -11.082765) (xy 264.55396 -11.038296)
			(xy 264.614351 -11.00035) (xy 264.67861 -10.969405) (xy 264.74593 -10.945848) (xy 264.815465 -10.929978)
			(xy 264.886339 -10.921992) (xy 264.957661 -10.921992) (xy 265.028535 -10.929978) (xy 265.09807 -10.945848)
			(xy 265.16539 -10.969405) (xy 265.229649 -11.00035) (xy 265.29004 -11.038296) (xy 265.345802 -11.082765)
			(xy 265.396235 -11.133198) (xy 265.440704 -11.18896) (xy 265.47865 -11.249351) (xy 265.509595 -11.31361)
			(xy 265.533152 -11.38093) (xy 265.549022 -11.450465) (xy 265.557008 -11.521339) (xy 265.557508 -11.557)
			(xy 265.557008 -11.592661) (xy 271.906992 -11.592661) (xy 271.906992 -11.521339) (xy 271.914978 -11.450465)
			(xy 271.930848 -11.38093) (xy 271.954405 -11.31361) (xy 271.98535 -11.249351) (xy 272.023296 -11.18896)
			(xy 272.067765 -11.133198) (xy 272.118198 -11.082765) (xy 272.17396 -11.038296) (xy 272.234351 -11.00035)
			(xy 272.29861 -10.969405) (xy 272.36593 -10.945848) (xy 272.435465 -10.929978) (xy 272.506339 -10.921992)
			(xy 272.577661 -10.921992) (xy 272.648535 -10.929978) (xy 272.71807 -10.945848) (xy 272.78539 -10.969405)
			(xy 272.849649 -11.00035) (xy 272.91004 -11.038296) (xy 272.965802 -11.082765) (xy 273.016235 -11.133198)
			(xy 273.060704 -11.18896) (xy 273.09865 -11.249351) (xy 273.129595 -11.31361) (xy 273.153152 -11.38093)
			(xy 273.169022 -11.450465) (xy 273.177008 -11.521339) (xy 273.177508 -11.557) (xy 273.177008 -11.592661)
			(xy 273.169022 -11.663535) (xy 273.153152 -11.73307) (xy 273.129595 -11.80039) (xy 273.09865 -11.864649)
			(xy 273.060704 -11.92504) (xy 273.016235 -11.980802) (xy 272.965802 -12.031235) (xy 272.91004 -12.075704)
			(xy 272.849649 -12.11365) (xy 272.78539 -12.144595) (xy 272.71807 -12.168152) (xy 272.648535 -12.184022)
			(xy 272.577661 -12.192008) (xy 272.506339 -12.192008) (xy 272.435465 -12.184022) (xy 272.36593 -12.168152)
			(xy 272.29861 -12.144595) (xy 272.234351 -12.11365) (xy 272.17396 -12.075704) (xy 272.118198 -12.031235)
			(xy 272.067765 -11.980802) (xy 272.023296 -11.92504) (xy 271.98535 -11.864649) (xy 271.954405 -11.80039)
			(xy 271.930848 -11.73307) (xy 271.914978 -11.663535) (xy 271.906992 -11.592661) (xy 265.557008 -11.592661)
			(xy 265.549022 -11.663535) (xy 265.533152 -11.73307) (xy 265.509595 -11.80039) (xy 265.47865 -11.864649)
			(xy 265.440704 -11.92504) (xy 265.396235 -11.980802) (xy 265.345802 -12.031235) (xy 265.29004 -12.075704)
			(xy 265.229649 -12.11365) (xy 265.16539 -12.144595) (xy 265.09807 -12.168152) (xy 265.028535 -12.184022)
			(xy 264.957661 -12.192008) (xy 264.886339 -12.192008) (xy 264.815465 -12.184022) (xy 264.74593 -12.168152)
			(xy 264.67861 -12.144595) (xy 264.614351 -12.11365) (xy 264.55396 -12.075704) (xy 264.498198 -12.031235)
			(xy 264.447765 -11.980802) (xy 264.403296 -11.92504) (xy 264.36535 -11.864649) (xy 264.334405 -11.80039)
			(xy 264.310848 -11.73307) (xy 264.294978 -11.663535) (xy 264.286992 -11.592661) (xy 207.135776 -11.592661)
			(xy 207.103602 -11.624835) (xy 207.04784 -11.669304) (xy 206.987449 -11.70725) (xy 206.92319 -11.738195)
			(xy 206.85587 -11.761752) (xy 206.786335 -11.777622) (xy 206.715461 -11.785608) (xy 206.644139 -11.785608)
			(xy 206.573265 -11.777622) (xy 206.50373 -11.761752) (xy 206.43641 -11.738195) (xy 206.372151 -11.70725)
			(xy 206.31176 -11.669304) (xy 206.255998 -11.624835) (xy 206.205565 -11.574402) (xy 206.161096 -11.51864)
			(xy 206.12315 -11.458249) (xy 206.092205 -11.39399) (xy 206.068648 -11.32667) (xy 206.052778 -11.257135)
			(xy 206.044792 -11.186261) (xy 202.524183 -11.186261) (xy 202.511659 -11.274699) (xy 202.480341 -11.439009)
			(xy 202.441228 -11.601639) (xy 202.394411 -11.76222) (xy 202.339994 -11.920389) (xy 202.278101 -12.075784)
			(xy 202.208875 -12.228054) (xy 202.13247 -12.376851) (xy 202.049062 -12.521839) (xy 201.95884 -12.662688)
			(xy 201.862008 -12.799077) (xy 201.758787 -12.930697) (xy 201.649412 -13.057249) (xy 201.53413 -13.178445)
			(xy 201.413203 -13.294009) (xy 201.286907 -13.40368) (xy 201.155529 -13.507208) (xy 201.019366 -13.604358)
			(xy 200.878729 -13.694909) (xy 200.733936 -13.778656) (xy 200.585317 -13.855407) (xy 200.43321 -13.92499)
			(xy 200.277959 -13.987245) (xy 200.119919 -14.042031) (xy 199.959447 -14.089223) (xy 199.796908 -14.128716)
			(xy 199.632673 -14.160418) (xy 199.467113 -14.184258) (xy 199.300605 -14.200181) (xy 199.133528 -14.208152)
			(xy 198.96626 -14.208152) (xy 198.799183 -14.200181) (xy 198.632675 -14.184258) (xy 198.467115 -14.160418)
			(xy 198.30288 -14.128716) (xy 198.140341 -14.089223) (xy 197.979869 -14.042031) (xy 197.821829 -13.987245)
			(xy 197.666578 -13.92499) (xy 197.514471 -13.855407) (xy 197.365852 -13.778656) (xy 197.221059 -13.694909)
			(xy 197.080422 -13.604358) (xy 196.944259 -13.507208) (xy 196.812881 -13.40368) (xy 196.686585 -13.294009)
			(xy 196.565658 -13.178445) (xy 196.450376 -13.057249) (xy 196.341001 -12.930697) (xy 196.23778 -12.799077)
			(xy 196.140948 -12.662688) (xy 196.050726 -12.521839) (xy 195.967318 -12.376851) (xy 195.890913 -12.228054)
			(xy 195.821687 -12.075784) (xy 195.759794 -11.920389) (xy 195.705377 -11.76222) (xy 195.65856 -11.601639)
			(xy 195.619447 -11.439009) (xy 195.588129 -11.274699) (xy 195.564676 -11.109084) (xy 195.549141 -10.94254)
			(xy 195.541561 -10.775444) (xy 175.4378 -10.775444) (xy 175.4378 -11.694668) (xy 175.444404 -11.71448)
			(xy 175.454011 -11.744482) (xy 175.467481 -11.806024) (xy 175.474258 -11.868657) (xy 175.474263 -11.931656)
			(xy 175.467495 -11.99429) (xy 175.454034 -12.055834) (xy 175.444404 -12.085828) (xy 175.4378 -12.10564)
			(xy 175.4378 -12.6238) (xy 175.431704 -12.6238) (xy 175.416083 -12.624255) (xy 175.385779 -12.631852)
			(xy 175.358232 -12.646589) (xy 175.335096 -12.667583) (xy 175.31776 -12.693573) (xy 175.31207 -12.708128)
			(xy 175.27778 -12.804394) (xy 175.292258 -12.874244) (xy 175.316642 -12.900406) (xy 175.339497 -12.925534)
			(xy 175.379863 -12.980165) (xy 175.413625 -13.039107) (xy 175.440328 -13.101564) (xy 175.459612 -13.166696)
			(xy 175.471217 -13.233624) (xy 175.474987 -13.301446) (xy 175.47087 -13.369247) (xy 175.458923 -13.436115)
			(xy 175.439306 -13.501147) (xy 175.412283 -13.563467) (xy 175.37822 -13.622235) (xy 175.337574 -13.676659)
			(xy 175.290895 -13.726005) (xy 175.23881 -13.769608) (xy 175.182023 -13.80688) (xy 175.121299 -13.83732)
			(xy 175.057455 -13.860515) (xy 174.991354 -13.876155) (xy 174.923885 -13.884028) (xy 174.855959 -13.884028)
			(xy 174.78849 -13.876155) (xy 174.722389 -13.860515) (xy 174.658545 -13.83732) (xy 174.597821 -13.80688)
			(xy 174.541034 -13.769608) (xy 174.488949 -13.726005) (xy 174.44227 -13.676659) (xy 174.401624 -13.622235)
			(xy 174.367561 -13.563467) (xy 174.340538 -13.501147) (xy 174.320921 -13.436115) (xy 174.308974 -13.369247)
			(xy 174.304857 -13.301446) (xy 174.308627 -13.233624) (xy 174.320232 -13.166696) (xy 174.339516 -13.101564)
			(xy 174.366219 -13.039107) (xy 174.399981 -12.980165) (xy 174.440347 -12.925534) (xy 174.463202 -12.900406)
			(xy 174.487586 -12.874244) (xy 174.502064 -12.804394) (xy 174.467774 -12.708128) (xy 174.462095 -12.69357)
			(xy 174.444754 -12.667586) (xy 174.421614 -12.6466) (xy 174.394064 -12.631873) (xy 174.36376 -12.624289)
			(xy 174.34814 -12.6238) (xy 174.2948 -12.6238) (xy 174.2948 -9.811004) (xy 174.315636 -9.801971)
			(xy 174.353974 -9.777636) (xy 174.387379 -9.746877) (xy 174.414789 -9.710674) (xy 174.435332 -9.670177)
			(xy 174.448354 -9.626676) (xy 174.453442 -9.581553) (xy 174.450434 -9.536243) (xy 174.439424 -9.492189)
			(xy 174.420764 -9.450791) (xy 174.408338 -9.431782) (xy 174.389185 -9.403099) (xy 174.357005 -9.342092)
			(xy 174.332229 -9.277722) (xy 174.3152 -9.210884) (xy 174.306155 -9.142506) (xy 174.305219 -9.073539)
			(xy 174.312406 -9.004941) (xy 174.327616 -8.937665) (xy 174.350637 -8.872647) (xy 174.38115 -8.81079)
			(xy 174.41873 -8.752954) (xy 174.462855 -8.699941) (xy 174.512912 -8.65249) (xy 174.568206 -8.61126)
			(xy 174.597822 -8.593582) (xy 174.62754 -8.576564) (xy 174.661322 -8.51789) (xy 174.661322 -8.4836)
			(xy 174.660779 -8.466951) (xy 174.652161 -8.434786) (xy 174.635514 -8.405948) (xy 174.61197 -8.3824)
			(xy 174.583134 -8.365747) (xy 174.550971 -8.357124) (xy 174.534322 -8.3566) (xy 174.3456 -8.3566)
			(xy 174.3456 -7.91464) (xy 174.335694 -7.886192) (xy 174.33417 -7.881366) (xy 174.333662 -7.879842)
			(xy 174.32295 -7.84487) (xy 174.309306 -7.77301) (xy 174.304733 -7.70001) (xy 174.309304 -7.627009)
			(xy 174.322945 -7.555149) (xy 174.333662 -7.520178) (xy 174.33417 -7.518654) (xy 174.335694 -7.513828)
			(xy 174.3456 -7.48538) (xy 174.3456 -6.514592) (xy 174.335694 -6.486144) (xy 174.333916 -6.480302)
			(xy 174.333408 -6.478778) (xy 174.323367 -6.445963) (xy 174.310135 -6.378624) (xy 174.304874 -6.310199)
			(xy 174.307655 -6.241628) (xy 174.31844 -6.173854) (xy 174.327312 -6.140704) (xy 174.329852 -6.132322)
			(xy 174.33798 -6.105652) (xy 174.33798 -6.086348) (xy 174.337491 -6.06969) (xy 174.328878 -6.037507)
			(xy 174.312226 -6.008652) (xy 174.288671 -5.985091) (xy 174.259819 -5.968433) (xy 174.227638 -5.959813)
			(xy 174.21098 -5.959348) (xy 174.126144 -5.959348) (xy 173.996604 -5.829808) (xy 173.720506 -5.829808)
			(xy 173.698781 -5.830243) (xy 173.655961 -5.83762) (xy 173.615021 -5.852177) (xy 173.577156 -5.873488)
			(xy 173.543471 -5.900933) (xy 173.514947 -5.93371) (xy 173.492418 -5.970864) (xy 173.476541 -6.011309)
			(xy 173.467778 -6.053867) (xy 173.466387 -6.097295) (xy 173.469046 -6.11886) (xy 173.473467 -6.154198)
			(xy 173.474722 -6.225405) (xy 173.467325 -6.296238) (xy 173.451388 -6.36565) (xy 173.427144 -6.432615)
			(xy 173.394953 -6.496143) (xy 173.375574 -6.526022) (xy 173.365414 -6.541008) (xy 173.33722 -6.6294)
			(xy 173.398942 -6.769608) (xy 173.4566 -6.8072) (xy 173.4566 -7.4549) (xy 173.459902 -7.469124) (xy 173.466865 -7.501442)
			(xy 173.474322 -7.567132) (xy 173.474323 -7.633244) (xy 173.466869 -7.698935) (xy 173.459902 -7.731252)
			(xy 173.4566 -7.745476) (xy 173.4566 -8.854694) (xy 173.459902 -8.868918) (xy 173.466865 -8.901236)
			(xy 173.474323 -8.966926) (xy 173.474325 -9.033039) (xy 173.466871 -9.09873) (xy 173.459902 -9.131046)
			(xy 173.4566 -9.14527) (xy 173.4566 -9.677654) (xy 173.436825 -9.68778) (xy 173.400861 -9.713859)
			(xy 173.369978 -9.745794) (xy 173.345119 -9.782611) (xy 173.327039 -9.82319) (xy 173.316289 -9.866294)
			(xy 173.313197 -9.910611) (xy 173.317858 -9.95479) (xy 173.330128 -9.997487) (xy 173.349635 -10.037399)
			(xy 173.362366 -10.055606) (xy 173.381779 -10.083027) (xy 173.414879 -10.141495) (xy 173.44106 -10.203371)
			(xy 173.459977 -10.267841) (xy 173.471379 -10.334054) (xy 173.475117 -10.401137) (xy 173.471141 -10.468207)
			(xy 173.459504 -10.534378) (xy 173.44036 -10.598781) (xy 173.41396 -10.660564) (xy 173.380652 -10.718914)
			(xy 173.361096 -10.746232) (xy 173.348238 -10.764541) (xy 173.328483 -10.804678) (xy 173.316059 -10.847653)
			(xy 173.311348 -10.892139) (xy 173.314497 -10.936763) (xy 173.325408 -10.980147) (xy 173.343745 -11.020952)
			(xy 173.36894 -11.057917) (xy 173.400217 -11.089902) (xy 173.436609 -11.115918) (xy 173.4566 -11.125962)
			(xy 173.4566 -11.65479) (xy 173.459902 -11.669014) (xy 173.466866 -11.701332) (xy 173.474323 -11.767022)
			(xy 173.474326 -11.833135) (xy 173.466873 -11.898826) (xy 173.459902 -11.931142) (xy 173.4566 -11.945366)
			(xy 173.4566 -13.054838) (xy 173.459902 -13.069062) (xy 173.466863 -13.10138) (xy 173.474315 -13.16707)
			(xy 173.474312 -13.233181) (xy 173.466854 -13.29887) (xy 173.459902 -13.33119) (xy 173.4566 -13.345414)
			(xy 173.4566 -13.903706) (xy 173.473872 -13.939774) (xy 173.478952 -13.951712) (xy 173.489179 -13.977863)
			(xy 173.502711 -14.032359) (xy 173.508106 -14.088251) (xy 173.505248 -14.144329) (xy 173.494197 -14.199382)
			(xy 173.475194 -14.252219) (xy 173.448648 -14.301699) (xy 173.415134 -14.346752) (xy 173.375376 -14.386403)
			(xy 173.330233 -14.419797) (xy 173.280682 -14.446209) (xy 173.227794 -14.465071) (xy 173.172711 -14.475974)
			(xy 173.116626 -14.478682) (xy 173.060749 -14.473137) (xy 173.00629 -14.459458) (xy 172.954424 -14.437942)
			(xy 172.906275 -14.409054) (xy 172.862881 -14.373417) (xy 172.825183 -14.331803) (xy 172.793993 -14.28511)
			(xy 172.769988 -14.23435) (xy 172.753684 -14.180617) (xy 172.745436 -14.125075) (xy 172.744892 -14.097)
			(xy 172.744437 -14.074818) (xy 172.736733 -14.031128) (xy 172.721559 -13.989439) (xy 172.699377 -13.951019)
			(xy 172.67086 -13.917035) (xy 172.636874 -13.888518) (xy 172.598453 -13.866337) (xy 172.556764 -13.851165)
			(xy 172.513074 -13.843462) (xy 172.490892 -13.843) (xy 172.339 -13.843) (xy 172.339 -13.397738) (xy 172.332904 -13.378688)
			(xy 172.322342 -13.343949) (xy 172.308901 -13.272594) (xy 172.304396 -13.200125) (xy 172.308895 -13.127655)
			(xy 172.32233 -13.056299) (xy 172.332904 -13.021564) (xy 172.339 -13.002514) (xy 172.339 -11.99769)
			(xy 172.332904 -11.97864) (xy 172.322345 -11.943901) (xy 172.30891 -11.872547) (xy 172.304411 -11.800079)
			(xy 172.308916 -11.727611) (xy 172.322355 -11.656258) (xy 172.332904 -11.621516) (xy 172.339 -11.602466)
			(xy 172.339 -11.117834) (xy 172.357483 -11.106878) (xy 172.390803 -11.079756) (xy 172.419085 -11.047415)
			(xy 172.441521 -11.010775) (xy 172.457473 -10.970883) (xy 172.466485 -10.928876) (xy 172.468301 -10.885952)
			(xy 172.462868 -10.843333) (xy 172.450342 -10.802237) (xy 172.43108 -10.763834) (xy 172.418756 -10.746232)
			(xy 172.398204 -10.717418) (xy 172.363459 -10.655755) (xy 172.336412 -10.590349) (xy 172.317457 -10.522156)
			(xy 172.306872 -10.452174) (xy 172.304813 -10.381426) (xy 172.311308 -10.310947) (xy 172.326264 -10.241767)
			(xy 172.349461 -10.174898) (xy 172.38056 -10.111318) (xy 172.419106 -10.051957) (xy 172.464535 -9.997684)
			(xy 172.516184 -9.94929) (xy 172.573297 -9.907486) (xy 172.603922 -9.889744) (xy 172.633894 -9.87298)
			(xy 172.668692 -9.813544) (xy 172.668692 -9.779) (xy 172.668197 -9.762346) (xy 172.659576 -9.730172)
			(xy 172.642921 -9.701326) (xy 172.619368 -9.677774) (xy 172.590521 -9.661121) (xy 172.558346 -9.652502)
			(xy 172.541692 -9.652) (xy 172.3644 -9.652) (xy 172.3644 -9.257792) (xy 172.353732 -9.233408) (xy 172.340488 -9.201751)
			(xy 172.320649 -9.136056) (xy 172.308637 -9.06849) (xy 172.304616 -8.999983) (xy 172.308641 -8.931477)
			(xy 172.320657 -8.863912) (xy 172.340499 -8.798218) (xy 172.353732 -8.766556) (xy 172.3644 -8.742172)
			(xy 172.3644 -7.857998) (xy 172.353732 -7.833614) (xy 172.340487 -7.801957) (xy 172.320648 -7.736262)
			(xy 172.308635 -7.668696) (xy 172.304614 -7.600189) (xy 172.308638 -7.531682) (xy 172.320654 -7.464117)
			(xy 172.340495 -7.398422) (xy 172.353732 -7.366762) (xy 172.3644 -7.342378) (xy 172.3644 -6.8072)
			(xy 172.414184 -6.694932) (xy 172.414184 -6.542278) (xy 172.394626 -6.51129) (xy 172.377125 -6.482513)
			(xy 172.348112 -6.421727) (xy 172.326277 -6.35801) (xy 172.311909 -6.292205) (xy 172.305199 -6.225185)
			(xy 172.305218 -6.191504) (xy 172.305062 -6.169118) (xy 172.297844 -6.12494) (xy 172.282997 -6.082711)
			(xy 172.260979 -6.043737) (xy 172.232471 -6.009224) (xy 172.198358 -5.980241) (xy 172.159693 -5.957684)
			(xy 172.117673 -5.942252) (xy 172.0736 -5.934422) (xy 172.051218 -5.933948) (xy 171.6532 -5.933948)
			(xy 171.636548 -5.934443) (xy 171.604378 -5.943065) (xy 171.575537 -5.959721) (xy 171.551991 -5.983275)
			(xy 171.535346 -6.012123) (xy 171.526736 -6.044295) (xy 171.5262 -6.060948) (xy 171.5262 -8.419846)
			(xy 171.50451 -8.427409) (xy 171.464086 -8.449218) (xy 171.428242 -8.477939) (xy 171.398147 -8.512638)
			(xy 171.374782 -8.552182) (xy 171.358907 -8.595283) (xy 171.351041 -8.640536) (xy 171.35144 -8.686466)
			(xy 171.360091 -8.731575) (xy 171.376712 -8.774394) (xy 171.388278 -8.794242) (xy 171.406312 -8.824643)
			(xy 171.435718 -8.888922) (xy 171.45716 -8.956278) (xy 171.470325 -9.025728) (xy 171.475021 -9.096258)
			(xy 171.471179 -9.16684) (xy 171.458856 -9.236444) (xy 171.43823 -9.304055) (xy 171.409604 -9.368686)
			(xy 171.373395 -9.429394) (xy 171.35221 -9.45769) (xy 171.331382 -9.484614) (xy 171.322238 -9.552178)
			(xy 171.3738 -9.676638) (xy 171.3738 -10.169906) (xy 171.391834 -10.200132) (xy 171.409353 -10.230447)
			(xy 171.437838 -10.294411) (xy 171.45848 -10.361318) (xy 171.470985 -10.430211) (xy 171.475173 -10.500105)
			(xy 171.470984 -10.569999) (xy 171.458478 -10.638892) (xy 171.437834 -10.705799) (xy 171.409348 -10.769762)
			(xy 171.391834 -10.80008) (xy 171.3738 -10.830306) (xy 171.3738 -11.569954) (xy 171.391834 -11.60018)
			(xy 171.409356 -11.630495) (xy 171.437847 -11.694459) (xy 171.458495 -11.761368) (xy 171.471006 -11.830264)
			(xy 171.475199 -11.90016) (xy 171.471015 -11.970058) (xy 171.458514 -12.038955) (xy 171.437875 -12.105867)
			(xy 171.409392 -12.169834) (xy 171.391834 -12.200128) (xy 171.3738 -12.230354) (xy 171.3738 -12.5476)
			(xy 171.229782 -12.5476) (xy 171.213135 -12.548145) (xy 171.180977 -12.556766) (xy 171.152145 -12.573416)
			(xy 171.128605 -12.59696) (xy 171.111959 -12.625794) (xy 171.103343 -12.657953) (xy 171.102782 -12.6746)
			(xy 171.102782 -12.709652) (xy 171.138342 -12.769342) (xy 171.169076 -12.786106) (xy 171.199236 -12.803073)
			(xy 171.255717 -12.84306) (xy 171.307084 -12.889433) (xy 171.352618 -12.941546) (xy 171.391682 -12.998669)
			(xy 171.423731 -13.060004) (xy 171.448315 -13.124693) (xy 171.465093 -13.191831) (xy 171.473828 -13.260481)
			(xy 171.474399 -13.329681) (xy 171.466797 -13.398466) (xy 171.45113 -13.465872) (xy 171.427616 -13.530957)
			(xy 171.396583 -13.592812) (xy 171.358467 -13.650572) (xy 171.313799 -13.703429) (xy 171.263204 -13.750643)
			(xy 171.20739 -13.791556) (xy 171.147137 -13.825595) (xy 171.083287 -13.852283) (xy 171.016733 -13.871248)
			(xy 170.948407 -13.882225) (xy 170.879262 -13.88506) (xy 170.810266 -13.879714) (xy 170.742383 -13.86626)
			(xy 170.676563 -13.844889) (xy 170.613725 -13.815897) (xy 170.554749 -13.779691) (xy 170.500459 -13.736777)
			(xy 170.451614 -13.687754) (xy 170.408897 -13.633309) (xy 170.372905 -13.574202) (xy 170.344141 -13.51126)
			(xy 170.323008 -13.445362) (xy 170.309801 -13.377431) (xy 170.304705 -13.308416) (xy 170.307791 -13.239282)
			(xy 170.319016 -13.170995) (xy 170.338222 -13.104511) (xy 170.365142 -13.040758) (xy 170.399399 -12.980629)
			(xy 170.419522 -12.952476) (xy 170.432192 -12.934547) (xy 170.451818 -12.89528) (xy 170.464402 -12.853224)
			(xy 170.469568 -12.80963) (xy 170.467163 -12.765798) (xy 170.457258 -12.723031) (xy 170.440148 -12.682604)
			(xy 170.416343 -12.645721) (xy 170.386552 -12.613479) (xy 170.351661 -12.586838) (xy 170.3324 -12.576302)
			(xy 170.3324 -12.077192) (xy 170.327574 -12.060174) (xy 170.319123 -12.028866) (xy 170.30839 -11.964908)
			(xy 170.304801 -11.900156) (xy 170.3084 -11.835404) (xy 170.319143 -11.771448) (xy 170.327574 -11.740134)
			(xy 170.3324 -11.723116) (xy 170.3324 -10.677144) (xy 170.327574 -10.660126) (xy 170.31912 -10.628818)
			(xy 170.308382 -10.564859) (xy 170.304787 -10.500106) (xy 170.30838 -10.435352) (xy 170.319118 -10.371394)
			(xy 170.327574 -10.340086) (xy 170.3324 -10.323068) (xy 170.3324 -9.7282) (xy 170.338242 -9.7282)
			(xy 170.40225 -9.685528) (xy 170.458638 -9.549384) (xy 170.42765 -9.45896) (xy 170.416474 -9.443466)
			(xy 170.396664 -9.415276) (xy 170.363069 -9.355118) (xy 170.336774 -9.291431) (xy 170.318141 -9.225096)
			(xy 170.307431 -9.157032) (xy 170.304789 -9.08818) (xy 170.310254 -9.019495) (xy 170.32375 -8.951928)
			(xy 170.34509 -8.886413) (xy 170.373977 -8.823859) (xy 170.391582 -8.794242) (xy 170.402423 -8.775719)
			(xy 170.418402 -8.73589) (xy 170.427461 -8.693942) (xy 170.42934 -8.651068) (xy 170.423988 -8.608488)
			(xy 170.411556 -8.567414) (xy 170.392398 -8.529012) (xy 170.367059 -8.494377) (xy 170.336259 -8.464492)
			(xy 170.300875 -8.440209) (xy 170.2816 -8.430768) (xy 170.2816 -6.060948) (xy 170.281111 -6.044289)
			(xy 170.272498 -6.012104) (xy 170.255847 -5.983246) (xy 170.232292 -5.959683) (xy 170.20344 -5.94302)
			(xy 170.171259 -5.934395) (xy 170.1546 -5.933948) (xy 169.728642 -5.933948) (xy 169.706264 -5.934425)
			(xy 169.662202 -5.942273) (xy 169.620195 -5.957717) (xy 169.581542 -5.980279) (xy 169.547438 -6.009261)
			(xy 169.518936 -6.043768) (xy 169.496919 -6.082734) (xy 169.482065 -6.124953) (xy 169.474835 -6.169121)
			(xy 169.474642 -6.191504) (xy 169.47464 -6.225889) (xy 169.467557 -6.294285) (xy 169.452501 -6.361379)
			(xy 169.429682 -6.426244) (xy 169.399412 -6.487985) (xy 169.38117 -6.517132) (xy 169.369147 -6.536678)
			(xy 169.351605 -6.579077) (xy 169.341968 -6.623938) (xy 169.340549 -6.6698) (xy 169.347395 -6.715171)
			(xy 169.362283 -6.758574) (xy 169.384727 -6.798594) (xy 169.413998 -6.83393) (xy 169.449142 -6.86343)
			(xy 169.4688 -6.875272) (xy 169.4688 -7.517384) (xy 169.47007 -7.527036) (xy 169.470324 -7.528814)
			(xy 169.470324 -7.530338) (xy 169.471086 -7.537196) (xy 169.47417 -7.569449) (xy 169.474043 -7.634242)
			(xy 169.470832 -7.666482) (xy 169.469816 -7.674356) (xy 169.4688 -7.682992) (xy 169.4688 -8.917178)
			(xy 169.47007 -8.92683) (xy 169.470324 -8.928608) (xy 169.470324 -8.930132) (xy 169.471086 -8.93699)
			(xy 169.474171 -8.969243) (xy 169.474044 -9.034036) (xy 169.470832 -9.066276) (xy 169.469816 -9.07415)
			(xy 169.4688 -9.082786) (xy 169.4688 -9.672066) (xy 169.447906 -9.681419) (xy 169.409612 -9.706494)
			(xy 169.376428 -9.738022) (xy 169.349429 -9.774986) (xy 169.329489 -9.816187) (xy 169.317252 -9.860295)
			(xy 169.313114 -9.905881) (xy 169.317209 -9.95147) (xy 169.329405 -9.995589) (xy 169.349307 -10.03681)
			(xy 169.362374 -10.055606) (xy 169.381786 -10.083027) (xy 169.414887 -10.141495) (xy 169.441067 -10.203371)
			(xy 169.459983 -10.267841) (xy 169.471386 -10.334054) (xy 169.475123 -10.401137) (xy 169.471148 -10.468206)
			(xy 169.459511 -10.534378) (xy 169.440367 -10.59878) (xy 169.413967 -10.660564) (xy 169.38066 -10.718914)
			(xy 169.361104 -10.746232) (xy 169.348188 -10.764635) (xy 169.328371 -10.804987) (xy 169.31596 -10.848196)
			(xy 169.311342 -10.892914) (xy 169.314663 -10.937747) (xy 169.325818 -10.981297) (xy 169.344459 -11.022206)
			(xy 169.370005 -11.059198) (xy 169.401659 -11.09112) (xy 169.438435 -11.116977) (xy 169.479186 -11.135961)
			(xy 169.52264 -11.147482) (xy 169.545 -11.149838) (xy 169.545 -13.7668) (xy 169.521453 -13.76736)
			(xy 169.475179 -13.776127) (xy 169.431313 -13.793267) (xy 169.391354 -13.818195) (xy 169.356671 -13.850056)
			(xy 169.32845 -13.887761) (xy 169.307658 -13.930019) (xy 169.295006 -13.975385) (xy 169.290926 -14.022304)
			(xy 169.29556 -14.069172) (xy 169.301668 -14.09192) (xy 169.308815 -14.118187) (xy 169.316453 -14.172084)
			(xy 169.316353 -14.22652) (xy 169.308516 -14.280389) (xy 169.293101 -14.332596) (xy 169.270421 -14.382082)
			(xy 169.240937 -14.427842) (xy 169.205248 -14.468946) (xy 169.164078 -14.504559) (xy 169.118264 -14.533958)
			(xy 169.068737 -14.556547) (xy 169.016501 -14.571866) (xy 168.962618 -14.579604) (xy 168.908182 -14.579604)
			(xy 168.854299 -14.571866) (xy 168.802063 -14.556547) (xy 168.752536 -14.533958) (xy 168.706722 -14.504559)
			(xy 168.665552 -14.468946) (xy 168.629863 -14.427842) (xy 168.600379 -14.382082) (xy 168.577699 -14.332596)
			(xy 168.562284 -14.280389) (xy 168.554447 -14.22652) (xy 168.554347 -14.172084) (xy 168.561985 -14.118187)
			(xy 168.569132 -14.09192) (xy 168.575232 -14.069171) (xy 168.579865 -14.022304) (xy 168.575786 -13.975386)
			(xy 168.563134 -13.930022) (xy 168.542343 -13.887765) (xy 168.514123 -13.850062) (xy 168.479441 -13.818201)
			(xy 168.439484 -13.793274) (xy 168.395618 -13.776135) (xy 168.349346 -13.767368) (xy 168.3258 -13.7668)
			(xy 168.3258 -13.354558) (xy 168.321736 -13.337032) (xy 168.319196 -13.32611) (xy 168.312759 -13.295013)
			(xy 168.305872 -13.231879) (xy 168.305869 -13.168371) (xy 168.312751 -13.105238) (xy 168.319196 -13.074142)
			(xy 168.321736 -13.06322) (xy 168.3258 -13.045694) (xy 168.3258 -11.95451) (xy 168.321736 -11.936984)
			(xy 168.319196 -11.926062) (xy 168.312762 -11.894965) (xy 168.30588 -11.831832) (xy 168.305882 -11.768325)
			(xy 168.312769 -11.705193) (xy 168.319196 -11.674094) (xy 168.321736 -11.663172) (xy 168.3258 -11.645646)
			(xy 168.3258 -11.124692) (xy 168.345554 -11.114499) (xy 168.381453 -11.088292) (xy 168.412246 -11.05624)
			(xy 168.436994 -11.01932) (xy 168.454942 -10.978657) (xy 168.465543 -10.935493) (xy 168.468473 -10.891142)
			(xy 168.463644 -10.846958) (xy 168.451202 -10.804287) (xy 168.431527 -10.764432) (xy 168.418764 -10.746232)
			(xy 168.399254 -10.718884) (xy 168.365947 -10.66054) (xy 168.339546 -10.598763) (xy 168.320402 -10.534367)
			(xy 168.308765 -10.468201) (xy 168.304789 -10.401137) (xy 168.308527 -10.334059) (xy 168.319929 -10.267852)
			(xy 168.338846 -10.203389) (xy 168.365027 -10.141518) (xy 168.398128 -10.083057) (xy 168.417494 -10.055606)
			(xy 168.430119 -10.037494) (xy 168.449576 -9.997867) (xy 168.461888 -9.955472) (xy 168.466685 -9.911588)
			(xy 168.463821 -9.867535) (xy 168.453383 -9.82464) (xy 168.435685 -9.784197) (xy 168.41126 -9.747423)
			(xy 168.380845 -9.715426) (xy 168.345355 -9.689171) (xy 168.3258 -9.678924) (xy 168.3258 -9.154414)
			(xy 168.321736 -9.136888) (xy 168.319196 -9.125966) (xy 168.312761 -9.094869) (xy 168.305879 -9.031736)
			(xy 168.305881 -8.968229) (xy 168.312767 -8.905097) (xy 168.319196 -8.873998) (xy 168.321736 -8.863076)
			(xy 168.3258 -8.84555) (xy 168.3258 -7.75462) (xy 168.321736 -7.737094) (xy 168.319196 -7.726172)
			(xy 168.312761 -7.695075) (xy 168.305878 -7.631942) (xy 168.305879 -7.568435) (xy 168.312765 -7.505302)
			(xy 168.319196 -7.474204) (xy 168.321736 -7.463282) (xy 168.3258 -7.445756) (xy 168.3258 -6.9088)
			(xy 168.38676 -6.9088) (xy 168.402844 -6.908325) (xy 168.433988 -6.900274) (xy 168.462134 -6.884699)
			(xy 168.485497 -6.862587) (xy 168.502596 -6.835339) (xy 168.507918 -6.820154) (xy 168.526968 -6.759702)
			(xy 168.531561 -6.742999) (xy 168.5326 -6.708388) (xy 168.524302 -6.674771) (xy 168.50728 -6.644617)
			(xy 168.495472 -6.63194) (xy 168.460166 -6.596634) (xy 168.437614 -6.571485) (xy 168.397831 -6.516888)
			(xy 168.364607 -6.45807) (xy 168.338383 -6.395814) (xy 168.319511 -6.33095) (xy 168.308241 -6.264343)
			(xy 168.304724 -6.196881) (xy 168.309006 -6.129464) (xy 168.321031 -6.062989) (xy 168.340638 -5.998344)
			(xy 168.367566 -5.936389) (xy 168.401455 -5.877951) (xy 168.441855 -5.82381) (xy 168.488226 -5.774685)
			(xy 168.53995 -5.731233) (xy 168.567862 -5.712206) (xy 168.586464 -5.69935) (xy 168.619213 -5.668175)
			(xy 168.64593 -5.631699) (xy 168.665772 -5.591071) (xy 168.678115 -5.547574) (xy 168.682569 -5.50258)
			(xy 168.678993 -5.457508) (xy 168.6675 -5.413778) (xy 168.648452 -5.372772) (xy 168.622451 -5.335782)
			(xy 168.590316 -5.303975) (xy 168.571926 -5.29082) (xy 168.544983 -5.272828) (xy 168.494851 -5.231782)
			(xy 168.449565 -5.185445) (xy 168.409681 -5.134385) (xy 168.375686 -5.079228) (xy 168.347999 -5.020651)
			(xy 168.326958 -4.959371) (xy 168.31945 -4.927854) (xy 168.312752 -4.895852) (xy 168.305676 -4.830852)
			(xy 168.305893 -4.765468) (xy 168.3134 -4.700516) (xy 168.328103 -4.636806) (xy 168.349819 -4.575133)
			(xy 168.378276 -4.516266) (xy 168.41312 -4.46094) (xy 168.453917 -4.409844) (xy 168.500156 -4.363616)
			(xy 168.525444 -4.342892) (xy 168.531032 -4.33832) (xy 168.5798 -4.289552) (xy 168.5798 -3.910584)
			(xy 168.531032 -3.861816) (xy 168.525444 -3.857244) (xy 168.498388 -3.835022) (xy 168.449239 -3.785154)
			(xy 168.406397 -3.729774) (xy 168.370476 -3.669674) (xy 168.341988 -3.605714) (xy 168.321343 -3.53881)
			(xy 168.308835 -3.469919) (xy 168.304643 -3.400027) (xy 168.308828 -3.330136) (xy 168.32133 -3.261244)
			(xy 168.341969 -3.194338) (xy 168.37045 -3.130375) (xy 168.406366 -3.070272) (xy 168.449203 -3.014887)
			(xy 168.498347 -2.965015) (xy 168.525444 -2.942844) (xy 168.531032 -2.938272) (xy 168.5798 -2.889504)
			(xy 168.5798 -2.54) (xy 167.8178 -1.778) (xy 167.6908 -1.778) (xy 167.674152 -1.778543) (xy 167.641989 -1.787161)
			(xy 167.613154 -1.803809) (xy 167.589609 -1.827354) (xy 167.572961 -1.856189) (xy 167.564343 -1.888352)
			(xy 167.5638 -1.905) (xy 167.5638 -4.220718) (xy 167.54203 -4.225239) (xy 167.500407 -4.240862) (xy 167.462137 -4.263489)
			(xy 167.428389 -4.292431) (xy 167.400193 -4.326805) (xy 167.378409 -4.365562) (xy 167.363703 -4.407518)
			(xy 167.356522 -4.451393) (xy 167.357087 -4.495848) (xy 167.36538 -4.539527) (xy 167.381147 -4.581095)
			(xy 167.392096 -4.600448) (xy 167.408902 -4.629518) (xy 167.436488 -4.69074) (xy 167.456881 -4.754718)
			(xy 167.469812 -4.820611) (xy 167.475111 -4.887552) (xy 167.472709 -4.954659) (xy 167.462637 -5.021049)
			(xy 167.445027 -5.085849) (xy 167.420112 -5.148205) (xy 167.38822 -5.207298) (xy 167.349769 -5.26235)
			(xy 167.327834 -5.287772) (xy 167.304212 -5.314442) (xy 167.291512 -5.383784) (xy 167.303958 -5.416804)
			(xy 167.327834 -5.480304) (xy 167.333658 -5.494571) (xy 167.351103 -5.519964) (xy 167.37413 -5.540431)
			(xy 167.401393 -5.554777) (xy 167.431302 -5.562166) (xy 167.446706 -5.5626) (xy 167.4876 -5.5626)
			(xy 167.4876 -8.436102) (xy 167.467269 -8.447248) (xy 167.430696 -8.475737) (xy 167.399898 -8.510389)
			(xy 167.375899 -8.550053) (xy 167.359494 -8.593413) (xy 167.351229 -8.63903) (xy 167.351377 -8.68539)
			(xy 167.359934 -8.730953) (xy 167.376615 -8.774207) (xy 167.388286 -8.794242) (xy 167.405892 -8.823861)
			(xy 167.434804 -8.886408) (xy 167.456163 -8.95192) (xy 167.469671 -9.019489) (xy 167.475142 -9.088177)
			(xy 167.472498 -9.157033) (xy 167.461778 -9.225099) (xy 167.443129 -9.291434) (xy 167.416811 -9.355116)
			(xy 167.383188 -9.415262) (xy 167.363394 -9.443466) (xy 167.352218 -9.45896) (xy 167.32123 -9.549384)
			(xy 167.379396 -9.6901) (xy 167.4368 -9.7282) (xy 167.4368 -10.291064) (xy 167.443658 -10.31113)
			(xy 167.453607 -10.34163) (xy 167.467561 -10.404253) (xy 167.474579 -10.468026) (xy 167.474579 -10.532185)
			(xy 167.467559 -10.595958) (xy 167.453604 -10.658581) (xy 167.443658 -10.689082) (xy 167.4368 -10.709148)
			(xy 167.4368 -11.691112) (xy 167.443658 -11.711178) (xy 167.45361 -11.741678) (xy 167.467569 -11.804302)
			(xy 167.474593 -11.868076) (xy 167.474598 -11.932237) (xy 167.467583 -11.996012) (xy 167.453634 -12.058638)
			(xy 167.443658 -12.08913) (xy 167.4368 -12.109196) (xy 167.4368 -12.5984) (xy 167.402256 -12.5984)
			(xy 167.386259 -12.598817) (xy 167.355253 -12.606703) (xy 167.327192 -12.622068) (xy 167.303846 -12.643942)
			(xy 167.286688 -12.670944) (xy 167.281352 -12.68603) (xy 167.250364 -12.781534) (xy 167.268144 -12.8524)
			(xy 167.29456 -12.8778) (xy 167.31865 -12.901553) (xy 167.361771 -12.953686) (xy 167.398587 -13.010447)
			(xy 167.428606 -13.071078) (xy 167.451426 -13.134768) (xy 167.466744 -13.200666) (xy 167.474355 -13.267892)
			(xy 167.474156 -13.335547) (xy 167.46615 -13.402727) (xy 167.450444 -13.468534) (xy 167.427249 -13.532088)
			(xy 167.396874 -13.592541) (xy 167.359725 -13.649085) (xy 167.316298 -13.700963) (xy 167.267174 -13.747483)
			(xy 167.21301 -13.788022) (xy 167.154529 -13.82204) (xy 167.092513 -13.849081) (xy 167.02779 -13.868784)
			(xy 166.961226 -13.880886) (xy 166.89371 -13.885224) (xy 166.826145 -13.881742) (xy 166.759433 -13.870485)
			(xy 166.694465 -13.851605) (xy 166.632111 -13.825352) (xy 166.573204 -13.792079) (xy 166.51853 -13.752229)
			(xy 166.46882 -13.706336) (xy 166.424739 -13.655012) (xy 166.386876 -13.598945) (xy 166.355737 -13.538881)
			(xy 166.331738 -13.475626) (xy 166.315199 -13.410023) (xy 166.306342 -13.34295) (xy 166.305285 -13.275304)
			(xy 166.312042 -13.207987) (xy 166.326524 -13.141899) (xy 166.348535 -13.077925) (xy 166.377783 -13.016919)
			(xy 166.3954 -12.988036) (xy 166.407574 -12.967791) (xy 166.424989 -12.923884) (xy 166.433991 -12.877515)
			(xy 166.43427 -12.830281) (xy 166.425817 -12.783809) (xy 166.408922 -12.739699) (xy 166.384168 -12.69947)
			(xy 166.352407 -12.664508) (xy 166.314733 -12.636016) (xy 166.2938 -12.62507) (xy 166.2938 -9.7536)
			(xy 166.3065 -9.7536) (xy 166.399718 -9.69137) (xy 166.458646 -9.549638) (xy 166.427658 -9.45896)
			(xy 166.416482 -9.443466) (xy 166.396672 -9.415276) (xy 166.363077 -9.355119) (xy 166.336781 -9.291432)
			(xy 166.318148 -9.225096) (xy 166.307437 -9.157032) (xy 166.304796 -9.08818) (xy 166.310261 -9.019495)
			(xy 166.323757 -8.951927) (xy 166.345097 -8.886413) (xy 166.373985 -8.823859) (xy 166.39159 -8.794242)
			(xy 166.403453 -8.773923) (xy 166.420254 -8.729978) (xy 166.428684 -8.683692) (xy 166.428455 -8.636645)
			(xy 166.419576 -8.590444) (xy 166.40235 -8.546664) (xy 166.377364 -8.5068) (xy 166.345471 -8.472213)
			(xy 166.30776 -8.444082) (xy 166.265518 -8.423369) (xy 166.243 -8.416544) (xy 166.243 -5.547614)
			(xy 166.263598 -5.539736) (xy 166.30192 -5.517922) (xy 166.335899 -5.489818) (xy 166.364513 -5.456267)
			(xy 166.386904 -5.418279) (xy 166.402397 -5.376995) (xy 166.410528 -5.333656) (xy 166.411052 -5.289563)
			(xy 166.403953 -5.246043) (xy 166.389444 -5.204402) (xy 166.379144 -5.184902) (xy 166.363018 -5.154952)
			(xy 166.33702 -5.092091) (xy 166.318491 -5.026638) (xy 166.307681 -4.959478) (xy 166.304736 -4.891517)
			(xy 166.309696 -4.823673) (xy 166.322494 -4.756863) (xy 166.342956 -4.691989) (xy 166.370807 -4.629927)
			(xy 166.38778 -4.600448) (xy 166.398712 -4.581166) (xy 166.414456 -4.539735) (xy 166.422772 -4.496202)
			(xy 166.423409 -4.451885) (xy 166.416347 -4.40813) (xy 166.401801 -4.366264) (xy 166.380212 -4.327557)
			(xy 166.352235 -4.293182) (xy 166.318718 -4.264183) (xy 166.280678 -4.241439) (xy 166.239269 -4.225639)
			(xy 166.2176 -4.220972) (xy 166.2176 -1.905) (xy 166.217057 -1.888352) (xy 166.208439 -1.856189)
			(xy 166.191791 -1.827354) (xy 166.168246 -1.803809) (xy 166.139411 -1.787161) (xy 166.107248 -1.778543)
			(xy 166.0906 -1.778) (xy 165.728142 -1.778) (xy 165.706481 -1.77841) (xy 165.663779 -1.785703) (xy 165.622934 -1.800135)
			(xy 165.58513 -1.821289) (xy 165.551463 -1.848551) (xy 165.52291 -1.881129) (xy 165.500299 -1.91808)
			(xy 165.484285 -1.958332) (xy 165.475333 -2.000717) (xy 165.474142 -2.022348) (xy 165.47234 -2.057161)
			(xy 165.461475 -2.12602) (xy 165.442496 -2.193097) (xy 165.41567 -2.25744) (xy 165.398958 -2.288032)
			(xy 165.388549 -2.307408) (xy 165.373832 -2.348852) (xy 165.366468 -2.392211) (xy 165.366676 -2.43619)
			(xy 165.37445 -2.479477) (xy 165.389559 -2.52078) (xy 165.41155 -2.558867) (xy 165.439768 -2.5926)
			(xy 165.47337 -2.620974) (xy 165.511355 -2.643141) (xy 165.5318 -2.651252) (xy 165.5318 -5.436616)
			(xy 165.509341 -5.43918) (xy 165.465775 -5.451225) (xy 165.425028 -5.470787) (xy 165.388385 -5.49725)
			(xy 165.357002 -5.529778) (xy 165.331869 -5.567345) (xy 165.313778 -5.608767) (xy 165.303302 -5.652736)
			(xy 165.300769 -5.697864) (xy 165.306261 -5.742729) (xy 165.319604 -5.785914) (xy 165.340377 -5.826058)
			(xy 165.353746 -5.844286) (xy 165.375159 -5.873096) (xy 165.411551 -5.934971) (xy 165.440095 -6.000836)
			(xy 165.460361 -6.0697) (xy 165.472045 -6.140526) (xy 165.474971 -6.212251) (xy 165.469095 -6.283794)
			(xy 165.454505 -6.354079) (xy 165.431421 -6.42205) (xy 165.40019 -6.486684) (xy 165.381178 -6.517132)
			(xy 165.369707 -6.535767) (xy 165.352645 -6.57606) (xy 165.342736 -6.618679) (xy 165.340272 -6.662366)
			(xy 165.345327 -6.705829) (xy 165.357751 -6.747784) (xy 165.377177 -6.786992) (xy 165.403031 -6.822293)
			(xy 165.434549 -6.852645) (xy 165.4708 -6.87715) (xy 165.510712 -6.895085) (xy 165.5318 -6.900926)
			(xy 165.5318 -9.65454) (xy 165.510272 -9.658061) (xy 165.468774 -9.671492) (xy 165.43018 -9.691813)
			(xy 165.395622 -9.718426) (xy 165.366116 -9.75055) (xy 165.34253 -9.78724) (xy 165.325556 -9.827419)
			(xy 165.315692 -9.869907) (xy 165.313229 -9.913455) (xy 165.318238 -9.956784) (xy 165.330573 -9.998621)
			(xy 165.349872 -10.037737) (xy 165.362382 -10.055606) (xy 165.381887 -10.083183) (xy 165.415119 -10.141993)
			(xy 165.441355 -10.20424) (xy 165.460245 -10.269094) (xy 165.471538 -10.335693) (xy 165.475084 -10.40315)
			(xy 165.470836 -10.470565) (xy 165.458849 -10.537043) (xy 165.439284 -10.601697) (xy 165.412401 -10.663667)
			(xy 165.39591 -10.693146) (xy 165.384692 -10.713587) (xy 165.369095 -10.757523) (xy 165.361768 -10.803566)
			(xy 165.362958 -10.850173) (xy 165.372623 -10.895782) (xy 165.39044 -10.938865) (xy 165.415812 -10.977979)
			(xy 165.447889 -11.011812) (xy 165.485596 -11.039231) (xy 165.5064 -11.049762) (xy 165.5064 -13.8938)
			(xy 165.3032 -13.8938) (xy 165.281587 -13.894235) (xy 165.238985 -13.901554) (xy 165.198236 -13.91598)
			(xy 165.160519 -13.937096) (xy 165.126922 -13.964294) (xy 165.098414 -13.996788) (xy 165.07582 -14.033639)
			(xy 165.059791 -14.073784) (xy 165.05079 -14.116063) (xy 165.049454 -14.13764) (xy 165.047805 -14.165808)
			(xy 165.037244 -14.221235) (xy 165.018636 -14.274502) (xy 164.992387 -14.324448) (xy 164.959069 -14.369984)
			(xy 164.919408 -14.410117) (xy 164.874269 -14.443972) (xy 164.824637 -14.47081) (xy 164.771594 -14.490047)
			(xy 164.716296 -14.501262) (xy 164.65995 -14.504212) (xy 164.603783 -14.498833) (xy 164.549021 -14.48524)
			(xy 164.496858 -14.463731) (xy 164.448431 -14.434775) (xy 164.404796 -14.399003) (xy 164.366905 -14.357195)
			(xy 164.335584 -14.310263) (xy 164.311515 -14.259231) (xy 164.295224 -14.20521) (xy 164.287066 -14.149379)
			(xy 164.287219 -14.092956) (xy 164.29101 -14.064996) (xy 164.292026 -14.059154) (xy 164.293804 -14.048486)
			(xy 164.296852 -14.0335) (xy 164.296852 -13.967968) (xy 164.222684 -13.8938) (xy 164.211 -13.8938)
			(xy 164.211 -11.070082) (xy 164.232616 -11.065563) (xy 164.273966 -11.050075) (xy 164.312015 -11.027669)
			(xy 164.345616 -10.999022) (xy 164.373757 -10.964996) (xy 164.39559 -10.926616) (xy 164.410457 -10.885038)
			(xy 164.41791 -10.841516) (xy 164.417726 -10.797361) (xy 164.409908 -10.753903) (xy 164.394693 -10.712452)
			(xy 164.383974 -10.693146) (xy 164.367455 -10.663679) (xy 164.340549 -10.601712) (xy 164.320967 -10.537057)
			(xy 164.30897 -10.470575) (xy 164.304717 -10.403153) (xy 164.308266 -10.33569) (xy 164.319569 -10.269086)
			(xy 164.338475 -10.20423) (xy 164.364732 -10.141985) (xy 164.397991 -10.083183) (xy 164.417502 -10.055606)
			(xy 164.430727 -10.036589) (xy 164.45077 -9.994835) (xy 164.462917 -9.950141) (xy 164.466765 -9.903985)
			(xy 164.462187 -9.857897) (xy 164.449335 -9.8134) (xy 164.428633 -9.771969) (xy 164.400767 -9.734974)
			(xy 164.36666 -9.70364) (xy 164.32744 -9.679004) (xy 164.284406 -9.661881) (xy 164.2618 -9.656826)
			(xy 164.2618 -6.896862) (xy 164.283883 -6.8893) (xy 164.325044 -6.8673) (xy 164.3615 -6.83816) (xy 164.392027 -6.802857)
			(xy 164.4156 -6.762577) (xy 164.431429 -6.718672) (xy 164.438981 -6.672615) (xy 164.438003 -6.625954)
			(xy 164.428528 -6.580255) (xy 164.410873 -6.537052) (xy 164.398706 -6.517132) (xy 164.379703 -6.486678)
			(xy 164.348458 -6.42205) (xy 164.325363 -6.354081) (xy 164.310766 -6.283796) (xy 164.304887 -6.212252)
			(xy 164.307814 -6.140527) (xy 164.319503 -6.0697) (xy 164.339778 -6.000838) (xy 164.368335 -5.934978)
			(xy 164.404742 -5.87311) (xy 164.426138 -5.844286) (xy 164.439796 -5.825671) (xy 164.460837 -5.784578)
			(xy 164.474109 -5.740361) (xy 164.479176 -5.694474) (xy 164.47587 -5.648427) (xy 164.464301 -5.603734)
			(xy 164.444849 -5.561866) (xy 164.418155 -5.524201) (xy 164.385096 -5.491977) (xy 164.34676 -5.466255)
			(xy 164.304408 -5.44788) (xy 164.259433 -5.437459) (xy 164.2364 -5.435854) (xy 164.2364 -2.655316)
			(xy 164.257814 -2.648027) (xy 164.297846 -2.626971) (xy 164.333519 -2.599162) (xy 164.363707 -2.565479)
			(xy 164.387457 -2.526984) (xy 164.404019 -2.484894) (xy 164.41287 -2.440537) (xy 164.413731 -2.395314)
			(xy 164.406574 -2.350652) (xy 164.391626 -2.307962) (xy 164.380926 -2.288032) (xy 164.364232 -2.257432)
			(xy 164.33742 -2.193087) (xy 164.318439 -2.126012) (xy 164.307559 -2.057158) (xy 164.305742 -2.022348)
			(xy 164.304474 -2.000731) (xy 164.295501 -1.95837) (xy 164.279477 -1.918144) (xy 164.256867 -1.881215)
			(xy 164.228323 -1.848654) (xy 164.194674 -1.821403) (xy 164.156892 -1.80025) (xy 164.116071 -1.785808)
			(xy 164.073393 -1.778495) (xy 164.051742 -1.778) (xy 158.9532 -1.778) (xy 157.641544 -3.089656) (xy 157.636464 -3.186684)
			(xy 157.666944 -3.22453) (xy 157.713109 -3.282682) (xy 157.799997 -3.403103) (xy 157.880455 -3.527911)
			(xy 157.954264 -3.656764) (xy 158.021219 -3.789307) (xy 158.081138 -3.925176) (xy 158.133855 -4.063998)
			(xy 158.179225 -4.205392) (xy 158.217125 -4.348968) (xy 158.24745 -4.494333) (xy 158.270116 -4.641088)
			(xy 158.285062 -4.788829) (xy 158.292246 -4.937149) (xy 158.291648 -5.085643) (xy 158.283271 -5.233901)
			(xy 158.267137 -5.381516) (xy 158.24329 -5.528084) (xy 158.211796 -5.6732) (xy 158.172742 -5.816467)
			(xy 158.126235 -5.957491) (xy 158.072403 -6.095885) (xy 158.011393 -6.231267) (xy 157.943373 -6.363267)
			(xy 157.86853 -6.491521) (xy 157.787069 -6.615678) (xy 157.699216 -6.735396) (xy 157.60521 -6.850346)
			(xy 157.50531 -6.960212) (xy 157.39979 -7.064693) (xy 157.288941 -7.163502) (xy 157.173067 -7.256367)
			(xy 157.052486 -7.343033) (xy 156.92753 -7.423261) (xy 156.863288 -7.460488) (xy 156.833824 -7.477252)
			(xy 156.7688 -7.587996) (xy 156.7688 -8.041894) (xy 156.833824 -8.152638) (xy 156.863288 -8.169402)
			(xy 156.927789 -8.206752) (xy 157.053211 -8.287315) (xy 157.174221 -8.374363) (xy 157.290485 -8.467655)
			(xy 157.401682 -8.566934) (xy 157.507502 -8.671924) (xy 157.607654 -8.782335) (xy 157.701859 -8.89786)
			(xy 157.789858 -9.018181) (xy 157.871407 -9.142963) (xy 157.946279 -9.271863) (xy 158.014267 -9.404522)
			(xy 158.075184 -9.540573) (xy 158.128861 -9.67964) (xy 158.175148 -9.821339) (xy 158.213919 -9.965275)
			(xy 158.245064 -10.111052) (xy 158.2685 -10.258265) (xy 158.284159 -10.406506) (xy 158.292 -10.555367)
			(xy 158.292 -10.704433) (xy 158.284159 -10.853294) (xy 158.2685 -11.001535) (xy 158.245064 -11.148748)
			(xy 158.213919 -11.294525) (xy 158.175148 -11.438461) (xy 158.128861 -11.58016) (xy 158.075184 -11.719227)
			(xy 158.014267 -11.855278) (xy 157.946279 -11.987937) (xy 157.871407 -12.116837) (xy 157.789858 -12.241619)
			(xy 157.701859 -12.36194) (xy 157.607654 -12.477465) (xy 157.507502 -12.587876) (xy 157.401682 -12.692866)
			(xy 157.290485 -12.792145) (xy 157.174221 -12.885437) (xy 157.053211 -12.972485) (xy 156.927789 -13.053048)
			(xy 156.863288 -13.090398) (xy 156.833824 -13.107162) (xy 156.7688 -13.217906) (xy 156.7688 -14.445996)
			(xy 156.769345 -14.463451) (xy 156.778802 -14.497055) (xy 156.797008 -14.526841) (xy 156.822602 -14.550582)
			(xy 156.837888 -14.559026) (xy 156.906349 -14.594637) (xy 157.03995 -14.671901) (xy 157.169434 -14.755882)
			(xy 157.294465 -14.84636) (xy 157.414717 -14.9431) (xy 157.47817 -14.999716) (xy 311.607711 -14.999716)
			(xy 311.611746 -14.924012) (xy 311.623805 -14.849167) (xy 311.643751 -14.776026) (xy 311.671358 -14.705421)
			(xy 311.706314 -14.63815) (xy 311.748222 -14.574975) (xy 311.796608 -14.516613) (xy 311.850924 -14.463725)
			(xy 311.910553 -14.41691) (xy 311.974821 -14.376698) (xy 312.042998 -14.343546) (xy 312.114314 -14.317828)
			(xy 312.187959 -14.299836) (xy 312.263099 -14.289774) (xy 312.338883 -14.287755) (xy 312.414453 -14.293804)
			(xy 312.488951 -14.307851) (xy 312.561534 -14.329737) (xy 312.63138 -14.359214) (xy 312.697697 -14.395949)
			(xy 312.759733 -14.439524) (xy 312.816786 -14.489446) (xy 312.86821 -14.54515) (xy 312.913421 -14.606005)
			(xy 312.951908 -14.67132) (xy 312.983234 -14.740356) (xy 313.007044 -14.812331) (xy 313.023069 -14.886429)
			(xy 313.031128 -14.96181) (xy 313.031632 -14.999716) (xy 313.607707 -14.999716) (xy 313.611742 -14.924012)
			(xy 313.623801 -14.849167) (xy 313.643747 -14.776026) (xy 313.671354 -14.705421) (xy 313.70631 -14.63815)
			(xy 313.748218 -14.574975) (xy 313.796604 -14.516613) (xy 313.85092 -14.463725) (xy 313.910549 -14.41691)
			(xy 313.974817 -14.376698) (xy 314.042994 -14.343546) (xy 314.11431 -14.317828) (xy 314.187955 -14.299836)
			(xy 314.263095 -14.289774) (xy 314.338879 -14.287755) (xy 314.414449 -14.293804) (xy 314.488947 -14.307851)
			(xy 314.56153 -14.329737) (xy 314.631376 -14.359214) (xy 314.697693 -14.395949) (xy 314.759729 -14.439524)
			(xy 314.816782 -14.489446) (xy 314.868206 -14.54515) (xy 314.913417 -14.606005) (xy 314.951904 -14.67132)
			(xy 314.98323 -14.740356) (xy 315.00704 -14.812331) (xy 315.023065 -14.886429) (xy 315.031124 -14.96181)
			(xy 315.031628 -14.999716) (xy 315.031124 -15.037622) (xy 315.023065 -15.113003) (xy 315.00704 -15.187101)
			(xy 314.98323 -15.259076) (xy 314.951904 -15.328112) (xy 314.913417 -15.393427) (xy 314.868206 -15.454282)
			(xy 314.816782 -15.509986) (xy 314.759729 -15.559908) (xy 314.697693 -15.603483) (xy 314.631376 -15.640218)
			(xy 314.56153 -15.669695) (xy 314.488947 -15.691581) (xy 314.414449 -15.705628) (xy 314.338879 -15.711677)
			(xy 314.263095 -15.709658) (xy 314.187955 -15.699596) (xy 314.11431 -15.681604) (xy 314.042994 -15.655886)
			(xy 313.974817 -15.622734) (xy 313.910549 -15.582522) (xy 313.85092 -15.535707) (xy 313.796604 -15.482819)
			(xy 313.748218 -15.424457) (xy 313.70631 -15.361282) (xy 313.671354 -15.294011) (xy 313.643747 -15.223406)
			(xy 313.623801 -15.150265) (xy 313.611742 -15.07542) (xy 313.607707 -14.999716) (xy 313.031632 -14.999716)
			(xy 313.031128 -15.037622) (xy 313.023069 -15.113003) (xy 313.007044 -15.187101) (xy 312.983234 -15.259076)
			(xy 312.951908 -15.328112) (xy 312.913421 -15.393427) (xy 312.86821 -15.454282) (xy 312.816786 -15.509986)
			(xy 312.759733 -15.559908) (xy 312.697697 -15.603483) (xy 312.63138 -15.640218) (xy 312.561534 -15.669695)
			(xy 312.488951 -15.691581) (xy 312.414453 -15.705628) (xy 312.338883 -15.711677) (xy 312.263099 -15.709658)
			(xy 312.187959 -15.699596) (xy 312.114314 -15.681604) (xy 312.042998 -15.655886) (xy 311.974821 -15.622734)
			(xy 311.910553 -15.582522) (xy 311.850924 -15.535707) (xy 311.796608 -15.482819) (xy 311.748222 -15.424457)
			(xy 311.706314 -15.361282) (xy 311.671358 -15.294011) (xy 311.643751 -15.223406) (xy 311.623805 -15.150265)
			(xy 311.611746 -15.07542) (xy 311.607711 -14.999716) (xy 157.47817 -14.999716) (xy 157.529875 -15.04585)
			(xy 157.639641 -15.154342) (xy 157.743728 -15.268293) (xy 157.841865 -15.387407) (xy 157.933796 -15.511374)
			(xy 158.019282 -15.639869) (xy 158.0981 -15.77256) (xy 158.170045 -15.909099) (xy 158.23493 -16.049131)
			(xy 158.292584 -16.192292) (xy 158.342859 -16.338208) (xy 158.36606 -16.418661) (xy 284.073592 -16.418661)
			(xy 284.073592 -16.347339) (xy 284.081578 -16.276465) (xy 284.097448 -16.20693) (xy 284.121005 -16.13961)
			(xy 284.15195 -16.075351) (xy 284.189896 -16.01496) (xy 284.234365 -15.959198) (xy 284.284798 -15.908765)
			(xy 284.34056 -15.864296) (xy 284.400951 -15.82635) (xy 284.46521 -15.795405) (xy 284.53253 -15.771848)
			(xy 284.602065 -15.755978) (xy 284.672939 -15.747992) (xy 284.744261 -15.747992) (xy 284.815135 -15.755978)
			(xy 284.88467 -15.771848) (xy 284.95199 -15.795405) (xy 285.016249 -15.82635) (xy 285.07664 -15.864296)
			(xy 285.132402 -15.908765) (xy 285.182835 -15.959198) (xy 285.227304 -16.01496) (xy 285.26525 -16.075351)
			(xy 285.296195 -16.13961) (xy 285.319752 -16.20693) (xy 285.335622 -16.276465) (xy 285.343608 -16.347339)
			(xy 285.344108 -16.383) (xy 285.343608 -16.418661) (xy 290.728392 -16.418661) (xy 290.728392 -16.347339)
			(xy 290.736378 -16.276465) (xy 290.752248 -16.20693) (xy 290.775805 -16.13961) (xy 290.80675 -16.075351)
			(xy 290.844696 -16.01496) (xy 290.889165 -15.959198) (xy 290.939598 -15.908765) (xy 290.99536 -15.864296)
			(xy 291.055751 -15.82635) (xy 291.12001 -15.795405) (xy 291.18733 -15.771848) (xy 291.256865 -15.755978)
			(xy 291.327739 -15.747992) (xy 291.399061 -15.747992) (xy 291.469935 -15.755978) (xy 291.53947 -15.771848)
			(xy 291.60679 -15.795405) (xy 291.671049 -15.82635) (xy 291.73144 -15.864296) (xy 291.787202 -15.908765)
			(xy 291.837635 -15.959198) (xy 291.882104 -16.01496) (xy 291.92005 -16.075351) (xy 291.950995 -16.13961)
			(xy 291.974552 -16.20693) (xy 291.990422 -16.276465) (xy 291.998408 -16.347339) (xy 291.998908 -16.383)
			(xy 291.998408 -16.418661) (xy 291.990422 -16.489535) (xy 291.974552 -16.55907) (xy 291.950995 -16.62639)
			(xy 291.92005 -16.690649) (xy 291.882104 -16.75104) (xy 291.837635 -16.806802) (xy 291.787202 -16.857235)
			(xy 291.73144 -16.901704) (xy 291.671049 -16.93965) (xy 291.60679 -16.970595) (xy 291.53947 -16.994152)
			(xy 291.469935 -17.010022) (xy 291.399061 -17.018008) (xy 291.327739 -17.018008) (xy 291.256865 -17.010022)
			(xy 291.18733 -16.994152) (xy 291.12001 -16.970595) (xy 291.055751 -16.93965) (xy 290.99536 -16.901704)
			(xy 290.939598 -16.857235) (xy 290.889165 -16.806802) (xy 290.844696 -16.75104) (xy 290.80675 -16.690649)
			(xy 290.775805 -16.62639) (xy 290.752248 -16.55907) (xy 290.736378 -16.489535) (xy 290.728392 -16.418661)
			(xy 285.343608 -16.418661) (xy 285.335622 -16.489535) (xy 285.319752 -16.55907) (xy 285.296195 -16.62639)
			(xy 285.26525 -16.690649) (xy 285.227304 -16.75104) (xy 285.182835 -16.806802) (xy 285.132402 -16.857235)
			(xy 285.07664 -16.901704) (xy 285.016249 -16.93965) (xy 284.95199 -16.970595) (xy 284.88467 -16.994152)
			(xy 284.815135 -17.010022) (xy 284.744261 -17.018008) (xy 284.672939 -17.018008) (xy 284.602065 -17.010022)
			(xy 284.53253 -16.994152) (xy 284.46521 -16.970595) (xy 284.400951 -16.93965) (xy 284.34056 -16.901704)
			(xy 284.284798 -16.857235) (xy 284.234365 -16.806802) (xy 284.189896 -16.75104) (xy 284.15195 -16.690649)
			(xy 284.121005 -16.62639) (xy 284.097448 -16.55907) (xy 284.081578 -16.489535) (xy 284.073592 -16.418661)
			(xy 158.36606 -16.418661) (xy 158.385623 -16.486499) (xy 158.420764 -16.636779) (xy 158.448192 -16.788656)
			(xy 158.467834 -16.941735) (xy 158.47964 -17.095617) (xy 158.483579 -17.249901) (xy 158.47964 -17.404185)
			(xy 158.467834 -17.558067) (xy 158.448192 -17.711146) (xy 158.420764 -17.863023) (xy 158.385622 -18.013303)
			(xy 158.342858 -18.161594) (xy 158.292583 -18.30751) (xy 158.234929 -18.450671) (xy 158.170044 -18.590703)
			(xy 158.115404 -18.6944) (xy 167.0304 -18.6944) (xy 167.0304 -18.3388) (xy 167.259 -18.1102) (xy 168.91 -18.1102)
			(xy 169.164 -18.3642) (xy 169.164 -18.6944) (xy 191.8716 -18.6944) (xy 191.8716 -18.3134) (xy 192.1002 -18.0848)
			(xy 193.7004 -18.0848) (xy 193.929 -18.3134) (xy 193.929 -18.669) (xy 193.675 -18.923) (xy 192.1002 -18.923)
			(xy 191.8716 -18.6944) (xy 169.164 -18.6944) (xy 168.91 -18.9484) (xy 167.2844 -18.9484) (xy 167.0304 -18.6944)
			(xy 158.115404 -18.6944) (xy 158.098099 -18.727242) (xy 158.019281 -18.859932) (xy 157.933795 -18.988428)
			(xy 157.841864 -19.112394) (xy 157.743727 -19.231508) (xy 157.63964 -19.34546) (xy 157.529874 -19.453952)
			(xy 157.414715 -19.556701) (xy 157.294464 -19.653441) (xy 157.169433 -19.743919) (xy 157.039948 -19.8279)
			(xy 156.906347 -19.905164) (xy 156.837888 -19.940778) (xy 156.822603 -19.949223) (xy 156.79701 -19.972964)
			(xy 156.778805 -20.00275) (xy 156.76935 -20.036354) (xy 156.7688 -20.053808) (xy 156.7688 -21.614892)
			(xy 157.160569 -22.006661) (xy 205.028792 -22.006661) (xy 205.028792 -21.935339) (xy 205.036778 -21.864465)
			(xy 205.052648 -21.79493) (xy 205.076205 -21.72761) (xy 205.10715 -21.663351) (xy 205.145096 -21.60296)
			(xy 205.189565 -21.547198) (xy 205.239998 -21.496765) (xy 205.29576 -21.452296) (xy 205.356151 -21.41435)
			(xy 205.42041 -21.383405) (xy 205.48773 -21.359848) (xy 205.557265 -21.343978) (xy 205.628139 -21.335992)
			(xy 205.699461 -21.335992) (xy 205.770335 -21.343978) (xy 205.83987 -21.359848) (xy 205.90719 -21.383405)
			(xy 205.971449 -21.41435) (xy 206.03184 -21.452296) (xy 206.087602 -21.496765) (xy 206.138035 -21.547198)
			(xy 206.182504 -21.60296) (xy 206.22045 -21.663351) (xy 206.251395 -21.72761) (xy 206.274952 -21.79493)
			(xy 206.290822 -21.864465) (xy 206.298808 -21.935339) (xy 206.299308 -21.971) (xy 206.298808 -22.006661)
			(xy 212.648792 -22.006661) (xy 212.648792 -21.935339) (xy 212.656778 -21.864465) (xy 212.672648 -21.79493)
			(xy 212.696205 -21.72761) (xy 212.72715 -21.663351) (xy 212.765096 -21.60296) (xy 212.809565 -21.547198)
			(xy 212.859998 -21.496765) (xy 212.91576 -21.452296) (xy 212.976151 -21.41435) (xy 213.04041 -21.383405)
			(xy 213.10773 -21.359848) (xy 213.177265 -21.343978) (xy 213.248139 -21.335992) (xy 213.319461 -21.335992)
			(xy 213.390335 -21.343978) (xy 213.45987 -21.359848) (xy 213.52719 -21.383405) (xy 213.591449 -21.41435)
			(xy 213.65184 -21.452296) (xy 213.707602 -21.496765) (xy 213.758035 -21.547198) (xy 213.802504 -21.60296)
			(xy 213.84045 -21.663351) (xy 213.871395 -21.72761) (xy 213.894952 -21.79493) (xy 213.910822 -21.864465)
			(xy 213.918808 -21.935339) (xy 213.919308 -21.971) (xy 213.918808 -22.006661) (xy 220.268792 -22.006661)
			(xy 220.268792 -21.935339) (xy 220.276778 -21.864465) (xy 220.292648 -21.79493) (xy 220.316205 -21.72761)
			(xy 220.34715 -21.663351) (xy 220.385096 -21.60296) (xy 220.429565 -21.547198) (xy 220.479998 -21.496765)
			(xy 220.53576 -21.452296) (xy 220.596151 -21.41435) (xy 220.66041 -21.383405) (xy 220.72773 -21.359848)
			(xy 220.797265 -21.343978) (xy 220.868139 -21.335992) (xy 220.939461 -21.335992) (xy 221.010335 -21.343978)
			(xy 221.07987 -21.359848) (xy 221.14719 -21.383405) (xy 221.211449 -21.41435) (xy 221.27184 -21.452296)
			(xy 221.327602 -21.496765) (xy 221.378035 -21.547198) (xy 221.422504 -21.60296) (xy 221.46045 -21.663351)
			(xy 221.491395 -21.72761) (xy 221.514952 -21.79493) (xy 221.530822 -21.864465) (xy 221.538808 -21.935339)
			(xy 221.539308 -21.971) (xy 221.538808 -22.006661) (xy 227.888792 -22.006661) (xy 227.888792 -21.935339)
			(xy 227.896778 -21.864465) (xy 227.912648 -21.79493) (xy 227.936205 -21.72761) (xy 227.96715 -21.663351)
			(xy 228.005096 -21.60296) (xy 228.049565 -21.547198) (xy 228.099998 -21.496765) (xy 228.15576 -21.452296)
			(xy 228.216151 -21.41435) (xy 228.28041 -21.383405) (xy 228.34773 -21.359848) (xy 228.417265 -21.343978)
			(xy 228.488139 -21.335992) (xy 228.559461 -21.335992) (xy 228.630335 -21.343978) (xy 228.69987 -21.359848)
			(xy 228.76719 -21.383405) (xy 228.831449 -21.41435) (xy 228.89184 -21.452296) (xy 228.947602 -21.496765)
			(xy 228.998035 -21.547198) (xy 229.042504 -21.60296) (xy 229.08045 -21.663351) (xy 229.111395 -21.72761)
			(xy 229.134952 -21.79493) (xy 229.150822 -21.864465) (xy 229.158808 -21.935339) (xy 229.159308 -21.971)
			(xy 229.158808 -22.006661) (xy 235.508792 -22.006661) (xy 235.508792 -21.935339) (xy 235.516778 -21.864465)
			(xy 235.532648 -21.79493) (xy 235.556205 -21.72761) (xy 235.58715 -21.663351) (xy 235.625096 -21.60296)
			(xy 235.669565 -21.547198) (xy 235.719998 -21.496765) (xy 235.77576 -21.452296) (xy 235.836151 -21.41435)
			(xy 235.90041 -21.383405) (xy 235.96773 -21.359848) (xy 236.037265 -21.343978) (xy 236.108139 -21.335992)
			(xy 236.179461 -21.335992) (xy 236.250335 -21.343978) (xy 236.31987 -21.359848) (xy 236.38719 -21.383405)
			(xy 236.451449 -21.41435) (xy 236.51184 -21.452296) (xy 236.567602 -21.496765) (xy 236.618035 -21.547198)
			(xy 236.662504 -21.60296) (xy 236.70045 -21.663351) (xy 236.731395 -21.72761) (xy 236.754952 -21.79493)
			(xy 236.770822 -21.864465) (xy 236.778808 -21.935339) (xy 236.779308 -21.971) (xy 236.778808 -22.006661)
			(xy 243.128792 -22.006661) (xy 243.128792 -21.935339) (xy 243.136778 -21.864465) (xy 243.152648 -21.79493)
			(xy 243.176205 -21.72761) (xy 243.20715 -21.663351) (xy 243.245096 -21.60296) (xy 243.289565 -21.547198)
			(xy 243.339998 -21.496765) (xy 243.39576 -21.452296) (xy 243.456151 -21.41435) (xy 243.52041 -21.383405)
			(xy 243.58773 -21.359848) (xy 243.657265 -21.343978) (xy 243.728139 -21.335992) (xy 243.799461 -21.335992)
			(xy 243.870335 -21.343978) (xy 243.93987 -21.359848) (xy 244.00719 -21.383405) (xy 244.071449 -21.41435)
			(xy 244.13184 -21.452296) (xy 244.187602 -21.496765) (xy 244.238035 -21.547198) (xy 244.282504 -21.60296)
			(xy 244.32045 -21.663351) (xy 244.351395 -21.72761) (xy 244.374952 -21.79493) (xy 244.390822 -21.864465)
			(xy 244.398808 -21.935339) (xy 244.399308 -21.971) (xy 244.398808 -22.006661) (xy 250.748792 -22.006661)
			(xy 250.748792 -21.935339) (xy 250.756778 -21.864465) (xy 250.772648 -21.79493) (xy 250.796205 -21.72761)
			(xy 250.82715 -21.663351) (xy 250.865096 -21.60296) (xy 250.909565 -21.547198) (xy 250.959998 -21.496765)
			(xy 251.01576 -21.452296) (xy 251.076151 -21.41435) (xy 251.14041 -21.383405) (xy 251.20773 -21.359848)
			(xy 251.277265 -21.343978) (xy 251.348139 -21.335992) (xy 251.419461 -21.335992) (xy 251.490335 -21.343978)
			(xy 251.55987 -21.359848) (xy 251.62719 -21.383405) (xy 251.655547 -21.397061) (xy 261.467592 -21.397061)
			(xy 261.467592 -21.325739) (xy 261.475578 -21.254865) (xy 261.491448 -21.18533) (xy 261.515005 -21.11801)
			(xy 261.54595 -21.053751) (xy 261.583896 -20.99336) (xy 261.628365 -20.937598) (xy 261.678798 -20.887165)
			(xy 261.73456 -20.842696) (xy 261.794951 -20.80475) (xy 261.85921 -20.773805) (xy 261.92653 -20.750248)
			(xy 261.996065 -20.734378) (xy 262.066939 -20.726392) (xy 262.138261 -20.726392) (xy 262.209135 -20.734378)
			(xy 262.27867 -20.750248) (xy 262.34599 -20.773805) (xy 262.410249 -20.80475) (xy 262.47064 -20.842696)
			(xy 262.526402 -20.887165) (xy 262.576835 -20.937598) (xy 262.621304 -20.99336) (xy 262.65925 -21.053751)
			(xy 262.690195 -21.11801) (xy 262.713752 -21.18533) (xy 262.729622 -21.254865) (xy 262.737608 -21.325739)
			(xy 262.738108 -21.3614) (xy 262.737608 -21.397061) (xy 269.087592 -21.397061) (xy 269.087592 -21.325739)
			(xy 269.095578 -21.254865) (xy 269.111448 -21.18533) (xy 269.135005 -21.11801) (xy 269.16595 -21.053751)
			(xy 269.203896 -20.99336) (xy 269.248365 -20.937598) (xy 269.298798 -20.887165) (xy 269.35456 -20.842696)
			(xy 269.414951 -20.80475) (xy 269.47921 -20.773805) (xy 269.54653 -20.750248) (xy 269.616065 -20.734378)
			(xy 269.686939 -20.726392) (xy 269.758261 -20.726392) (xy 269.829135 -20.734378) (xy 269.89867 -20.750248)
			(xy 269.96599 -20.773805) (xy 270.030249 -20.80475) (xy 270.09064 -20.842696) (xy 270.146402 -20.887165)
			(xy 270.196835 -20.937598) (xy 270.241304 -20.99336) (xy 270.27925 -21.053751) (xy 270.310195 -21.11801)
			(xy 270.333752 -21.18533) (xy 270.349622 -21.254865) (xy 270.357608 -21.325739) (xy 270.358108 -21.3614)
			(xy 270.357608 -21.397061) (xy 276.707592 -21.397061) (xy 276.707592 -21.325739) (xy 276.715578 -21.254865)
			(xy 276.731448 -21.18533) (xy 276.755005 -21.11801) (xy 276.78595 -21.053751) (xy 276.823896 -20.99336)
			(xy 276.868365 -20.937598) (xy 276.918798 -20.887165) (xy 276.97456 -20.842696) (xy 277.034951 -20.80475)
			(xy 277.09921 -20.773805) (xy 277.16653 -20.750248) (xy 277.236065 -20.734378) (xy 277.306939 -20.726392)
			(xy 277.378261 -20.726392) (xy 277.449135 -20.734378) (xy 277.51867 -20.750248) (xy 277.58599 -20.773805)
			(xy 277.650249 -20.80475) (xy 277.71064 -20.842696) (xy 277.766402 -20.887165) (xy 277.816835 -20.937598)
			(xy 277.861304 -20.99336) (xy 277.89925 -21.053751) (xy 277.930195 -21.11801) (xy 277.953752 -21.18533)
			(xy 277.969622 -21.254865) (xy 277.977608 -21.325739) (xy 277.978108 -21.3614) (xy 277.977608 -21.397061)
			(xy 284.327592 -21.397061) (xy 284.327592 -21.325739) (xy 284.335578 -21.254865) (xy 284.351448 -21.18533)
			(xy 284.375005 -21.11801) (xy 284.40595 -21.053751) (xy 284.443896 -20.99336) (xy 284.488365 -20.937598)
			(xy 284.538798 -20.887165) (xy 284.59456 -20.842696) (xy 284.654951 -20.80475) (xy 284.71921 -20.773805)
			(xy 284.78653 -20.750248) (xy 284.856065 -20.734378) (xy 284.926939 -20.726392) (xy 284.998261 -20.726392)
			(xy 285.069135 -20.734378) (xy 285.13867 -20.750248) (xy 285.20599 -20.773805) (xy 285.270249 -20.80475)
			(xy 285.33064 -20.842696) (xy 285.386402 -20.887165) (xy 285.436835 -20.937598) (xy 285.481304 -20.99336)
			(xy 285.51925 -21.053751) (xy 285.550195 -21.11801) (xy 285.573752 -21.18533) (xy 285.589622 -21.254865)
			(xy 285.597608 -21.325739) (xy 285.598108 -21.3614) (xy 285.597608 -21.397061) (xy 291.947592 -21.397061)
			(xy 291.947592 -21.325739) (xy 291.955578 -21.254865) (xy 291.971448 -21.18533) (xy 291.995005 -21.11801)
			(xy 292.02595 -21.053751) (xy 292.063896 -20.99336) (xy 292.108365 -20.937598) (xy 292.158798 -20.887165)
			(xy 292.21456 -20.842696) (xy 292.274951 -20.80475) (xy 292.33921 -20.773805) (xy 292.40653 -20.750248)
			(xy 292.476065 -20.734378) (xy 292.546939 -20.726392) (xy 292.618261 -20.726392) (xy 292.689135 -20.734378)
			(xy 292.75867 -20.750248) (xy 292.82599 -20.773805) (xy 292.890249 -20.80475) (xy 292.95064 -20.842696)
			(xy 293.006402 -20.887165) (xy 293.056835 -20.937598) (xy 293.101304 -20.99336) (xy 293.13925 -21.053751)
			(xy 293.170195 -21.11801) (xy 293.193752 -21.18533) (xy 293.209622 -21.254865) (xy 293.217608 -21.325739)
			(xy 293.218108 -21.3614) (xy 293.217608 -21.397061) (xy 293.209622 -21.467935) (xy 293.193752 -21.53747)
			(xy 293.170195 -21.60479) (xy 293.13925 -21.669049) (xy 293.101304 -21.72944) (xy 293.056835 -21.785202)
			(xy 293.006402 -21.835635) (xy 292.95064 -21.880104) (xy 292.890249 -21.91805) (xy 292.82599 -21.948995)
			(xy 292.75867 -21.972552) (xy 292.689135 -21.988422) (xy 292.618261 -21.996408) (xy 292.546939 -21.996408)
			(xy 292.476065 -21.988422) (xy 292.40653 -21.972552) (xy 292.33921 -21.948995) (xy 292.274951 -21.91805)
			(xy 292.21456 -21.880104) (xy 292.158798 -21.835635) (xy 292.108365 -21.785202) (xy 292.063896 -21.72944)
			(xy 292.02595 -21.669049) (xy 291.995005 -21.60479) (xy 291.971448 -21.53747) (xy 291.955578 -21.467935)
			(xy 291.947592 -21.397061) (xy 285.597608 -21.397061) (xy 285.589622 -21.467935) (xy 285.573752 -21.53747)
			(xy 285.550195 -21.60479) (xy 285.51925 -21.669049) (xy 285.481304 -21.72944) (xy 285.436835 -21.785202)
			(xy 285.386402 -21.835635) (xy 285.33064 -21.880104) (xy 285.270249 -21.91805) (xy 285.20599 -21.948995)
			(xy 285.13867 -21.972552) (xy 285.069135 -21.988422) (xy 284.998261 -21.996408) (xy 284.926939 -21.996408)
			(xy 284.856065 -21.988422) (xy 284.78653 -21.972552) (xy 284.71921 -21.948995) (xy 284.654951 -21.91805)
			(xy 284.59456 -21.880104) (xy 284.538798 -21.835635) (xy 284.488365 -21.785202) (xy 284.443896 -21.72944)
			(xy 284.40595 -21.669049) (xy 284.375005 -21.60479) (xy 284.351448 -21.53747) (xy 284.335578 -21.467935)
			(xy 284.327592 -21.397061) (xy 277.977608 -21.397061) (xy 277.969622 -21.467935) (xy 277.953752 -21.53747)
			(xy 277.930195 -21.60479) (xy 277.89925 -21.669049) (xy 277.861304 -21.72944) (xy 277.816835 -21.785202)
			(xy 277.766402 -21.835635) (xy 277.71064 -21.880104) (xy 277.650249 -21.91805) (xy 277.58599 -21.948995)
			(xy 277.51867 -21.972552) (xy 277.449135 -21.988422) (xy 277.378261 -21.996408) (xy 277.306939 -21.996408)
			(xy 277.236065 -21.988422) (xy 277.16653 -21.972552) (xy 277.09921 -21.948995) (xy 277.034951 -21.91805)
			(xy 276.97456 -21.880104) (xy 276.918798 -21.835635) (xy 276.868365 -21.785202) (xy 276.823896 -21.72944)
			(xy 276.78595 -21.669049) (xy 276.755005 -21.60479) (xy 276.731448 -21.53747) (xy 276.715578 -21.467935)
			(xy 276.707592 -21.397061) (xy 270.357608 -21.397061) (xy 270.349622 -21.467935) (xy 270.333752 -21.53747)
			(xy 270.310195 -21.60479) (xy 270.27925 -21.669049) (xy 270.241304 -21.72944) (xy 270.196835 -21.785202)
			(xy 270.146402 -21.835635) (xy 270.09064 -21.880104) (xy 270.030249 -21.91805) (xy 269.96599 -21.948995)
			(xy 269.89867 -21.972552) (xy 269.829135 -21.988422) (xy 269.758261 -21.996408) (xy 269.686939 -21.996408)
			(xy 269.616065 -21.988422) (xy 269.54653 -21.972552) (xy 269.47921 -21.948995) (xy 269.414951 -21.91805)
			(xy 269.35456 -21.880104) (xy 269.298798 -21.835635) (xy 269.248365 -21.785202) (xy 269.203896 -21.72944)
			(xy 269.16595 -21.669049) (xy 269.135005 -21.60479) (xy 269.111448 -21.53747) (xy 269.095578 -21.467935)
			(xy 269.087592 -21.397061) (xy 262.737608 -21.397061) (xy 262.729622 -21.467935) (xy 262.713752 -21.53747)
			(xy 262.690195 -21.60479) (xy 262.65925 -21.669049) (xy 262.621304 -21.72944) (xy 262.576835 -21.785202)
			(xy 262.526402 -21.835635) (xy 262.47064 -21.880104) (xy 262.410249 -21.91805) (xy 262.34599 -21.948995)
			(xy 262.27867 -21.972552) (xy 262.209135 -21.988422) (xy 262.138261 -21.996408) (xy 262.066939 -21.996408)
			(xy 261.996065 -21.988422) (xy 261.92653 -21.972552) (xy 261.85921 -21.948995) (xy 261.794951 -21.91805)
			(xy 261.73456 -21.880104) (xy 261.678798 -21.835635) (xy 261.628365 -21.785202) (xy 261.583896 -21.72944)
			(xy 261.54595 -21.669049) (xy 261.515005 -21.60479) (xy 261.491448 -21.53747) (xy 261.475578 -21.467935)
			(xy 261.467592 -21.397061) (xy 251.655547 -21.397061) (xy 251.691449 -21.41435) (xy 251.75184 -21.452296)
			(xy 251.807602 -21.496765) (xy 251.858035 -21.547198) (xy 251.902504 -21.60296) (xy 251.94045 -21.663351)
			(xy 251.971395 -21.72761) (xy 251.994952 -21.79493) (xy 252.010822 -21.864465) (xy 252.018808 -21.935339)
			(xy 252.019308 -21.971) (xy 252.018808 -22.006661) (xy 252.010822 -22.077535) (xy 251.994952 -22.14707)
			(xy 251.971395 -22.21439) (xy 251.94045 -22.278649) (xy 251.902504 -22.33904) (xy 251.858035 -22.394802)
			(xy 251.807602 -22.445235) (xy 251.75184 -22.489704) (xy 251.691449 -22.52765) (xy 251.62719 -22.558595)
			(xy 251.55987 -22.582152) (xy 251.490335 -22.598022) (xy 251.419461 -22.606008) (xy 251.348139 -22.606008)
			(xy 251.277265 -22.598022) (xy 251.20773 -22.582152) (xy 251.14041 -22.558595) (xy 251.076151 -22.52765)
			(xy 251.01576 -22.489704) (xy 250.959998 -22.445235) (xy 250.909565 -22.394802) (xy 250.865096 -22.33904)
			(xy 250.82715 -22.278649) (xy 250.796205 -22.21439) (xy 250.772648 -22.14707) (xy 250.756778 -22.077535)
			(xy 250.748792 -22.006661) (xy 244.398808 -22.006661) (xy 244.390822 -22.077535) (xy 244.374952 -22.14707)
			(xy 244.351395 -22.21439) (xy 244.32045 -22.278649) (xy 244.282504 -22.33904) (xy 244.238035 -22.394802)
			(xy 244.187602 -22.445235) (xy 244.13184 -22.489704) (xy 244.071449 -22.52765) (xy 244.00719 -22.558595)
			(xy 243.93987 -22.582152) (xy 243.870335 -22.598022) (xy 243.799461 -22.606008) (xy 243.728139 -22.606008)
			(xy 243.657265 -22.598022) (xy 243.58773 -22.582152) (xy 243.52041 -22.558595) (xy 243.456151 -22.52765)
			(xy 243.39576 -22.489704) (xy 243.339998 -22.445235) (xy 243.289565 -22.394802) (xy 243.245096 -22.33904)
			(xy 243.20715 -22.278649) (xy 243.176205 -22.21439) (xy 243.152648 -22.14707) (xy 243.136778 -22.077535)
			(xy 243.128792 -22.006661) (xy 236.778808 -22.006661) (xy 236.770822 -22.077535) (xy 236.754952 -22.14707)
			(xy 236.731395 -22.21439) (xy 236.70045 -22.278649) (xy 236.662504 -22.33904) (xy 236.618035 -22.394802)
			(xy 236.567602 -22.445235) (xy 236.51184 -22.489704) (xy 236.451449 -22.52765) (xy 236.38719 -22.558595)
			(xy 236.31987 -22.582152) (xy 236.250335 -22.598022) (xy 236.179461 -22.606008) (xy 236.108139 -22.606008)
			(xy 236.037265 -22.598022) (xy 235.96773 -22.582152) (xy 235.90041 -22.558595) (xy 235.836151 -22.52765)
			(xy 235.77576 -22.489704) (xy 235.719998 -22.445235) (xy 235.669565 -22.394802) (xy 235.625096 -22.33904)
			(xy 235.58715 -22.278649) (xy 235.556205 -22.21439) (xy 235.532648 -22.14707) (xy 235.516778 -22.077535)
			(xy 235.508792 -22.006661) (xy 229.158808 -22.006661) (xy 229.150822 -22.077535) (xy 229.134952 -22.14707)
			(xy 229.111395 -22.21439) (xy 229.08045 -22.278649) (xy 229.042504 -22.33904) (xy 228.998035 -22.394802)
			(xy 228.947602 -22.445235) (xy 228.89184 -22.489704) (xy 228.831449 -22.52765) (xy 228.76719 -22.558595)
			(xy 228.69987 -22.582152) (xy 228.630335 -22.598022) (xy 228.559461 -22.606008) (xy 228.488139 -22.606008)
			(xy 228.417265 -22.598022) (xy 228.34773 -22.582152) (xy 228.28041 -22.558595) (xy 228.216151 -22.52765)
			(xy 228.15576 -22.489704) (xy 228.099998 -22.445235) (xy 228.049565 -22.394802) (xy 228.005096 -22.33904)
			(xy 227.96715 -22.278649) (xy 227.936205 -22.21439) (xy 227.912648 -22.14707) (xy 227.896778 -22.077535)
			(xy 227.888792 -22.006661) (xy 221.538808 -22.006661) (xy 221.530822 -22.077535) (xy 221.514952 -22.14707)
			(xy 221.491395 -22.21439) (xy 221.46045 -22.278649) (xy 221.422504 -22.33904) (xy 221.378035 -22.394802)
			(xy 221.327602 -22.445235) (xy 221.27184 -22.489704) (xy 221.211449 -22.52765) (xy 221.14719 -22.558595)
			(xy 221.07987 -22.582152) (xy 221.010335 -22.598022) (xy 220.939461 -22.606008) (xy 220.868139 -22.606008)
			(xy 220.797265 -22.598022) (xy 220.72773 -22.582152) (xy 220.66041 -22.558595) (xy 220.596151 -22.52765)
			(xy 220.53576 -22.489704) (xy 220.479998 -22.445235) (xy 220.429565 -22.394802) (xy 220.385096 -22.33904)
			(xy 220.34715 -22.278649) (xy 220.316205 -22.21439) (xy 220.292648 -22.14707) (xy 220.276778 -22.077535)
			(xy 220.268792 -22.006661) (xy 213.918808 -22.006661) (xy 213.910822 -22.077535) (xy 213.894952 -22.14707)
			(xy 213.871395 -22.21439) (xy 213.84045 -22.278649) (xy 213.802504 -22.33904) (xy 213.758035 -22.394802)
			(xy 213.707602 -22.445235) (xy 213.65184 -22.489704) (xy 213.591449 -22.52765) (xy 213.52719 -22.558595)
			(xy 213.45987 -22.582152) (xy 213.390335 -22.598022) (xy 213.319461 -22.606008) (xy 213.248139 -22.606008)
			(xy 213.177265 -22.598022) (xy 213.10773 -22.582152) (xy 213.04041 -22.558595) (xy 212.976151 -22.52765)
			(xy 212.91576 -22.489704) (xy 212.859998 -22.445235) (xy 212.809565 -22.394802) (xy 212.765096 -22.33904)
			(xy 212.72715 -22.278649) (xy 212.696205 -22.21439) (xy 212.672648 -22.14707) (xy 212.656778 -22.077535)
			(xy 212.648792 -22.006661) (xy 206.298808 -22.006661) (xy 206.290822 -22.077535) (xy 206.274952 -22.14707)
			(xy 206.251395 -22.21439) (xy 206.22045 -22.278649) (xy 206.182504 -22.33904) (xy 206.138035 -22.394802)
			(xy 206.087602 -22.445235) (xy 206.03184 -22.489704) (xy 205.971449 -22.52765) (xy 205.90719 -22.558595)
			(xy 205.83987 -22.582152) (xy 205.770335 -22.598022) (xy 205.699461 -22.606008) (xy 205.628139 -22.606008)
			(xy 205.557265 -22.598022) (xy 205.48773 -22.582152) (xy 205.42041 -22.558595) (xy 205.356151 -22.52765)
			(xy 205.29576 -22.489704) (xy 205.239998 -22.445235) (xy 205.189565 -22.394802) (xy 205.145096 -22.33904)
			(xy 205.10715 -22.278649) (xy 205.076205 -22.21439) (xy 205.052648 -22.14707) (xy 205.036778 -22.077535)
			(xy 205.028792 -22.006661) (xy 157.160569 -22.006661) (xy 157.455108 -22.3012) (xy 157.455108 -24.8412)
			(xy 165.7858 -24.8412) (xy 165.7858 -23.241) (xy 166.0398 -22.987) (xy 166.3954 -22.987) (xy 166.6494 -23.241)
			(xy 166.6494 -23.876) (xy 170.4594 -23.876) (xy 170.4594 -23.5458) (xy 170.7134 -23.2918) (xy 172.2882 -23.2918)
			(xy 172.5422 -23.5458) (xy 172.5422 -23.8506) (xy 172.2882 -24.1046) (xy 170.688 -24.1046) (xy 170.4594 -23.876)
			(xy 166.6494 -23.876) (xy 166.6494 -24.8158) (xy 166.624 -24.8412) (xy 177.8 -24.8412) (xy 177.8 -23.2156)
			(xy 178.054 -22.9616) (xy 178.3842 -22.9616) (xy 178.6382 -23.2156) (xy 178.6382 -23.7236) (xy 189.4586 -23.7236)
			(xy 189.4586 -23.3934) (xy 189.6618 -23.1902) (xy 191.3128 -23.1902) (xy 191.5414 -23.4188) (xy 191.5414 -23.749)
			(xy 191.3128 -23.9776) (xy 189.7126 -23.9776) (xy 189.4586 -23.7236) (xy 178.6382 -23.7236) (xy 178.6382 -24.8158)
			(xy 197.231 -24.8158) (xy 197.231 -23.241) (xy 197.485 -22.987) (xy 197.8152 -22.987) (xy 198.0692 -23.241)
			(xy 198.0692 -24.8412) (xy 197.8406 -25.0698) (xy 197.485 -25.0698) (xy 197.231 -24.8158) (xy 178.6382 -24.8158)
			(xy 178.6382 -24.8412) (xy 178.4096 -25.0698) (xy 178.0286 -25.0698) (xy 177.8 -24.8412) (xy 166.624 -24.8412)
			(xy 166.3954 -25.0698) (xy 166.0144 -25.0698) (xy 165.7858 -24.8412) (xy 157.455108 -24.8412) (xy 157.455108 -27.0002)
			(xy 183.5912 -27.0002) (xy 183.5912 -26.67) (xy 183.8452 -26.416) (xy 185.4454 -26.416) (xy 185.674 -26.6446)
			(xy 185.674 -26.9748) (xy 185.42 -27.2288) (xy 183.8198 -27.2288) (xy 183.5912 -27.0002) (xy 157.455108 -27.0002)
			(xy 157.455108 -27.104848) (xy 158.496762 -28.146502) (xy 158.519258 -28.16972) (xy 158.558475 -28.221115)
			(xy 158.590486 -28.277282) (xy 158.614718 -28.337217) (xy 158.63074 -28.399849) (xy 158.638263 -28.464058)
			(xy 158.637154 -28.528697) (xy 158.627432 -28.59261) (xy 158.609272 -28.654656) (xy 158.582997 -28.713724)
			(xy 158.549078 -28.76876) (xy 158.508121 -28.818779) (xy 158.484824 -28.841192) (xy 158.468634 -28.857027)
			(xy 158.441585 -28.893343) (xy 158.421401 -28.933878) (xy 158.40872 -28.977349) (xy 158.403944 -29.022379)
			(xy 158.407224 -29.067542) (xy 158.418456 -29.111409) (xy 158.437285 -29.152591) (xy 158.463114 -29.189785)
			(xy 158.478728 -29.20619) (xy 158.521908 -29.24937) (xy 158.521908 -29.4386) (xy 183.8198 -29.4386)
			(xy 183.8198 -29.1592) (xy 184.15 -28.829) (xy 185.6232 -28.829) (xy 185.9026 -29.1084) (xy 185.9026 -29.464)
			(xy 185.674 -29.6926) (xy 184.0738 -29.6926) (xy 183.976264 -29.595064) (xy 183.967999 -29.587657)
			(xy 183.952239 -29.572029) (xy 183.944768 -29.563822) (xy 183.942482 -29.561282) (xy 183.8198 -29.4386)
			(xy 158.521908 -29.4386) (xy 158.521908 -30.545532) (xy 158.521391 -30.577163) (xy 158.513134 -30.639883)
			(xy 158.496761 -30.700989) (xy 158.472551 -30.759435) (xy 158.440921 -30.81422) (xy 158.40241 -30.864409)
			(xy 158.357677 -30.909142) (xy 158.354213 -30.9118) (xy 167.64 -30.9118) (xy 167.64 -30.5562) (xy 167.894 -30.3022)
			(xy 169.4688 -30.3022) (xy 169.7228 -30.5562) (xy 169.7228 -30.8864) (xy 169.4688 -31.1404) (xy 167.8686 -31.1404)
			(xy 167.64 -30.9118) (xy 158.354213 -30.9118) (xy 158.307488 -30.947653) (xy 158.252703 -30.979283)
			(xy 158.194257 -31.003493) (xy 158.133151 -31.019866) (xy 158.070431 -31.028123) (xy 158.007169 -31.028123)
			(xy 157.944449 -31.019866) (xy 157.883343 -31.003493) (xy 157.824897 -30.979283) (xy 157.770112 -30.947653)
			(xy 157.719923 -30.909142) (xy 157.67519 -30.864409) (xy 157.636679 -30.81422) (xy 157.605049 -30.759435)
			(xy 157.580839 -30.700989) (xy 157.564466 -30.639883) (xy 157.556209 -30.577163) (xy 157.555692 -30.545532)
			(xy 157.555692 -29.649674) (xy 156.256482 -28.35021) (xy 156.066998 -28.16098) (xy 156.054827 -28.149627)
			(xy 156.025988 -28.133038) (xy 155.993844 -28.124453) (xy 155.960574 -28.124453) (xy 155.92843 -28.133038)
			(xy 155.899591 -28.149627) (xy 155.88742 -28.16098) (xy 153.7208 -30.3276) (xy 152.5778 -30.3276)
			(xy 152.4508 -30.2006) (xy 136.34212 -30.2006) (xy 136.26846 -30.271974) (xy 136.266936 -30.323536)
			(xy 136.26514 -30.365147) (xy 136.254844 -30.447803) (xy 136.236973 -30.529159) (xy 136.21168 -30.60852)
			(xy 136.17918 -30.685213) (xy 136.13975 -30.758584) (xy 136.093725 -30.828008) (xy 136.041498 -30.892895)
			(xy 135.983512 -30.952692) (xy 135.920262 -31.006891) (xy 135.852285 -31.055028) (xy 135.780162 -31.096696)
			(xy 135.704504 -31.131539) (xy 135.625958 -31.15926) (xy 135.600019 -31.1658) (xy 174.8536 -31.1658)
			(xy 174.8536 -30.8356) (xy 175.0822 -30.607) (xy 176.6824 -30.607) (xy 176.784 -30.7086) (xy 189.0268 -30.7086)
			(xy 189.0268 -30.4546) (xy 189.3316 -30.1498) (xy 190.881 -30.1498) (xy 191.135 -30.4038) (xy 191.135 -30.7594)
			(xy 193.8528 -30.7594) (xy 193.8528 -30.353) (xy 194.0814 -30.1244) (xy 195.6816 -30.1244) (xy 195.9356 -30.3784)
			(xy 195.9356 -30.734) (xy 195.6816 -30.988) (xy 194.0814 -30.988) (xy 193.8528 -30.7594) (xy 191.135 -30.7594)
			(xy 191.135 -30.7848) (xy 190.9318 -30.988) (xy 189.3062 -30.988) (xy 189.0268 -30.7086) (xy 176.784 -30.7086)
			(xy 176.911 -30.8356) (xy 176.911 -31.1658) (xy 176.6824 -31.3944) (xy 175.0822 -31.3944) (xy 174.8536 -31.1658)
			(xy 135.600019 -31.1658) (xy 135.545191 -31.179624) (xy 135.46289 -31.192457) (xy 135.379758 -31.19765)
			(xy 135.2965 -31.195159) (xy 135.213827 -31.185005) (xy 135.132441 -31.167274) (xy 135.053036 -31.142118)
			(xy 134.976287 -31.10975) (xy 134.902848 -31.070446) (xy 134.833345 -31.02454) (xy 134.768368 -30.972424)
			(xy 134.73811 -30.943804) (xy 134.722021 -30.928886) (xy 134.685717 -30.904253) (xy 134.645722 -30.886222)
			(xy 134.603224 -30.875326) (xy 134.559487 -30.871891) (xy 134.51581 -30.876017) (xy 134.47349 -30.887584)
			(xy 134.433785 -30.906246) (xy 134.397875 -30.931449) (xy 134.382002 -30.946598) (xy 133.1722 -32.1564)
			(xy 170.053 -32.1564) (xy 170.053 -31.8262) (xy 170.2816 -31.5976) (xy 171.8818 -31.5976) (xy 172.1104 -31.8262)
			(xy 172.1104 -31.877) (xy 191.4652 -31.877) (xy 191.4652 -31.5214) (xy 191.7192 -31.2674) (xy 193.294 -31.2674)
			(xy 193.548 -31.5214) (xy 193.548 -31.8516) (xy 193.294 -32.1056) (xy 191.6938 -32.1056) (xy 191.4652 -31.877)
			(xy 172.1104 -31.877) (xy 172.1104 -32.1564) (xy 171.8818 -32.385) (xy 170.2816 -32.385) (xy 170.053 -32.1564)
			(xy 133.1722 -32.1564) (xy 132.5626 -32.766) (xy 132.5626 -33.639119) (xy 165.265595 -33.639119)
			(xy 165.265595 -33.540833) (xy 165.273504 -33.442866) (xy 165.28927 -33.345853) (xy 165.312791 -33.250424)
			(xy 165.343915 -33.157196) (xy 165.38244 -33.066775) (xy 165.428115 -32.979748) (xy 165.480646 -32.896677)
			(xy 165.53969 -32.818104) (xy 165.604865 -32.744536) (xy 165.675749 -32.676451) (xy 165.751882 -32.61429)
			(xy 165.832769 -32.558458) (xy 165.917887 -32.509315) (xy 166.006684 -32.467181) (xy 166.098582 -32.432328)
			(xy 166.192988 -32.404983) (xy 166.289287 -32.385324) (xy 166.386856 -32.373477) (xy 166.485062 -32.369519)
			(xy 166.583268 -32.373477) (xy 166.680837 -32.385324) (xy 166.777136 -32.404983) (xy 166.871542 -32.432328)
			(xy 166.96344 -32.467181) (xy 167.052237 -32.509315) (xy 167.137355 -32.558458) (xy 167.218242 -32.61429)
			(xy 167.294375 -32.676451) (xy 167.365259 -32.744536) (xy 167.430434 -32.818104) (xy 167.489478 -32.896677)
			(xy 167.542009 -32.979748) (xy 167.587684 -33.066775) (xy 167.589399 -33.0708) (xy 172.466 -33.0708)
			(xy 172.466 -32.766) (xy 172.72 -32.512) (xy 174.2948 -32.512) (xy 174.5488 -32.766) (xy 174.5488 -33.0962)
			(xy 174.3202 -33.3248) (xy 172.72 -33.3248) (xy 172.466 -33.0708) (xy 167.589399 -33.0708) (xy 167.626209 -33.157196)
			(xy 167.657333 -33.250424) (xy 167.680854 -33.345853) (xy 167.69662 -33.442866) (xy 167.704529 -33.540833)
			(xy 167.705024 -33.589976) (xy 167.704529 -33.639119) (xy 167.704526 -33.63915) (xy 177.264809 -33.63915)
			(xy 177.264809 -33.540802) (xy 177.272723 -33.442774) (xy 177.288499 -33.345701) (xy 177.312035 -33.250211)
			(xy 177.343178 -33.156926) (xy 177.381727 -33.066448) (xy 177.427431 -32.979366) (xy 177.479994 -32.896244)
			(xy 177.539075 -32.817621) (xy 177.604292 -32.744008) (xy 177.67522 -32.67588) (xy 177.7514 -32.613681)
			(xy 177.832338 -32.557813) (xy 177.917509 -32.50864) (xy 178.006361 -32.466479) (xy 178.098317 -32.431605)
			(xy 178.192781 -32.404243) (xy 178.289141 -32.384571) (xy 178.386771 -32.372717) (xy 178.485038 -32.368757)
			(xy 178.583305 -32.372717) (xy 178.680935 -32.384571) (xy 178.777295 -32.404243) (xy 178.871759 -32.431605)
			(xy 178.963715 -32.466479) (xy 179.052567 -32.50864) (xy 179.137738 -32.557813) (xy 179.218676 -32.613681)
			(xy 179.294856 -32.67588) (xy 179.365784 -32.744008) (xy 179.431001 -32.817621) (xy 179.490082 -32.896244)
			(xy 179.542645 -32.979366) (xy 179.588349 -33.066448) (xy 179.626898 -33.156926) (xy 179.658041 -33.250211)
			(xy 179.681577 -33.345701) (xy 179.697353 -33.442774) (xy 179.705267 -33.540802) (xy 179.705762 -33.589976)
			(xy 179.705267 -33.639119) (xy 184.275463 -33.639119) (xy 184.275463 -33.540833) (xy 184.283372 -33.442866)
			(xy 184.299138 -33.345853) (xy 184.322659 -33.250424) (xy 184.353783 -33.157196) (xy 184.392308 -33.066775)
			(xy 184.437983 -32.979748) (xy 184.490514 -32.896677) (xy 184.549558 -32.818104) (xy 184.614733 -32.744536)
			(xy 184.685617 -32.676451) (xy 184.76175 -32.61429) (xy 184.842637 -32.558458) (xy 184.927755 -32.509315)
			(xy 185.016552 -32.467181) (xy 185.10845 -32.432328) (xy 185.202856 -32.404983) (xy 185.299155 -32.385324)
			(xy 185.396724 -32.373477) (xy 185.49493 -32.369519) (xy 185.593136 -32.373477) (xy 185.690705 -32.385324)
			(xy 185.787004 -32.404983) (xy 185.88141 -32.432328) (xy 185.973308 -32.467181) (xy 186.062105 -32.509315)
			(xy 186.147223 -32.558458) (xy 186.22811 -32.61429) (xy 186.304243 -32.676451) (xy 186.375127 -32.744536)
			(xy 186.440302 -32.818104) (xy 186.499346 -32.896677) (xy 186.551877 -32.979748) (xy 186.597552 -33.066775)
			(xy 186.636077 -33.157196) (xy 186.667201 -33.250424) (xy 186.690722 -33.345853) (xy 186.706488 -33.442866)
			(xy 186.714397 -33.540833) (xy 186.714892 -33.589976) (xy 186.714397 -33.639119) (xy 186.714394 -33.63915)
			(xy 196.274677 -33.63915) (xy 196.274677 -33.540802) (xy 196.282591 -33.442774) (xy 196.298367 -33.345701)
			(xy 196.321903 -33.250211) (xy 196.353046 -33.156926) (xy 196.391595 -33.066448) (xy 196.437299 -32.979366)
			(xy 196.489862 -32.896244) (xy 196.548943 -32.817621) (xy 196.61416 -32.744008) (xy 196.685088 -32.67588)
			(xy 196.761268 -32.613681) (xy 196.842206 -32.557813) (xy 196.927377 -32.50864) (xy 197.016229 -32.466479)
			(xy 197.108185 -32.431605) (xy 197.202649 -32.404243) (xy 197.299009 -32.384571) (xy 197.396639 -32.372717)
			(xy 197.494906 -32.368757) (xy 197.593173 -32.372717) (xy 197.690803 -32.384571) (xy 197.787163 -32.404243)
			(xy 197.881627 -32.431605) (xy 197.973583 -32.466479) (xy 198.062435 -32.50864) (xy 198.147606 -32.557813)
			(xy 198.169696 -32.573061) (xy 212.293192 -32.573061) (xy 212.293192 -32.501739) (xy 212.301178 -32.430865)
			(xy 212.317048 -32.36133) (xy 212.340605 -32.29401) (xy 212.37155 -32.229751) (xy 212.409496 -32.16936)
			(xy 212.453965 -32.113598) (xy 212.504398 -32.063165) (xy 212.56016 -32.018696) (xy 212.620551 -31.98075)
			(xy 212.68481 -31.949805) (xy 212.75213 -31.926248) (xy 212.821665 -31.910378) (xy 212.892539 -31.902392)
			(xy 212.963861 -31.902392) (xy 213.034735 -31.910378) (xy 213.10427 -31.926248) (xy 213.17159 -31.949805)
			(xy 213.235849 -31.98075) (xy 213.29624 -32.018696) (xy 213.352002 -32.063165) (xy 213.402435 -32.113598)
			(xy 213.446904 -32.16936) (xy 213.48485 -32.229751) (xy 213.515795 -32.29401) (xy 213.539352 -32.36133)
			(xy 213.555222 -32.430865) (xy 213.563208 -32.501739) (xy 213.563708 -32.5374) (xy 213.563208 -32.573061)
			(xy 219.913192 -32.573061) (xy 219.913192 -32.501739) (xy 219.921178 -32.430865) (xy 219.937048 -32.36133)
			(xy 219.960605 -32.29401) (xy 219.99155 -32.229751) (xy 220.029496 -32.16936) (xy 220.073965 -32.113598)
			(xy 220.124398 -32.063165) (xy 220.18016 -32.018696) (xy 220.240551 -31.98075) (xy 220.30481 -31.949805)
			(xy 220.37213 -31.926248) (xy 220.441665 -31.910378) (xy 220.512539 -31.902392) (xy 220.583861 -31.902392)
			(xy 220.654735 -31.910378) (xy 220.72427 -31.926248) (xy 220.79159 -31.949805) (xy 220.855849 -31.98075)
			(xy 220.91624 -32.018696) (xy 220.972002 -32.063165) (xy 221.022435 -32.113598) (xy 221.066904 -32.16936)
			(xy 221.10485 -32.229751) (xy 221.135795 -32.29401) (xy 221.159352 -32.36133) (xy 221.175222 -32.430865)
			(xy 221.183208 -32.501739) (xy 221.183708 -32.5374) (xy 221.183208 -32.573061) (xy 227.533192 -32.573061)
			(xy 227.533192 -32.501739) (xy 227.541178 -32.430865) (xy 227.557048 -32.36133) (xy 227.580605 -32.29401)
			(xy 227.61155 -32.229751) (xy 227.649496 -32.16936) (xy 227.693965 -32.113598) (xy 227.744398 -32.063165)
			(xy 227.80016 -32.018696) (xy 227.860551 -31.98075) (xy 227.92481 -31.949805) (xy 227.99213 -31.926248)
			(xy 228.061665 -31.910378) (xy 228.132539 -31.902392) (xy 228.203861 -31.902392) (xy 228.274735 -31.910378)
			(xy 228.34427 -31.926248) (xy 228.41159 -31.949805) (xy 228.475849 -31.98075) (xy 228.53624 -32.018696)
			(xy 228.592002 -32.063165) (xy 228.642435 -32.113598) (xy 228.686904 -32.16936) (xy 228.72485 -32.229751)
			(xy 228.755795 -32.29401) (xy 228.779352 -32.36133) (xy 228.795222 -32.430865) (xy 228.803208 -32.501739)
			(xy 228.803708 -32.5374) (xy 228.803208 -32.573061) (xy 235.153192 -32.573061) (xy 235.153192 -32.501739)
			(xy 235.161178 -32.430865) (xy 235.177048 -32.36133) (xy 235.200605 -32.29401) (xy 235.23155 -32.229751)
			(xy 235.269496 -32.16936) (xy 235.313965 -32.113598) (xy 235.364398 -32.063165) (xy 235.42016 -32.018696)
			(xy 235.480551 -31.98075) (xy 235.54481 -31.949805) (xy 235.61213 -31.926248) (xy 235.681665 -31.910378)
			(xy 235.752539 -31.902392) (xy 235.823861 -31.902392) (xy 235.894735 -31.910378) (xy 235.96427 -31.926248)
			(xy 236.03159 -31.949805) (xy 236.095849 -31.98075) (xy 236.15624 -32.018696) (xy 236.212002 -32.063165)
			(xy 236.262435 -32.113598) (xy 236.306904 -32.16936) (xy 236.34485 -32.229751) (xy 236.375795 -32.29401)
			(xy 236.399352 -32.36133) (xy 236.415222 -32.430865) (xy 236.423208 -32.501739) (xy 236.423708 -32.5374)
			(xy 236.423208 -32.573061) (xy 242.773192 -32.573061) (xy 242.773192 -32.501739) (xy 242.781178 -32.430865)
			(xy 242.797048 -32.36133) (xy 242.820605 -32.29401) (xy 242.85155 -32.229751) (xy 242.889496 -32.16936)
			(xy 242.933965 -32.113598) (xy 242.984398 -32.063165) (xy 243.04016 -32.018696) (xy 243.100551 -31.98075)
			(xy 243.16481 -31.949805) (xy 243.23213 -31.926248) (xy 243.301665 -31.910378) (xy 243.372539 -31.902392)
			(xy 243.443861 -31.902392) (xy 243.514735 -31.910378) (xy 243.58427 -31.926248) (xy 243.65159 -31.949805)
			(xy 243.715849 -31.98075) (xy 243.77624 -32.018696) (xy 243.832002 -32.063165) (xy 243.882435 -32.113598)
			(xy 243.926904 -32.16936) (xy 243.96485 -32.229751) (xy 243.995795 -32.29401) (xy 244.019352 -32.36133)
			(xy 244.035222 -32.430865) (xy 244.043208 -32.501739) (xy 244.043708 -32.5374) (xy 244.043208 -32.573061)
			(xy 250.393192 -32.573061) (xy 250.393192 -32.501739) (xy 250.401178 -32.430865) (xy 250.417048 -32.36133)
			(xy 250.440605 -32.29401) (xy 250.47155 -32.229751) (xy 250.509496 -32.16936) (xy 250.553965 -32.113598)
			(xy 250.604398 -32.063165) (xy 250.66016 -32.018696) (xy 250.720551 -31.98075) (xy 250.78481 -31.949805)
			(xy 250.85213 -31.926248) (xy 250.921665 -31.910378) (xy 250.992539 -31.902392) (xy 251.063861 -31.902392)
			(xy 251.134735 -31.910378) (xy 251.20427 -31.926248) (xy 251.27159 -31.949805) (xy 251.335849 -31.98075)
			(xy 251.39624 -32.018696) (xy 251.452002 -32.063165) (xy 251.502435 -32.113598) (xy 251.546904 -32.16936)
			(xy 251.58485 -32.229751) (xy 251.615795 -32.29401) (xy 251.639352 -32.36133) (xy 251.655222 -32.430865)
			(xy 251.663208 -32.501739) (xy 251.663708 -32.5374) (xy 251.663208 -32.573061) (xy 258.013192 -32.573061)
			(xy 258.013192 -32.501739) (xy 258.021178 -32.430865) (xy 258.037048 -32.36133) (xy 258.060605 -32.29401)
			(xy 258.09155 -32.229751) (xy 258.129496 -32.16936) (xy 258.173965 -32.113598) (xy 258.224398 -32.063165)
			(xy 258.28016 -32.018696) (xy 258.340551 -31.98075) (xy 258.40481 -31.949805) (xy 258.47213 -31.926248)
			(xy 258.541665 -31.910378) (xy 258.612539 -31.902392) (xy 258.683861 -31.902392) (xy 258.754735 -31.910378)
			(xy 258.82427 -31.926248) (xy 258.89159 -31.949805) (xy 258.955849 -31.98075) (xy 259.01624 -32.018696)
			(xy 259.072002 -32.063165) (xy 259.122435 -32.113598) (xy 259.166904 -32.16936) (xy 259.20485 -32.229751)
			(xy 259.235795 -32.29401) (xy 259.259352 -32.36133) (xy 259.275222 -32.430865) (xy 259.283208 -32.501739)
			(xy 259.283708 -32.5374) (xy 259.283208 -32.573061) (xy 265.633192 -32.573061) (xy 265.633192 -32.501739)
			(xy 265.641178 -32.430865) (xy 265.657048 -32.36133) (xy 265.680605 -32.29401) (xy 265.71155 -32.229751)
			(xy 265.749496 -32.16936) (xy 265.793965 -32.113598) (xy 265.844398 -32.063165) (xy 265.90016 -32.018696)
			(xy 265.960551 -31.98075) (xy 266.02481 -31.949805) (xy 266.09213 -31.926248) (xy 266.161665 -31.910378)
			(xy 266.232539 -31.902392) (xy 266.303861 -31.902392) (xy 266.374735 -31.910378) (xy 266.44427 -31.926248)
			(xy 266.51159 -31.949805) (xy 266.575849 -31.98075) (xy 266.63624 -32.018696) (xy 266.692002 -32.063165)
			(xy 266.742435 -32.113598) (xy 266.786904 -32.16936) (xy 266.82485 -32.229751) (xy 266.855795 -32.29401)
			(xy 266.879352 -32.36133) (xy 266.895222 -32.430865) (xy 266.903208 -32.501739) (xy 266.903708 -32.5374)
			(xy 266.903208 -32.573061) (xy 273.253192 -32.573061) (xy 273.253192 -32.501739) (xy 273.261178 -32.430865)
			(xy 273.277048 -32.36133) (xy 273.300605 -32.29401) (xy 273.33155 -32.229751) (xy 273.369496 -32.16936)
			(xy 273.413965 -32.113598) (xy 273.464398 -32.063165) (xy 273.52016 -32.018696) (xy 273.580551 -31.98075)
			(xy 273.64481 -31.949805) (xy 273.71213 -31.926248) (xy 273.781665 -31.910378) (xy 273.852539 -31.902392)
			(xy 273.923861 -31.902392) (xy 273.994735 -31.910378) (xy 274.06427 -31.926248) (xy 274.13159 -31.949805)
			(xy 274.195849 -31.98075) (xy 274.25624 -32.018696) (xy 274.312002 -32.063165) (xy 274.362435 -32.113598)
			(xy 274.406904 -32.16936) (xy 274.44485 -32.229751) (xy 274.475795 -32.29401) (xy 274.499352 -32.36133)
			(xy 274.515222 -32.430865) (xy 274.523208 -32.501739) (xy 274.523708 -32.5374) (xy 274.523208 -32.573061)
			(xy 280.873192 -32.573061) (xy 280.873192 -32.501739) (xy 280.881178 -32.430865) (xy 280.897048 -32.36133)
			(xy 280.920605 -32.29401) (xy 280.95155 -32.229751) (xy 280.989496 -32.16936) (xy 281.033965 -32.113598)
			(xy 281.084398 -32.063165) (xy 281.14016 -32.018696) (xy 281.200551 -31.98075) (xy 281.26481 -31.949805)
			(xy 281.33213 -31.926248) (xy 281.401665 -31.910378) (xy 281.472539 -31.902392) (xy 281.543861 -31.902392)
			(xy 281.614735 -31.910378) (xy 281.68427 -31.926248) (xy 281.75159 -31.949805) (xy 281.815849 -31.98075)
			(xy 281.87624 -32.018696) (xy 281.932002 -32.063165) (xy 281.982435 -32.113598) (xy 282.026904 -32.16936)
			(xy 282.06485 -32.229751) (xy 282.095795 -32.29401) (xy 282.119352 -32.36133) (xy 282.135222 -32.430865)
			(xy 282.143208 -32.501739) (xy 282.143708 -32.5374) (xy 282.143208 -32.573061) (xy 282.135222 -32.643935)
			(xy 282.119352 -32.71347) (xy 282.095795 -32.78079) (xy 282.06485 -32.845049) (xy 282.026904 -32.90544)
			(xy 281.982435 -32.961202) (xy 281.932002 -33.011635) (xy 281.87624 -33.056104) (xy 281.815849 -33.09405)
			(xy 281.75159 -33.124995) (xy 281.68427 -33.148552) (xy 281.614735 -33.164422) (xy 281.543861 -33.172408)
			(xy 281.472539 -33.172408) (xy 281.401665 -33.164422) (xy 281.33213 -33.148552) (xy 281.26481 -33.124995)
			(xy 281.200551 -33.09405) (xy 281.14016 -33.056104) (xy 281.084398 -33.011635) (xy 281.033965 -32.961202)
			(xy 280.989496 -32.90544) (xy 280.95155 -32.845049) (xy 280.920605 -32.78079) (xy 280.897048 -32.71347)
			(xy 280.881178 -32.643935) (xy 280.873192 -32.573061) (xy 274.523208 -32.573061) (xy 274.515222 -32.643935)
			(xy 274.499352 -32.71347) (xy 274.475795 -32.78079) (xy 274.44485 -32.845049) (xy 274.406904 -32.90544)
			(xy 274.362435 -32.961202) (xy 274.312002 -33.011635) (xy 274.25624 -33.056104) (xy 274.195849 -33.09405)
			(xy 274.13159 -33.124995) (xy 274.06427 -33.148552) (xy 273.994735 -33.164422) (xy 273.923861 -33.172408)
			(xy 273.852539 -33.172408) (xy 273.781665 -33.164422) (xy 273.71213 -33.148552) (xy 273.64481 -33.124995)
			(xy 273.580551 -33.09405) (xy 273.52016 -33.056104) (xy 273.464398 -33.011635) (xy 273.413965 -32.961202)
			(xy 273.369496 -32.90544) (xy 273.33155 -32.845049) (xy 273.300605 -32.78079) (xy 273.277048 -32.71347)
			(xy 273.261178 -32.643935) (xy 273.253192 -32.573061) (xy 266.903208 -32.573061) (xy 266.895222 -32.643935)
			(xy 266.879352 -32.71347) (xy 266.855795 -32.78079) (xy 266.82485 -32.845049) (xy 266.786904 -32.90544)
			(xy 266.742435 -32.961202) (xy 266.692002 -33.011635) (xy 266.63624 -33.056104) (xy 266.575849 -33.09405)
			(xy 266.51159 -33.124995) (xy 266.44427 -33.148552) (xy 266.374735 -33.164422) (xy 266.303861 -33.172408)
			(xy 266.232539 -33.172408) (xy 266.161665 -33.164422) (xy 266.09213 -33.148552) (xy 266.02481 -33.124995)
			(xy 265.960551 -33.09405) (xy 265.90016 -33.056104) (xy 265.844398 -33.011635) (xy 265.793965 -32.961202)
			(xy 265.749496 -32.90544) (xy 265.71155 -32.845049) (xy 265.680605 -32.78079) (xy 265.657048 -32.71347)
			(xy 265.641178 -32.643935) (xy 265.633192 -32.573061) (xy 259.283208 -32.573061) (xy 259.275222 -32.643935)
			(xy 259.259352 -32.71347) (xy 259.235795 -32.78079) (xy 259.20485 -32.845049) (xy 259.166904 -32.90544)
			(xy 259.122435 -32.961202) (xy 259.072002 -33.011635) (xy 259.01624 -33.056104) (xy 258.955849 -33.09405)
			(xy 258.89159 -33.124995) (xy 258.82427 -33.148552) (xy 258.754735 -33.164422) (xy 258.683861 -33.172408)
			(xy 258.612539 -33.172408) (xy 258.541665 -33.164422) (xy 258.47213 -33.148552) (xy 258.40481 -33.124995)
			(xy 258.340551 -33.09405) (xy 258.28016 -33.056104) (xy 258.224398 -33.011635) (xy 258.173965 -32.961202)
			(xy 258.129496 -32.90544) (xy 258.09155 -32.845049) (xy 258.060605 -32.78079) (xy 258.037048 -32.71347)
			(xy 258.021178 -32.643935) (xy 258.013192 -32.573061) (xy 251.663208 -32.573061) (xy 251.655222 -32.643935)
			(xy 251.639352 -32.71347) (xy 251.615795 -32.78079) (xy 251.58485 -32.845049) (xy 251.546904 -32.90544)
			(xy 251.502435 -32.961202) (xy 251.452002 -33.011635) (xy 251.39624 -33.056104) (xy 251.335849 -33.09405)
			(xy 251.27159 -33.124995) (xy 251.20427 -33.148552) (xy 251.134735 -33.164422) (xy 251.063861 -33.172408)
			(xy 250.992539 -33.172408) (xy 250.921665 -33.164422) (xy 250.85213 -33.148552) (xy 250.78481 -33.124995)
			(xy 250.720551 -33.09405) (xy 250.66016 -33.056104) (xy 250.604398 -33.011635) (xy 250.553965 -32.961202)
			(xy 250.509496 -32.90544) (xy 250.47155 -32.845049) (xy 250.440605 -32.78079) (xy 250.417048 -32.71347)
			(xy 250.401178 -32.643935) (xy 250.393192 -32.573061) (xy 244.043208 -32.573061) (xy 244.035222 -32.643935)
			(xy 244.019352 -32.71347) (xy 243.995795 -32.78079) (xy 243.96485 -32.845049) (xy 243.926904 -32.90544)
			(xy 243.882435 -32.961202) (xy 243.832002 -33.011635) (xy 243.77624 -33.056104) (xy 243.715849 -33.09405)
			(xy 243.65159 -33.124995) (xy 243.58427 -33.148552) (xy 243.514735 -33.164422) (xy 243.443861 -33.172408)
			(xy 243.372539 -33.172408) (xy 243.301665 -33.164422) (xy 243.23213 -33.148552) (xy 243.16481 -33.124995)
			(xy 243.100551 -33.09405) (xy 243.04016 -33.056104) (xy 242.984398 -33.011635) (xy 242.933965 -32.961202)
			(xy 242.889496 -32.90544) (xy 242.85155 -32.845049) (xy 242.820605 -32.78079) (xy 242.797048 -32.71347)
			(xy 242.781178 -32.643935) (xy 242.773192 -32.573061) (xy 236.423208 -32.573061) (xy 236.415222 -32.643935)
			(xy 236.399352 -32.71347) (xy 236.375795 -32.78079) (xy 236.34485 -32.845049) (xy 236.306904 -32.90544)
			(xy 236.262435 -32.961202) (xy 236.212002 -33.011635) (xy 236.15624 -33.056104) (xy 236.095849 -33.09405)
			(xy 236.03159 -33.124995) (xy 235.96427 -33.148552) (xy 235.894735 -33.164422) (xy 235.823861 -33.172408)
			(xy 235.752539 -33.172408) (xy 235.681665 -33.164422) (xy 235.61213 -33.148552) (xy 235.54481 -33.124995)
			(xy 235.480551 -33.09405) (xy 235.42016 -33.056104) (xy 235.364398 -33.011635) (xy 235.313965 -32.961202)
			(xy 235.269496 -32.90544) (xy 235.23155 -32.845049) (xy 235.200605 -32.78079) (xy 235.177048 -32.71347)
			(xy 235.161178 -32.643935) (xy 235.153192 -32.573061) (xy 228.803208 -32.573061) (xy 228.795222 -32.643935)
			(xy 228.779352 -32.71347) (xy 228.755795 -32.78079) (xy 228.72485 -32.845049) (xy 228.686904 -32.90544)
			(xy 228.642435 -32.961202) (xy 228.592002 -33.011635) (xy 228.53624 -33.056104) (xy 228.475849 -33.09405)
			(xy 228.41159 -33.124995) (xy 228.34427 -33.148552) (xy 228.274735 -33.164422) (xy 228.203861 -33.172408)
			(xy 228.132539 -33.172408) (xy 228.061665 -33.164422) (xy 227.99213 -33.148552) (xy 227.92481 -33.124995)
			(xy 227.860551 -33.09405) (xy 227.80016 -33.056104) (xy 227.744398 -33.011635) (xy 227.693965 -32.961202)
			(xy 227.649496 -32.90544) (xy 227.61155 -32.845049) (xy 227.580605 -32.78079) (xy 227.557048 -32.71347)
			(xy 227.541178 -32.643935) (xy 227.533192 -32.573061) (xy 221.183208 -32.573061) (xy 221.175222 -32.643935)
			(xy 221.159352 -32.71347) (xy 221.135795 -32.78079) (xy 221.10485 -32.845049) (xy 221.066904 -32.90544)
			(xy 221.022435 -32.961202) (xy 220.972002 -33.011635) (xy 220.91624 -33.056104) (xy 220.855849 -33.09405)
			(xy 220.79159 -33.124995) (xy 220.72427 -33.148552) (xy 220.654735 -33.164422) (xy 220.583861 -33.172408)
			(xy 220.512539 -33.172408) (xy 220.441665 -33.164422) (xy 220.37213 -33.148552) (xy 220.30481 -33.124995)
			(xy 220.240551 -33.09405) (xy 220.18016 -33.056104) (xy 220.124398 -33.011635) (xy 220.073965 -32.961202)
			(xy 220.029496 -32.90544) (xy 219.99155 -32.845049) (xy 219.960605 -32.78079) (xy 219.937048 -32.71347)
			(xy 219.921178 -32.643935) (xy 219.913192 -32.573061) (xy 213.563208 -32.573061) (xy 213.555222 -32.643935)
			(xy 213.539352 -32.71347) (xy 213.515795 -32.78079) (xy 213.48485 -32.845049) (xy 213.446904 -32.90544)
			(xy 213.402435 -32.961202) (xy 213.352002 -33.011635) (xy 213.29624 -33.056104) (xy 213.235849 -33.09405)
			(xy 213.17159 -33.124995) (xy 213.10427 -33.148552) (xy 213.034735 -33.164422) (xy 212.963861 -33.172408)
			(xy 212.892539 -33.172408) (xy 212.821665 -33.164422) (xy 212.75213 -33.148552) (xy 212.68481 -33.124995)
			(xy 212.620551 -33.09405) (xy 212.56016 -33.056104) (xy 212.504398 -33.011635) (xy 212.453965 -32.961202)
			(xy 212.409496 -32.90544) (xy 212.37155 -32.845049) (xy 212.340605 -32.78079) (xy 212.317048 -32.71347)
			(xy 212.301178 -32.643935) (xy 212.293192 -32.573061) (xy 198.169696 -32.573061) (xy 198.228544 -32.613681)
			(xy 198.304724 -32.67588) (xy 198.375652 -32.744008) (xy 198.440869 -32.817621) (xy 198.49995 -32.896244)
			(xy 198.552513 -32.979366) (xy 198.598217 -33.066448) (xy 198.636766 -33.156926) (xy 198.667909 -33.250211)
			(xy 198.691445 -33.345701) (xy 198.707221 -33.442774) (xy 198.715135 -33.540802) (xy 198.71563 -33.589976)
			(xy 198.715135 -33.63915) (xy 198.707221 -33.737178) (xy 198.691445 -33.834251) (xy 198.667909 -33.929741)
			(xy 198.636766 -34.023026) (xy 198.598217 -34.113504) (xy 198.552513 -34.200586) (xy 198.49995 -34.283708)
			(xy 198.440869 -34.362331) (xy 198.375652 -34.435944) (xy 198.304724 -34.504072) (xy 198.228544 -34.566271)
			(xy 198.147606 -34.622139) (xy 198.062435 -34.671312) (xy 197.973583 -34.713473) (xy 197.881627 -34.748347)
			(xy 197.787163 -34.775709) (xy 197.690803 -34.795381) (xy 197.593173 -34.807235) (xy 197.494906 -34.811196)
			(xy 197.396639 -34.807235) (xy 197.299009 -34.795381) (xy 197.202649 -34.775709) (xy 197.108185 -34.748347)
			(xy 197.016229 -34.713473) (xy 196.927377 -34.671312) (xy 196.842206 -34.622139) (xy 196.761268 -34.566271)
			(xy 196.685088 -34.504072) (xy 196.61416 -34.435944) (xy 196.548943 -34.362331) (xy 196.489862 -34.283708)
			(xy 196.437299 -34.200586) (xy 196.391595 -34.113504) (xy 196.353046 -34.023026) (xy 196.321903 -33.929741)
			(xy 196.298367 -33.834251) (xy 196.282591 -33.737178) (xy 196.274677 -33.63915) (xy 186.714394 -33.63915)
			(xy 186.706488 -33.737086) (xy 186.690722 -33.834099) (xy 186.667201 -33.929528) (xy 186.636077 -34.022756)
			(xy 186.597552 -34.113177) (xy 186.551877 -34.200205) (xy 186.499346 -34.283275) (xy 186.440302 -34.361848)
			(xy 186.375127 -34.435416) (xy 186.304243 -34.503501) (xy 186.22811 -34.565662) (xy 186.147223 -34.621494)
			(xy 186.062105 -34.670637) (xy 185.973308 -34.712771) (xy 185.88141 -34.747624) (xy 185.787004 -34.774969)
			(xy 185.690705 -34.794628) (xy 185.593136 -34.806475) (xy 185.49493 -34.810433) (xy 185.396724 -34.806475)
			(xy 185.299155 -34.794628) (xy 185.202856 -34.774969) (xy 185.10845 -34.747624) (xy 185.016552 -34.712771)
			(xy 184.927755 -34.670637) (xy 184.842637 -34.621494) (xy 184.76175 -34.565662) (xy 184.685617 -34.503501)
			(xy 184.614733 -34.435416) (xy 184.549558 -34.361848) (xy 184.490514 -34.283275) (xy 184.437983 -34.200205)
			(xy 184.392308 -34.113177) (xy 184.353783 -34.022756) (xy 184.322659 -33.929528) (xy 184.299138 -33.834099)
			(xy 184.283372 -33.737086) (xy 184.275463 -33.639119) (xy 179.705267 -33.639119) (xy 179.705267 -33.63915)
			(xy 179.697353 -33.737178) (xy 179.681577 -33.834251) (xy 179.658041 -33.929741) (xy 179.626898 -34.023026)
			(xy 179.588349 -34.113504) (xy 179.542645 -34.200586) (xy 179.490082 -34.283708) (xy 179.431001 -34.362331)
			(xy 179.365784 -34.435944) (xy 179.294856 -34.504072) (xy 179.218676 -34.566271) (xy 179.137738 -34.622139)
			(xy 179.052567 -34.671312) (xy 178.963715 -34.713473) (xy 178.871759 -34.748347) (xy 178.777295 -34.775709)
			(xy 178.680935 -34.795381) (xy 178.583305 -34.807235) (xy 178.485038 -34.811196) (xy 178.386771 -34.807235)
			(xy 178.289141 -34.795381) (xy 178.192781 -34.775709) (xy 178.098317 -34.748347) (xy 178.006361 -34.713473)
			(xy 177.917509 -34.671312) (xy 177.832338 -34.622139) (xy 177.7514 -34.566271) (xy 177.67522 -34.504072)
			(xy 177.604292 -34.435944) (xy 177.539075 -34.362331) (xy 177.479994 -34.283708) (xy 177.427431 -34.200586)
			(xy 177.381727 -34.113504) (xy 177.343178 -34.023026) (xy 177.312035 -33.929741) (xy 177.288499 -33.834251)
			(xy 177.272723 -33.737178) (xy 177.264809 -33.63915) (xy 167.704526 -33.63915) (xy 167.69662 -33.737086)
			(xy 167.680854 -33.834099) (xy 167.657333 -33.929528) (xy 167.626209 -34.022756) (xy 167.587684 -34.113177)
			(xy 167.542009 -34.200205) (xy 167.489478 -34.283275) (xy 167.430434 -34.361848) (xy 167.365259 -34.435416)
			(xy 167.294375 -34.503501) (xy 167.218242 -34.565662) (xy 167.137355 -34.621494) (xy 167.052237 -34.670637)
			(xy 166.96344 -34.712771) (xy 166.871542 -34.747624) (xy 166.777136 -34.774969) (xy 166.680837 -34.794628)
			(xy 166.583268 -34.806475) (xy 166.485062 -34.810433) (xy 166.386856 -34.806475) (xy 166.289287 -34.794628)
			(xy 166.192988 -34.774969) (xy 166.098582 -34.747624) (xy 166.006684 -34.712771) (xy 165.917887 -34.670637)
			(xy 165.832769 -34.621494) (xy 165.751882 -34.565662) (xy 165.675749 -34.503501) (xy 165.604865 -34.435416)
			(xy 165.53969 -34.361848) (xy 165.480646 -34.283275) (xy 165.428115 -34.200205) (xy 165.38244 -34.113177)
			(xy 165.343915 -34.022756) (xy 165.312791 -33.929528) (xy 165.28927 -33.834099) (xy 165.273504 -33.737086)
			(xy 165.265595 -33.639119) (xy 132.5626 -33.639119) (xy 132.5626 -34.688526) (xy 132.597704 -34.732542)
			(xy 132.662533 -34.824602) (xy 132.720941 -34.920863) (xy 132.772656 -35.02088) (xy 132.817439 -35.124187)
			(xy 132.85508 -35.230305) (xy 132.885405 -35.33874) (xy 132.908274 -35.448989) (xy 132.92358 -35.56054)
			(xy 132.931251 -35.672874) (xy 132.931253 -35.78547) (xy 132.923585 -35.897804) (xy 132.908283 -36.009356)
			(xy 132.896121 -36.068) (xy 133.37743 -36.068) (xy 133.381501 -36.012378) (xy 133.393627 -35.957941)
			(xy 133.41355 -35.90585) (xy 133.440846 -35.857215) (xy 133.474932 -35.813072) (xy 133.515081 -35.774363)
			(xy 133.560439 -35.741912) (xy 133.610039 -35.716411) (xy 133.662823 -35.698404) (xy 133.717666 -35.688274)
			(xy 133.7734 -35.686237) (xy 133.828837 -35.692337) (xy 133.882794 -35.706443) (xy 133.934123 -35.728255)
			(xy 133.981729 -35.757309) (xy 134.024597 -35.792984) (xy 134.061814 -35.834521) (xy 134.092587 -35.881034)
			(xy 134.116259 -35.931531) (xy 134.132327 -35.984938) (xy 134.140447 -36.040114) (xy 134.140956 -36.068)
			(xy 134.140447 -36.095886) (xy 134.132327 -36.151062) (xy 134.116259 -36.204469) (xy 134.092587 -36.254966)
			(xy 134.061814 -36.301479) (xy 134.024597 -36.343016) (xy 133.981729 -36.378691) (xy 133.934123 -36.407745)
			(xy 133.882794 -36.429557) (xy 133.828837 -36.443663) (xy 133.7734 -36.449763) (xy 133.717666 -36.447726)
			(xy 133.662823 -36.437596) (xy 133.610039 -36.419589) (xy 133.560439 -36.394088) (xy 133.515081 -36.361637)
			(xy 133.474932 -36.322928) (xy 133.440846 -36.278785) (xy 133.41355 -36.23015) (xy 133.393627 -36.178059)
			(xy 133.381501 -36.123622) (xy 133.37743 -36.068) (xy 132.896121 -36.068) (xy 132.885418 -36.119605)
			(xy 132.855097 -36.228042) (xy 132.817459 -36.334161) (xy 132.77268 -36.437469) (xy 132.720968 -36.537488)
			(xy 132.662564 -36.633752) (xy 132.597737 -36.725813) (xy 132.5626 -36.769802) (xy 132.5626 -36.8046)
			(xy 307.262782 -36.8046) (xy 307.266853 -36.748978) (xy 307.278979 -36.694541) (xy 307.298902 -36.64245)
			(xy 307.326198 -36.593815) (xy 307.360284 -36.549672) (xy 307.400433 -36.510963) (xy 307.445791 -36.478512)
			(xy 307.495391 -36.453011) (xy 307.548175 -36.435004) (xy 307.603018 -36.424874) (xy 307.658752 -36.422837)
			(xy 307.714189 -36.428937) (xy 307.768146 -36.443043) (xy 307.819475 -36.464855) (xy 307.867081 -36.493909)
			(xy 307.909949 -36.529584) (xy 307.927641 -36.54933) (xy 308.838852 -36.54933) (xy 308.842923 -36.493708)
			(xy 308.855049 -36.439271) (xy 308.874972 -36.38718) (xy 308.902268 -36.338545) (xy 308.936354 -36.294402)
			(xy 308.976503 -36.255693) (xy 309.021861 -36.223242) (xy 309.071461 -36.197741) (xy 309.124245 -36.179734)
			(xy 309.179088 -36.169604) (xy 309.234822 -36.167567) (xy 309.290259 -36.173667) (xy 309.344216 -36.187773)
			(xy 309.395545 -36.209585) (xy 309.443151 -36.238639) (xy 309.486019 -36.274314) (xy 309.523236 -36.315851)
			(xy 309.554009 -36.362364) (xy 309.577681 -36.412861) (xy 309.593749 -36.466268) (xy 309.601869 -36.521444)
			(xy 309.602378 -36.54933) (xy 309.601869 -36.577216) (xy 309.593749 -36.632392) (xy 309.577681 -36.685799)
			(xy 309.554009 -36.736296) (xy 309.523236 -36.782809) (xy 309.486019 -36.824346) (xy 309.443151 -36.860021)
			(xy 309.395545 -36.889075) (xy 309.344216 -36.910887) (xy 309.290259 -36.924993) (xy 309.234822 -36.931093)
			(xy 309.179088 -36.929056) (xy 309.124245 -36.918926) (xy 309.071461 -36.900919) (xy 309.021861 -36.875418)
			(xy 308.976503 -36.842967) (xy 308.936354 -36.804258) (xy 308.902268 -36.760115) (xy 308.874972 -36.71148)
			(xy 308.855049 -36.659389) (xy 308.842923 -36.604952) (xy 308.838852 -36.54933) (xy 307.927641 -36.54933)
			(xy 307.947166 -36.571121) (xy 307.977939 -36.617634) (xy 308.001611 -36.668131) (xy 308.017679 -36.721538)
			(xy 308.025799 -36.776714) (xy 308.026308 -36.8046) (xy 308.025799 -36.832486) (xy 308.017679 -36.887662)
			(xy 308.001611 -36.941069) (xy 307.977939 -36.991566) (xy 307.947166 -37.038079) (xy 307.909949 -37.079616)
			(xy 307.867081 -37.115291) (xy 307.819475 -37.144345) (xy 307.768146 -37.166157) (xy 307.714189 -37.180263)
			(xy 307.658752 -37.186363) (xy 307.603018 -37.184326) (xy 307.548175 -37.174196) (xy 307.495391 -37.156189)
			(xy 307.445791 -37.130688) (xy 307.400433 -37.098237) (xy 307.360284 -37.059528) (xy 307.326198 -37.015385)
			(xy 307.298902 -36.96675) (xy 307.278979 -36.914659) (xy 307.266853 -36.860222) (xy 307.262782 -36.8046)
			(xy 132.5626 -36.8046) (xy 132.5626 -37.338) (xy 156.577028 -37.338) (xy 156.581099 -37.282378) (xy 156.593225 -37.227941)
			(xy 156.613148 -37.17585) (xy 156.640444 -37.127215) (xy 156.67453 -37.083072) (xy 156.714679 -37.044363)
			(xy 156.760037 -37.011912) (xy 156.809637 -36.986411) (xy 156.862421 -36.968404) (xy 156.917264 -36.958274)
			(xy 156.972998 -36.956237) (xy 157.028435 -36.962337) (xy 157.082392 -36.976443) (xy 157.133721 -36.998255)
			(xy 157.181327 -37.027309) (xy 157.224195 -37.062984) (xy 157.261412 -37.104521) (xy 157.292185 -37.151034)
			(xy 157.315857 -37.201531) (xy 157.331925 -37.254938) (xy 157.340045 -37.310114) (xy 157.340554 -37.338)
			(xy 157.340045 -37.365886) (xy 157.331925 -37.421062) (xy 157.315857 -37.474469) (xy 157.292185 -37.524966)
			(xy 157.261412 -37.571479) (xy 157.224195 -37.613016) (xy 157.181327 -37.648691) (xy 157.133721 -37.677745)
			(xy 157.09641 -37.6936) (xy 158.665924 -37.6936) (xy 158.669995 -37.637978) (xy 158.682121 -37.583541)
			(xy 158.702044 -37.53145) (xy 158.72934 -37.482815) (xy 158.763426 -37.438672) (xy 158.803575 -37.399963)
			(xy 158.848933 -37.367512) (xy 158.898533 -37.342011) (xy 158.951317 -37.324004) (xy 159.00616 -37.313874)
			(xy 159.061894 -37.311837) (xy 159.117331 -37.317937) (xy 159.171288 -37.332043) (xy 159.222617 -37.353855)
			(xy 159.270223 -37.382909) (xy 159.313091 -37.418584) (xy 159.350308 -37.460121) (xy 159.381081 -37.506634)
			(xy 159.404753 -37.557131) (xy 159.420821 -37.610538) (xy 159.428941 -37.665714) (xy 159.42945 -37.6936)
			(xy 159.428941 -37.721486) (xy 159.420821 -37.776662) (xy 159.404753 -37.830069) (xy 159.381081 -37.880566)
			(xy 159.350308 -37.927079) (xy 159.313091 -37.968616) (xy 159.270223 -38.004291) (xy 159.222617 -38.033345)
			(xy 159.171288 -38.055157) (xy 159.117331 -38.069263) (xy 159.061894 -38.075363) (xy 159.00616 -38.073326)
			(xy 158.951317 -38.063196) (xy 158.898533 -38.045189) (xy 158.848933 -38.019688) (xy 158.803575 -37.987237)
			(xy 158.763426 -37.948528) (xy 158.72934 -37.904385) (xy 158.702044 -37.85575) (xy 158.682121 -37.803659)
			(xy 158.669995 -37.749222) (xy 158.665924 -37.6936) (xy 157.09641 -37.6936) (xy 157.082392 -37.699557)
			(xy 157.028435 -37.713663) (xy 156.972998 -37.719763) (xy 156.917264 -37.717726) (xy 156.862421 -37.707596)
			(xy 156.809637 -37.689589) (xy 156.760037 -37.664088) (xy 156.714679 -37.631637) (xy 156.67453 -37.592928)
			(xy 156.640444 -37.548785) (xy 156.613148 -37.50015) (xy 156.593225 -37.448059) (xy 156.581099 -37.393622)
			(xy 156.577028 -37.338) (xy 132.5626 -37.338) (xy 132.5626 -38.745261) (xy 216.636592 -38.745261)
			(xy 216.636592 -38.673939) (xy 216.644578 -38.603065) (xy 216.660448 -38.53353) (xy 216.684005 -38.46621)
			(xy 216.71495 -38.401951) (xy 216.752896 -38.34156) (xy 216.797365 -38.285798) (xy 216.847798 -38.235365)
			(xy 216.90356 -38.190896) (xy 216.963951 -38.15295) (xy 217.02821 -38.122005) (xy 217.09553 -38.098448)
			(xy 217.165065 -38.082578) (xy 217.235939 -38.074592) (xy 217.307261 -38.074592) (xy 217.378135 -38.082578)
			(xy 217.44767 -38.098448) (xy 217.51499 -38.122005) (xy 217.579249 -38.15295) (xy 217.63964 -38.190896)
			(xy 217.695402 -38.235365) (xy 217.745835 -38.285798) (xy 217.790304 -38.34156) (xy 217.82825 -38.401951)
			(xy 217.859195 -38.46621) (xy 217.882752 -38.53353) (xy 217.898622 -38.603065) (xy 217.906608 -38.673939)
			(xy 217.907108 -38.7096) (xy 217.906608 -38.745261) (xy 224.256592 -38.745261) (xy 224.256592 -38.673939)
			(xy 224.264578 -38.603065) (xy 224.280448 -38.53353) (xy 224.304005 -38.46621) (xy 224.33495 -38.401951)
			(xy 224.372896 -38.34156) (xy 224.417365 -38.285798) (xy 224.467798 -38.235365) (xy 224.52356 -38.190896)
			(xy 224.583951 -38.15295) (xy 224.64821 -38.122005) (xy 224.71553 -38.098448) (xy 224.785065 -38.082578)
			(xy 224.855939 -38.074592) (xy 224.927261 -38.074592) (xy 224.998135 -38.082578) (xy 225.06767 -38.098448)
			(xy 225.13499 -38.122005) (xy 225.199249 -38.15295) (xy 225.25964 -38.190896) (xy 225.315402 -38.235365)
			(xy 225.365835 -38.285798) (xy 225.410304 -38.34156) (xy 225.44825 -38.401951) (xy 225.479195 -38.46621)
			(xy 225.502752 -38.53353) (xy 225.518622 -38.603065) (xy 225.526608 -38.673939) (xy 225.527108 -38.7096)
			(xy 225.526608 -38.745261) (xy 231.876592 -38.745261) (xy 231.876592 -38.673939) (xy 231.884578 -38.603065)
			(xy 231.900448 -38.53353) (xy 231.924005 -38.46621) (xy 231.95495 -38.401951) (xy 231.992896 -38.34156)
			(xy 232.037365 -38.285798) (xy 232.087798 -38.235365) (xy 232.14356 -38.190896) (xy 232.203951 -38.15295)
			(xy 232.26821 -38.122005) (xy 232.33553 -38.098448) (xy 232.405065 -38.082578) (xy 232.475939 -38.074592)
			(xy 232.547261 -38.074592) (xy 232.618135 -38.082578) (xy 232.68767 -38.098448) (xy 232.75499 -38.122005)
			(xy 232.819249 -38.15295) (xy 232.87964 -38.190896) (xy 232.935402 -38.235365) (xy 232.985835 -38.285798)
			(xy 233.030304 -38.34156) (xy 233.06825 -38.401951) (xy 233.099195 -38.46621) (xy 233.122752 -38.53353)
			(xy 233.138622 -38.603065) (xy 233.146608 -38.673939) (xy 233.147108 -38.7096) (xy 233.146608 -38.745261)
			(xy 239.496592 -38.745261) (xy 239.496592 -38.673939) (xy 239.504578 -38.603065) (xy 239.520448 -38.53353)
			(xy 239.544005 -38.46621) (xy 239.57495 -38.401951) (xy 239.612896 -38.34156) (xy 239.657365 -38.285798)
			(xy 239.707798 -38.235365) (xy 239.76356 -38.190896) (xy 239.823951 -38.15295) (xy 239.88821 -38.122005)
			(xy 239.95553 -38.098448) (xy 240.025065 -38.082578) (xy 240.095939 -38.074592) (xy 240.167261 -38.074592)
			(xy 240.238135 -38.082578) (xy 240.30767 -38.098448) (xy 240.37499 -38.122005) (xy 240.439249 -38.15295)
			(xy 240.49964 -38.190896) (xy 240.555402 -38.235365) (xy 240.605835 -38.285798) (xy 240.650304 -38.34156)
			(xy 240.68825 -38.401951) (xy 240.719195 -38.46621) (xy 240.742752 -38.53353) (xy 240.758622 -38.603065)
			(xy 240.766608 -38.673939) (xy 240.767108 -38.7096) (xy 240.766608 -38.745261) (xy 247.116592 -38.745261)
			(xy 247.116592 -38.673939) (xy 247.124578 -38.603065) (xy 247.140448 -38.53353) (xy 247.164005 -38.46621)
			(xy 247.19495 -38.401951) (xy 247.232896 -38.34156) (xy 247.277365 -38.285798) (xy 247.327798 -38.235365)
			(xy 247.38356 -38.190896) (xy 247.443951 -38.15295) (xy 247.50821 -38.122005) (xy 247.57553 -38.098448)
			(xy 247.645065 -38.082578) (xy 247.715939 -38.074592) (xy 247.787261 -38.074592) (xy 247.858135 -38.082578)
			(xy 247.92767 -38.098448) (xy 247.99499 -38.122005) (xy 248.059249 -38.15295) (xy 248.11964 -38.190896)
			(xy 248.175402 -38.235365) (xy 248.225835 -38.285798) (xy 248.270304 -38.34156) (xy 248.30825 -38.401951)
			(xy 248.339195 -38.46621) (xy 248.362752 -38.53353) (xy 248.378622 -38.603065) (xy 248.386608 -38.673939)
			(xy 248.387108 -38.7096) (xy 248.386608 -38.745261) (xy 254.736592 -38.745261) (xy 254.736592 -38.673939)
			(xy 254.744578 -38.603065) (xy 254.760448 -38.53353) (xy 254.784005 -38.46621) (xy 254.81495 -38.401951)
			(xy 254.852896 -38.34156) (xy 254.897365 -38.285798) (xy 254.947798 -38.235365) (xy 255.00356 -38.190896)
			(xy 255.063951 -38.15295) (xy 255.12821 -38.122005) (xy 255.19553 -38.098448) (xy 255.265065 -38.082578)
			(xy 255.335939 -38.074592) (xy 255.407261 -38.074592) (xy 255.478135 -38.082578) (xy 255.54767 -38.098448)
			(xy 255.61499 -38.122005) (xy 255.679249 -38.15295) (xy 255.73964 -38.190896) (xy 255.795402 -38.235365)
			(xy 255.845835 -38.285798) (xy 255.890304 -38.34156) (xy 255.92825 -38.401951) (xy 255.959195 -38.46621)
			(xy 255.982752 -38.53353) (xy 255.998622 -38.603065) (xy 256.006608 -38.673939) (xy 256.007108 -38.7096)
			(xy 256.006608 -38.745261) (xy 262.356592 -38.745261) (xy 262.356592 -38.673939) (xy 262.364578 -38.603065)
			(xy 262.380448 -38.53353) (xy 262.404005 -38.46621) (xy 262.43495 -38.401951) (xy 262.472896 -38.34156)
			(xy 262.517365 -38.285798) (xy 262.567798 -38.235365) (xy 262.62356 -38.190896) (xy 262.683951 -38.15295)
			(xy 262.74821 -38.122005) (xy 262.81553 -38.098448) (xy 262.885065 -38.082578) (xy 262.955939 -38.074592)
			(xy 263.027261 -38.074592) (xy 263.098135 -38.082578) (xy 263.16767 -38.098448) (xy 263.23499 -38.122005)
			(xy 263.299249 -38.15295) (xy 263.35964 -38.190896) (xy 263.415402 -38.235365) (xy 263.465835 -38.285798)
			(xy 263.510304 -38.34156) (xy 263.54825 -38.401951) (xy 263.579195 -38.46621) (xy 263.602752 -38.53353)
			(xy 263.618622 -38.603065) (xy 263.626608 -38.673939) (xy 263.627108 -38.7096) (xy 263.626608 -38.745261)
			(xy 269.976592 -38.745261) (xy 269.976592 -38.673939) (xy 269.984578 -38.603065) (xy 270.000448 -38.53353)
			(xy 270.024005 -38.46621) (xy 270.05495 -38.401951) (xy 270.092896 -38.34156) (xy 270.137365 -38.285798)
			(xy 270.187798 -38.235365) (xy 270.24356 -38.190896) (xy 270.303951 -38.15295) (xy 270.36821 -38.122005)
			(xy 270.43553 -38.098448) (xy 270.505065 -38.082578) (xy 270.575939 -38.074592) (xy 270.647261 -38.074592)
			(xy 270.718135 -38.082578) (xy 270.78767 -38.098448) (xy 270.85499 -38.122005) (xy 270.919249 -38.15295)
			(xy 270.97964 -38.190896) (xy 271.035402 -38.235365) (xy 271.085835 -38.285798) (xy 271.130304 -38.34156)
			(xy 271.16825 -38.401951) (xy 271.199195 -38.46621) (xy 271.222752 -38.53353) (xy 271.238622 -38.603065)
			(xy 271.246608 -38.673939) (xy 271.247108 -38.7096) (xy 271.246608 -38.745261) (xy 277.596592 -38.745261)
			(xy 277.596592 -38.673939) (xy 277.604578 -38.603065) (xy 277.620448 -38.53353) (xy 277.644005 -38.46621)
			(xy 277.67495 -38.401951) (xy 277.712896 -38.34156) (xy 277.757365 -38.285798) (xy 277.807798 -38.235365)
			(xy 277.86356 -38.190896) (xy 277.923951 -38.15295) (xy 277.98821 -38.122005) (xy 278.05553 -38.098448)
			(xy 278.125065 -38.082578) (xy 278.195939 -38.074592) (xy 278.267261 -38.074592) (xy 278.338135 -38.082578)
			(xy 278.40767 -38.098448) (xy 278.47499 -38.122005) (xy 278.539249 -38.15295) (xy 278.59964 -38.190896)
			(xy 278.655402 -38.235365) (xy 278.705835 -38.285798) (xy 278.750304 -38.34156) (xy 278.78825 -38.401951)
			(xy 278.819195 -38.46621) (xy 278.842752 -38.53353) (xy 278.858622 -38.603065) (xy 278.866608 -38.673939)
			(xy 278.867108 -38.7096) (xy 278.866608 -38.745261) (xy 285.216592 -38.745261) (xy 285.216592 -38.673939)
			(xy 285.224578 -38.603065) (xy 285.240448 -38.53353) (xy 285.264005 -38.46621) (xy 285.29495 -38.401951)
			(xy 285.332896 -38.34156) (xy 285.377365 -38.285798) (xy 285.427798 -38.235365) (xy 285.48356 -38.190896)
			(xy 285.543951 -38.15295) (xy 285.60821 -38.122005) (xy 285.67553 -38.098448) (xy 285.745065 -38.082578)
			(xy 285.815939 -38.074592) (xy 285.887261 -38.074592) (xy 285.958135 -38.082578) (xy 286.02767 -38.098448)
			(xy 286.09499 -38.122005) (xy 286.159249 -38.15295) (xy 286.21964 -38.190896) (xy 286.275402 -38.235365)
			(xy 286.325835 -38.285798) (xy 286.370304 -38.34156) (xy 286.40825 -38.401951) (xy 286.439195 -38.46621)
			(xy 286.462752 -38.53353) (xy 286.478622 -38.603065) (xy 286.486608 -38.673939) (xy 286.487108 -38.7096)
			(xy 286.486608 -38.745261) (xy 292.836592 -38.745261) (xy 292.836592 -38.673939) (xy 292.844578 -38.603065)
			(xy 292.860448 -38.53353) (xy 292.884005 -38.46621) (xy 292.91495 -38.401951) (xy 292.952896 -38.34156)
			(xy 292.997365 -38.285798) (xy 293.047798 -38.235365) (xy 293.10356 -38.190896) (xy 293.163951 -38.15295)
			(xy 293.22821 -38.122005) (xy 293.29553 -38.098448) (xy 293.365065 -38.082578) (xy 293.435939 -38.074592)
			(xy 293.507261 -38.074592) (xy 293.578135 -38.082578) (xy 293.64767 -38.098448) (xy 293.71499 -38.122005)
			(xy 293.779249 -38.15295) (xy 293.83964 -38.190896) (xy 293.895402 -38.235365) (xy 293.945835 -38.285798)
			(xy 293.990304 -38.34156) (xy 294.02825 -38.401951) (xy 294.059195 -38.46621) (xy 294.082752 -38.53353)
			(xy 294.098622 -38.603065) (xy 294.106608 -38.673939) (xy 294.107108 -38.7096) (xy 294.106608 -38.745261)
			(xy 294.098622 -38.816135) (xy 294.082752 -38.88567) (xy 294.059195 -38.95299) (xy 294.02825 -39.017249)
			(xy 293.990304 -39.07764) (xy 293.945835 -39.133402) (xy 293.895402 -39.183835) (xy 293.83964 -39.228304)
			(xy 293.779249 -39.26625) (xy 293.71499 -39.297195) (xy 293.64767 -39.320752) (xy 293.578135 -39.336622)
			(xy 293.507261 -39.344608) (xy 293.435939 -39.344608) (xy 293.365065 -39.336622) (xy 293.29553 -39.320752)
			(xy 293.22821 -39.297195) (xy 293.163951 -39.26625) (xy 293.10356 -39.228304) (xy 293.047798 -39.183835)
			(xy 292.997365 -39.133402) (xy 292.952896 -39.07764) (xy 292.91495 -39.017249) (xy 292.884005 -38.95299)
			(xy 292.860448 -38.88567) (xy 292.844578 -38.816135) (xy 292.836592 -38.745261) (xy 286.486608 -38.745261)
			(xy 286.478622 -38.816135) (xy 286.462752 -38.88567) (xy 286.439195 -38.95299) (xy 286.40825 -39.017249)
			(xy 286.370304 -39.07764) (xy 286.325835 -39.133402) (xy 286.275402 -39.183835) (xy 286.21964 -39.228304)
			(xy 286.159249 -39.26625) (xy 286.09499 -39.297195) (xy 286.02767 -39.320752) (xy 285.958135 -39.336622)
			(xy 285.887261 -39.344608) (xy 285.815939 -39.344608) (xy 285.745065 -39.336622) (xy 285.67553 -39.320752)
			(xy 285.60821 -39.297195) (xy 285.543951 -39.26625) (xy 285.48356 -39.228304) (xy 285.427798 -39.183835)
			(xy 285.377365 -39.133402) (xy 285.332896 -39.07764) (xy 285.29495 -39.017249) (xy 285.264005 -38.95299)
			(xy 285.240448 -38.88567) (xy 285.224578 -38.816135) (xy 285.216592 -38.745261) (xy 278.866608 -38.745261)
			(xy 278.858622 -38.816135) (xy 278.842752 -38.88567) (xy 278.819195 -38.95299) (xy 278.78825 -39.017249)
			(xy 278.750304 -39.07764) (xy 278.705835 -39.133402) (xy 278.655402 -39.183835) (xy 278.59964 -39.228304)
			(xy 278.539249 -39.26625) (xy 278.47499 -39.297195) (xy 278.40767 -39.320752) (xy 278.338135 -39.336622)
			(xy 278.267261 -39.344608) (xy 278.195939 -39.344608) (xy 278.125065 -39.336622) (xy 278.05553 -39.320752)
			(xy 277.98821 -39.297195) (xy 277.923951 -39.26625) (xy 277.86356 -39.228304) (xy 277.807798 -39.183835)
			(xy 277.757365 -39.133402) (xy 277.712896 -39.07764) (xy 277.67495 -39.017249) (xy 277.644005 -38.95299)
			(xy 277.620448 -38.88567) (xy 277.604578 -38.816135) (xy 277.596592 -38.745261) (xy 271.246608 -38.745261)
			(xy 271.238622 -38.816135) (xy 271.222752 -38.88567) (xy 271.199195 -38.95299) (xy 271.16825 -39.017249)
			(xy 271.130304 -39.07764) (xy 271.085835 -39.133402) (xy 271.035402 -39.183835) (xy 270.97964 -39.228304)
			(xy 270.919249 -39.26625) (xy 270.85499 -39.297195) (xy 270.78767 -39.320752) (xy 270.718135 -39.336622)
			(xy 270.647261 -39.344608) (xy 270.575939 -39.344608) (xy 270.505065 -39.336622) (xy 270.43553 -39.320752)
			(xy 270.36821 -39.297195) (xy 270.303951 -39.26625) (xy 270.24356 -39.228304) (xy 270.187798 -39.183835)
			(xy 270.137365 -39.133402) (xy 270.092896 -39.07764) (xy 270.05495 -39.017249) (xy 270.024005 -38.95299)
			(xy 270.000448 -38.88567) (xy 269.984578 -38.816135) (xy 269.976592 -38.745261) (xy 263.626608 -38.745261)
			(xy 263.618622 -38.816135) (xy 263.602752 -38.88567) (xy 263.579195 -38.95299) (xy 263.54825 -39.017249)
			(xy 263.510304 -39.07764) (xy 263.465835 -39.133402) (xy 263.415402 -39.183835) (xy 263.35964 -39.228304)
			(xy 263.299249 -39.26625) (xy 263.23499 -39.297195) (xy 263.16767 -39.320752) (xy 263.098135 -39.336622)
			(xy 263.027261 -39.344608) (xy 262.955939 -39.344608) (xy 262.885065 -39.336622) (xy 262.81553 -39.320752)
			(xy 262.74821 -39.297195) (xy 262.683951 -39.26625) (xy 262.62356 -39.228304) (xy 262.567798 -39.183835)
			(xy 262.517365 -39.133402) (xy 262.472896 -39.07764) (xy 262.43495 -39.017249) (xy 262.404005 -38.95299)
			(xy 262.380448 -38.88567) (xy 262.364578 -38.816135) (xy 262.356592 -38.745261) (xy 256.006608 -38.745261)
			(xy 255.998622 -38.816135) (xy 255.982752 -38.88567) (xy 255.959195 -38.95299) (xy 255.92825 -39.017249)
			(xy 255.890304 -39.07764) (xy 255.845835 -39.133402) (xy 255.795402 -39.183835) (xy 255.73964 -39.228304)
			(xy 255.679249 -39.26625) (xy 255.61499 -39.297195) (xy 255.54767 -39.320752) (xy 255.478135 -39.336622)
			(xy 255.407261 -39.344608) (xy 255.335939 -39.344608) (xy 255.265065 -39.336622) (xy 255.19553 -39.320752)
			(xy 255.12821 -39.297195) (xy 255.063951 -39.26625) (xy 255.00356 -39.228304) (xy 254.947798 -39.183835)
			(xy 254.897365 -39.133402) (xy 254.852896 -39.07764) (xy 254.81495 -39.017249) (xy 254.784005 -38.95299)
			(xy 254.760448 -38.88567) (xy 254.744578 -38.816135) (xy 254.736592 -38.745261) (xy 248.386608 -38.745261)
			(xy 248.378622 -38.816135) (xy 248.362752 -38.88567) (xy 248.339195 -38.95299) (xy 248.30825 -39.017249)
			(xy 248.270304 -39.07764) (xy 248.225835 -39.133402) (xy 248.175402 -39.183835) (xy 248.11964 -39.228304)
			(xy 248.059249 -39.26625) (xy 247.99499 -39.297195) (xy 247.92767 -39.320752) (xy 247.858135 -39.336622)
			(xy 247.787261 -39.344608) (xy 247.715939 -39.344608) (xy 247.645065 -39.336622) (xy 247.57553 -39.320752)
			(xy 247.50821 -39.297195) (xy 247.443951 -39.26625) (xy 247.38356 -39.228304) (xy 247.327798 -39.183835)
			(xy 247.277365 -39.133402) (xy 247.232896 -39.07764) (xy 247.19495 -39.017249) (xy 247.164005 -38.95299)
			(xy 247.140448 -38.88567) (xy 247.124578 -38.816135) (xy 247.116592 -38.745261) (xy 240.766608 -38.745261)
			(xy 240.758622 -38.816135) (xy 240.742752 -38.88567) (xy 240.719195 -38.95299) (xy 240.68825 -39.017249)
			(xy 240.650304 -39.07764) (xy 240.605835 -39.133402) (xy 240.555402 -39.183835) (xy 240.49964 -39.228304)
			(xy 240.439249 -39.26625) (xy 240.37499 -39.297195) (xy 240.30767 -39.320752) (xy 240.238135 -39.336622)
			(xy 240.167261 -39.344608) (xy 240.095939 -39.344608) (xy 240.025065 -39.336622) (xy 239.95553 -39.320752)
			(xy 239.88821 -39.297195) (xy 239.823951 -39.26625) (xy 239.76356 -39.228304) (xy 239.707798 -39.183835)
			(xy 239.657365 -39.133402) (xy 239.612896 -39.07764) (xy 239.57495 -39.017249) (xy 239.544005 -38.95299)
			(xy 239.520448 -38.88567) (xy 239.504578 -38.816135) (xy 239.496592 -38.745261) (xy 233.146608 -38.745261)
			(xy 233.138622 -38.816135) (xy 233.122752 -38.88567) (xy 233.099195 -38.95299) (xy 233.06825 -39.017249)
			(xy 233.030304 -39.07764) (xy 232.985835 -39.133402) (xy 232.935402 -39.183835) (xy 232.87964 -39.228304)
			(xy 232.819249 -39.26625) (xy 232.75499 -39.297195) (xy 232.68767 -39.320752) (xy 232.618135 -39.336622)
			(xy 232.547261 -39.344608) (xy 232.475939 -39.344608) (xy 232.405065 -39.336622) (xy 232.33553 -39.320752)
			(xy 232.26821 -39.297195) (xy 232.203951 -39.26625) (xy 232.14356 -39.228304) (xy 232.087798 -39.183835)
			(xy 232.037365 -39.133402) (xy 231.992896 -39.07764) (xy 231.95495 -39.017249) (xy 231.924005 -38.95299)
			(xy 231.900448 -38.88567) (xy 231.884578 -38.816135) (xy 231.876592 -38.745261) (xy 225.526608 -38.745261)
			(xy 225.518622 -38.816135) (xy 225.502752 -38.88567) (xy 225.479195 -38.95299) (xy 225.44825 -39.017249)
			(xy 225.410304 -39.07764) (xy 225.365835 -39.133402) (xy 225.315402 -39.183835) (xy 225.25964 -39.228304)
			(xy 225.199249 -39.26625) (xy 225.13499 -39.297195) (xy 225.06767 -39.320752) (xy 224.998135 -39.336622)
			(xy 224.927261 -39.344608) (xy 224.855939 -39.344608) (xy 224.785065 -39.336622) (xy 224.71553 -39.320752)
			(xy 224.64821 -39.297195) (xy 224.583951 -39.26625) (xy 224.52356 -39.228304) (xy 224.467798 -39.183835)
			(xy 224.417365 -39.133402) (xy 224.372896 -39.07764) (xy 224.33495 -39.017249) (xy 224.304005 -38.95299)
			(xy 224.280448 -38.88567) (xy 224.264578 -38.816135) (xy 224.256592 -38.745261) (xy 217.906608 -38.745261)
			(xy 217.898622 -38.816135) (xy 217.882752 -38.88567) (xy 217.859195 -38.95299) (xy 217.82825 -39.017249)
			(xy 217.790304 -39.07764) (xy 217.745835 -39.133402) (xy 217.695402 -39.183835) (xy 217.63964 -39.228304)
			(xy 217.579249 -39.26625) (xy 217.51499 -39.297195) (xy 217.44767 -39.320752) (xy 217.378135 -39.336622)
			(xy 217.307261 -39.344608) (xy 217.235939 -39.344608) (xy 217.165065 -39.336622) (xy 217.09553 -39.320752)
			(xy 217.02821 -39.297195) (xy 216.963951 -39.26625) (xy 216.90356 -39.228304) (xy 216.847798 -39.183835)
			(xy 216.797365 -39.133402) (xy 216.752896 -39.07764) (xy 216.71495 -39.017249) (xy 216.684005 -38.95299)
			(xy 216.660448 -38.88567) (xy 216.644578 -38.816135) (xy 216.636592 -38.745261) (xy 132.5626 -38.745261)
			(xy 132.5626 -38.862) (xy 130.6576 -40.767) (xy 129.233422 -40.767) (xy 129.216778 -40.767518) (xy 129.184635 -40.776181)
			(xy 129.155831 -40.792869) (xy 129.14376 -40.804338) (xy 128.97739 -40.970708) (xy 119.494808 -40.970708)
			(xy 119.2911 -40.767) (xy 119.2022 -40.767) (xy 117.803422 -39.368222) (xy 117.787512 -39.352982)
			(xy 117.75145 -39.327678) (xy 117.711564 -39.308974) (xy 117.66905 -39.297431) (xy 117.625181 -39.293396)
			(xy 117.581275 -39.296989) (xy 117.538646 -39.308103) (xy 117.498574 -39.326404) (xy 117.462259 -39.351343)
			(xy 117.430792 -39.382174) (xy 117.405114 -39.41797) (xy 117.385997 -39.45766) (xy 117.379496 -39.478712)
			(xy 117.363433 -39.533694) (xy 117.324685 -39.641497) (xy 117.278561 -39.746357) (xy 117.225281 -39.847768)
			(xy 117.165102 -39.945244) (xy 117.098313 -40.038315) (xy 117.025236 -40.126535) (xy 116.94622 -40.209478)
			(xy 116.861648 -40.286747) (xy 116.771924 -40.35797) (xy 116.67748 -40.422804) (xy 116.578771 -40.480937)
			(xy 116.476271 -40.532091) (xy 116.370472 -40.57602) (xy 116.261884 -40.612511) (xy 116.151028 -40.64139)
			(xy 116.038438 -40.662518) (xy 115.924654 -40.675793) (xy 115.810224 -40.681152) (xy 115.695697 -40.678568)
			(xy 115.581625 -40.668055) (xy 115.468555 -40.649662) (xy 115.357032 -40.623478) (xy 115.247591 -40.589629)
			(xy 115.140759 -40.548278) (xy 115.037049 -40.499624) (xy 114.93696 -40.4439) (xy 114.840973 -40.381374)
			(xy 114.749549 -40.312347) (xy 114.663128 -40.23715) (xy 114.582126 -40.156146) (xy 114.506932 -40.069724)
			(xy 114.437907 -39.978299) (xy 114.375383 -39.88231) (xy 114.319661 -39.78222) (xy 114.271008 -39.678509)
			(xy 114.229659 -39.571676) (xy 114.195813 -39.462235) (xy 114.169631 -39.350711) (xy 114.151241 -39.237641)
			(xy 114.14073 -39.123569) (xy 114.138149 -39.009042) (xy 114.14351 -38.894612) (xy 114.156787 -38.780828)
			(xy 114.177918 -38.668238) (xy 114.206799 -38.557383) (xy 114.243293 -38.448795) (xy 114.287223 -38.342998)
			(xy 114.338379 -38.240498) (xy 114.396515 -38.141791) (xy 114.461351 -38.047348) (xy 114.532575 -37.957626)
			(xy 114.609846 -37.873055) (xy 114.692791 -37.794041) (xy 114.781012 -37.720966) (xy 114.874085 -37.654179)
			(xy 114.971561 -37.594002) (xy 115.072974 -37.540724) (xy 115.177835 -37.494602) (xy 115.285639 -37.455857)
			(xy 115.340638 -37.439854) (xy 115.361704 -37.433405) (xy 115.401389 -37.414279) (xy 115.43718 -37.388595)
			(xy 115.468003 -37.357123) (xy 115.492937 -37.320805) (xy 115.511232 -37.280731) (xy 115.52234 -37.238102)
			(xy 115.525928 -37.194195) (xy 115.52189 -37.150328) (xy 115.510345 -37.107815) (xy 115.49164 -37.067931)
			(xy 115.466335 -37.03187) (xy 115.451128 -37.015928) (xy 112.9157 -34.4805) (xy 112.70615 -34.4805)
			(xy 112.684151 -34.480964) (xy 112.640811 -34.488536) (xy 112.599424 -34.503463) (xy 112.561227 -34.525298)
			(xy 112.527364 -34.553388) (xy 112.498848 -34.586893) (xy 112.476532 -34.62481) (xy 112.461082 -34.666005)
			(xy 112.452962 -34.709246) (xy 112.452414 -34.753239) (xy 112.459454 -34.796669) (xy 112.473872 -34.838237)
			(xy 112.484154 -34.85769) (xy 112.504371 -34.895187) (xy 112.538463 -34.973265) (xy 112.565042 -35.054208)
			(xy 112.583873 -35.137296) (xy 112.594788 -35.221789) (xy 112.59769 -35.306935) (xy 112.592553 -35.391975)
			(xy 112.579422 -35.476153) (xy 112.558415 -35.558717) (xy 112.529719 -35.638934) (xy 112.493589 -35.716089)
			(xy 112.450347 -35.789495) (xy 112.400378 -35.858497) (xy 112.344127 -35.922482) (xy 112.282095 -35.98088)
			(xy 112.214835 -36.03317) (xy 112.142945 -36.078888) (xy 112.067065 -36.117625) (xy 111.987872 -36.149037)
			(xy 111.906071 -36.172844) (xy 111.82239 -36.188834) (xy 111.737574 -36.196865) (xy 111.652378 -36.196865)
			(xy 111.567562 -36.188834) (xy 111.483881 -36.172844) (xy 111.40208 -36.149037) (xy 111.322887 -36.117625)
			(xy 111.247007 -36.078888) (xy 111.175117 -36.03317) (xy 111.107857 -35.98088) (xy 111.045825 -35.922482)
			(xy 110.989574 -35.858497) (xy 110.939605 -35.789495) (xy 110.896363 -35.716089) (xy 110.860233 -35.638934)
			(xy 110.831537 -35.558717) (xy 110.81053 -35.476153) (xy 110.797399 -35.391975) (xy 110.792262 -35.306935)
			(xy 110.795164 -35.221789) (xy 110.806079 -35.137296) (xy 110.82491 -35.054208) (xy 110.851489 -34.973265)
			(xy 110.885581 -34.895187) (xy 110.905798 -34.85769) (xy 110.916057 -34.838232) (xy 110.930449 -34.796669)
			(xy 110.937468 -34.753249) (xy 110.936906 -34.709269) (xy 110.928778 -34.666042) (xy 110.913328 -34.624861)
			(xy 110.891018 -34.586956) (xy 110.862513 -34.553459) (xy 110.828665 -34.525371) (xy 110.790487 -34.503531)
			(xy 110.749117 -34.488593) (xy 110.705794 -34.481001) (xy 110.683802 -34.4805) (xy 92.8751 -34.4805)
			(xy 91.44 -33.0454) (xy 91.44 -31.507176) (xy 91.439454 -31.49053) (xy 91.430832 -31.458373) (xy 91.414182 -31.429543)
			(xy 91.390638 -31.406003) (xy 91.361805 -31.389359) (xy 91.329646 -31.380743) (xy 91.313 -31.380176)
			(xy 89.0778 -31.380176) (xy 89.048224 -31.37973) (xy 88.989515 -31.37251) (xy 88.932125 -31.358179)
			(xy 88.876914 -31.33695) (xy 88.824707 -31.309142) (xy 88.776284 -31.275169) (xy 88.732369 -31.23554)
			(xy 88.69362 -31.190848) (xy 88.676734 -31.166562) (xy 88.65997 -31.14167) (xy 88.602312 -31.108904)
			(xy 88.587653 -31.101264) (xy 88.555655 -31.093012) (xy 88.522611 -31.093265) (xy 88.490743 -31.102006)
			(xy 88.462193 -31.118646) (xy 88.450166 -31.129986) (xy 88.341708 -31.238444) (xy 88.341708 -31.7754)
			(xy 88.341191 -31.807031) (xy 88.332934 -31.869751) (xy 88.316561 -31.930857) (xy 88.292351 -31.989303)
			(xy 88.260721 -32.044088) (xy 88.22221 -32.094277) (xy 88.177477 -32.13901) (xy 88.127288 -32.177521)
			(xy 88.072503 -32.209151) (xy 88.014057 -32.233361) (xy 87.952951 -32.249734) (xy 87.890231 -32.257991)
			(xy 87.826969 -32.257991) (xy 87.764249 -32.249734) (xy 87.703143 -32.233361) (xy 87.644697 -32.209151)
			(xy 87.589912 -32.177521) (xy 87.539723 -32.13901) (xy 87.49499 -32.094277) (xy 87.456479 -32.044088)
			(xy 87.424849 -31.989303) (xy 87.400639 -31.930857) (xy 87.384266 -31.869751) (xy 87.376009 -31.807031)
			(xy 87.375492 -31.7754) (xy 87.375492 -30.83814) (xy 88.561672 -29.65196) (xy 90.531188 -29.65196)
			(xy 90.603578 -29.57957) (xy 90.613912 -29.568667) (xy 90.629629 -29.543075) (xy 90.638935 -29.514519)
			(xy 90.641315 -29.484581) (xy 90.636638 -29.454914) (xy 90.631264 -29.440886) (xy 90.611706 -29.39415)
			(xy 90.597228 -29.377894) (xy 90.596974 -29.37764) (xy 90.578614 -29.356411) (xy 90.54768 -29.309582)
			(xy 90.523937 -29.258727) (xy 90.507898 -29.204944) (xy 90.499908 -29.149392) (xy 90.500139 -29.093268)
			(xy 90.508587 -29.037783) (xy 90.525069 -28.984134) (xy 90.54923 -28.933477) (xy 90.580549 -28.886904)
			(xy 90.61835 -28.845419) (xy 90.66182 -28.809918) (xy 90.710019 -28.781165) (xy 90.76191 -28.759781)
			(xy 90.816372 -28.746226) (xy 90.872233 -28.740794) (xy 90.928287 -28.7436) (xy 90.983325 -28.754585)
			(xy 91.036162 -28.773511) (xy 91.085657 -28.799972) (xy 91.130744 -28.833395) (xy 91.150948 -28.852876)
			(xy 91.163066 -28.864315) (xy 91.191905 -28.880991) (xy 91.22408 -28.889623) (xy 91.257394 -28.889623)
			(xy 91.289569 -28.880991) (xy 91.318408 -28.864315) (xy 91.330526 -28.852876) (xy 91.44 -28.743402)
			(xy 91.44 -28.0924) (xy 94.893892 -24.638508) (xy 94.893892 -9.415526) (xy 96.591374 -7.718298) (xy 96.84004 -7.469632)
			(xy 96.85097 -7.457582) (xy 96.866883 -7.42922) (xy 96.875106 -7.397755) (xy 96.8756 -7.381494) (xy 96.8756 -3.048)
			(xy 95.9612 -2.1336) (xy 94.067122 -2.1336) (xy 94.045043 -2.134047) (xy 94.00154 -2.141628) (xy 93.960005 -2.156618)
			(xy 93.921687 -2.178565) (xy 93.887742 -2.206807) (xy 93.859192 -2.240494) (xy 93.836898 -2.278611)
			(xy 93.821531 -2.320009) (xy 93.813555 -2.36344) (xy 93.81321 -2.407597) (xy 93.820506 -2.451147)
			(xy 93.835223 -2.49278) (xy 93.856918 -2.531241) (xy 93.870526 -2.548636) (xy 93.893845 -2.57784)
			(xy 93.934901 -2.640291) (xy 93.969186 -2.706701) (xy 93.996322 -2.776339) (xy 94.016011 -2.848436)
			(xy 94.028036 -2.9222) (xy 94.032263 -2.996819) (xy 94.028648 -3.071469) (xy 94.017229 -3.145329)
			(xy 93.998132 -3.217586) (xy 93.971568 -3.287444) (xy 93.937829 -3.354133) (xy 93.897287 -3.416919)
			(xy 93.850388 -3.47511) (xy 93.797649 -3.528066) (xy 93.739651 -3.575203) (xy 93.677032 -3.616002)
			(xy 93.610482 -3.650015) (xy 93.540734 -3.676865) (xy 93.468556 -3.696258) (xy 93.394743 -3.70798)
			(xy 93.320108 -3.711901) (xy 93.245473 -3.70798) (xy 93.17166 -3.696258) (xy 93.099482 -3.676865)
			(xy 93.029734 -3.650015) (xy 92.963184 -3.616002) (xy 92.900565 -3.575203) (xy 92.842567 -3.528066)
			(xy 92.789828 -3.47511) (xy 92.742929 -3.416919) (xy 92.702387 -3.354133) (xy 92.668648 -3.287444)
			(xy 92.642084 -3.217586) (xy 92.622987 -3.145329) (xy 92.611568 -3.071469) (xy 92.607953 -2.996819)
			(xy 92.61218 -2.9222) (xy 92.624205 -2.848436) (xy 92.643894 -2.776339) (xy 92.67103 -2.706701) (xy 92.705315 -2.640291)
			(xy 92.746371 -2.57784) (xy 92.76969 -2.548636) (xy 92.78332 -2.531265) (xy 92.804992 -2.492801)
			(xy 92.819688 -2.451169) (xy 92.826968 -2.407623) (xy 92.82661 -2.363475) (xy 92.818628 -2.320053)
			(xy 92.803259 -2.278664) (xy 92.780968 -2.240555) (xy 92.752425 -2.206873) (xy 92.71849 -2.178631)
			(xy 92.680184 -2.15668) (xy 92.638661 -2.141681) (xy 92.595169 -2.134085) (xy 92.573094 -2.1336)
			(xy 92.067126 -2.1336) (xy 92.045046 -2.134047) (xy 92.001544 -2.141627) (xy 91.960007 -2.156617)
			(xy 91.921689 -2.178563) (xy 91.887743 -2.206806) (xy 91.859193 -2.240493) (xy 91.836898 -2.27861)
			(xy 91.821531 -2.320008) (xy 91.813555 -2.36344) (xy 91.81321 -2.407597) (xy 91.820506 -2.451149)
			(xy 91.835224 -2.492782) (xy 91.85692 -2.531243) (xy 91.87053 -2.548636) (xy 91.893849 -2.57784)
			(xy 91.934905 -2.640291) (xy 91.96919 -2.706701) (xy 91.996326 -2.776339) (xy 92.016015 -2.848436)
			(xy 92.02804 -2.9222) (xy 92.032267 -2.996819) (xy 92.028652 -3.071469) (xy 92.017233 -3.145329)
			(xy 91.998136 -3.217586) (xy 91.971572 -3.287444) (xy 91.937833 -3.354133) (xy 91.897291 -3.416919)
			(xy 91.850392 -3.47511) (xy 91.797653 -3.528066) (xy 91.739655 -3.575203) (xy 91.677036 -3.616002)
			(xy 91.610486 -3.650015) (xy 91.540738 -3.676865) (xy 91.46856 -3.696258) (xy 91.394747 -3.70798)
			(xy 91.320112 -3.711901) (xy 91.245477 -3.70798) (xy 91.171664 -3.696258) (xy 91.099486 -3.676865)
			(xy 91.029738 -3.650015) (xy 90.963188 -3.616002) (xy 90.900569 -3.575203) (xy 90.842571 -3.528066)
			(xy 90.789832 -3.47511) (xy 90.742933 -3.416919) (xy 90.702391 -3.354133) (xy 90.668652 -3.287444)
			(xy 90.642088 -3.217586) (xy 90.622991 -3.145329) (xy 90.611572 -3.071469) (xy 90.607957 -2.996819)
			(xy 90.612184 -2.9222) (xy 90.624209 -2.848436) (xy 90.643898 -2.776339) (xy 90.671034 -2.706701)
			(xy 90.705319 -2.640291) (xy 90.746375 -2.57784) (xy 90.769694 -2.548636) (xy 90.783324 -2.531265)
			(xy 90.804995 -2.4928) (xy 90.819692 -2.451168) (xy 90.826971 -2.407623) (xy 90.826614 -2.363474)
			(xy 90.818631 -2.320052) (xy 90.803262 -2.278664) (xy 90.780971 -2.240555) (xy 90.752429 -2.206872)
			(xy 90.718494 -2.17863) (xy 90.680188 -2.156679) (xy 90.638665 -2.141679) (xy 90.595173 -2.134082)
			(xy 90.573098 -2.1336) (xy 88.067134 -2.1336) (xy 88.045054 -2.134046) (xy 88.00155 -2.141626) (xy 87.960012 -2.156614)
			(xy 87.921692 -2.178561) (xy 87.887745 -2.206803) (xy 87.859194 -2.240491) (xy 87.836899 -2.278609)
			(xy 87.821531 -2.320008) (xy 87.813555 -2.363441) (xy 87.81321 -2.407599) (xy 87.820507 -2.451151)
			(xy 87.835225 -2.492785) (xy 87.856922 -2.531247) (xy 87.870538 -2.548636) (xy 87.893857 -2.57784)
			(xy 87.934913 -2.640291) (xy 87.969198 -2.706701) (xy 87.996334 -2.776339) (xy 88.016023 -2.848436)
			(xy 88.028048 -2.9222) (xy 88.032275 -2.996819) (xy 88.02866 -3.071469) (xy 88.017241 -3.145329)
			(xy 87.998144 -3.217586) (xy 87.97158 -3.287444) (xy 87.937841 -3.354133) (xy 87.897299 -3.416919)
			(xy 87.8504 -3.47511) (xy 87.797661 -3.528066) (xy 87.739663 -3.575203) (xy 87.677044 -3.616002)
			(xy 87.610494 -3.650015) (xy 87.540746 -3.676865) (xy 87.468568 -3.696258) (xy 87.394755 -3.70798)
			(xy 87.32012 -3.711901) (xy 87.245485 -3.70798) (xy 87.171672 -3.696258) (xy 87.099494 -3.676865)
			(xy 87.029746 -3.650015) (xy 86.963196 -3.616002) (xy 86.900577 -3.575203) (xy 86.842579 -3.528066)
			(xy 86.78984 -3.47511) (xy 86.742941 -3.416919) (xy 86.702399 -3.354133) (xy 86.66866 -3.287444)
			(xy 86.642096 -3.217586) (xy 86.622999 -3.145329) (xy 86.61158 -3.071469) (xy 86.607965 -2.996819)
			(xy 86.612192 -2.9222) (xy 86.624217 -2.848436) (xy 86.643906 -2.776339) (xy 86.671042 -2.706701)
			(xy 86.705327 -2.640291) (xy 86.746383 -2.57784) (xy 86.769702 -2.548636) (xy 86.783332 -2.531265)
			(xy 86.805002 -2.492799) (xy 86.819698 -2.451167) (xy 86.826977 -2.407622) (xy 86.82662 -2.363473)
			(xy 86.818637 -2.320051) (xy 86.803269 -2.278663) (xy 86.780978 -2.240553) (xy 86.752436 -2.20687)
			(xy 86.718501 -2.178627) (xy 86.680196 -2.156675) (xy 86.638672 -2.141674) (xy 86.595181 -2.134077)
			(xy 86.573106 -2.1336) (xy 86.067138 -2.1336) (xy 86.045057 -2.134046) (xy 86.001553 -2.141625) (xy 85.960015 -2.156613)
			(xy 85.921694 -2.178559) (xy 85.887747 -2.206802) (xy 85.859195 -2.24049) (xy 85.836899 -2.278608)
			(xy 85.821531 -2.320008) (xy 85.813555 -2.363441) (xy 85.81321 -2.4076) (xy 85.820507 -2.451152)
			(xy 85.835226 -2.492787) (xy 85.856924 -2.531249) (xy 85.870542 -2.548636) (xy 85.893861 -2.57784)
			(xy 85.934917 -2.640291) (xy 85.969202 -2.706701) (xy 85.996338 -2.776339) (xy 86.016027 -2.848436)
			(xy 86.028052 -2.9222) (xy 86.032279 -2.996819) (xy 86.028664 -3.071469) (xy 86.017245 -3.145329)
			(xy 85.998148 -3.217586) (xy 85.971584 -3.287444) (xy 85.937845 -3.354133) (xy 85.897303 -3.416919)
			(xy 85.850404 -3.47511) (xy 85.797665 -3.528066) (xy 85.739667 -3.575203) (xy 85.677048 -3.616002)
			(xy 85.610498 -3.650015) (xy 85.54075 -3.676865) (xy 85.468572 -3.696258) (xy 85.394759 -3.70798)
			(xy 85.320124 -3.711901) (xy 85.245489 -3.70798) (xy 85.171676 -3.696258) (xy 85.099498 -3.676865)
			(xy 85.02975 -3.650015) (xy 84.9632 -3.616002) (xy 84.900581 -3.575203) (xy 84.842583 -3.528066)
			(xy 84.789844 -3.47511) (xy 84.742945 -3.416919) (xy 84.702403 -3.354133) (xy 84.668664 -3.287444)
			(xy 84.6421 -3.217586) (xy 84.623003 -3.145329) (xy 84.611584 -3.071469) (xy 84.607969 -2.996819)
			(xy 84.612196 -2.9222) (xy 84.624221 -2.848436) (xy 84.64391 -2.776339) (xy 84.671046 -2.706701)
			(xy 84.705331 -2.640291) (xy 84.746387 -2.57784) (xy 84.769706 -2.548636) (xy 84.783336 -2.531265)
			(xy 84.805006 -2.492799) (xy 84.819702 -2.451167) (xy 84.82698 -2.407621) (xy 84.826623 -2.363473)
			(xy 84.81864 -2.320051) (xy 84.803272 -2.278662) (xy 84.780981 -2.240552) (xy 84.752439 -2.206869)
			(xy 84.718505 -2.178626) (xy 84.680199 -2.156674) (xy 84.638676 -2.141672) (xy 84.595185 -2.134074)
			(xy 84.57311 -2.1336) (xy 79.563976 -2.1336) (xy 79.542129 -2.134074) (xy 79.499086 -2.141586) (xy 79.457962 -2.156351)
			(xy 79.41997 -2.177932) (xy 79.38623 -2.205695) (xy 79.357736 -2.23882) (xy 79.335329 -2.276331)
			(xy 79.319669 -2.317122) (xy 79.311217 -2.359991) (xy 79.310223 -2.403674) (xy 79.316716 -2.446882)
			(xy 79.330505 -2.488344) (xy 79.351183 -2.526835) (xy 79.37814 -2.561222) (xy 79.410583 -2.59049)
			(xy 79.428848 -2.602484) (xy 79.491665 -2.64259) (xy 79.613468 -2.728502) (xy 79.730585 -2.820701)
			(xy 79.842691 -2.918932) (xy 79.949475 -3.022922) (xy 80.050643 -3.132385) (xy 80.145914 -3.247016)
			(xy 80.235024 -3.366499) (xy 80.317728 -3.490503) (xy 80.393796 -3.618686) (xy 80.463017 -3.750691)
			(xy 80.5252 -3.886154) (xy 80.580173 -4.024699) (xy 80.627784 -4.165944) (xy 80.6679 -4.309498) (xy 80.700412 -4.454962)
			(xy 80.725228 -4.601935) (xy 80.742281 -4.75001) (xy 80.751523 -4.898777) (xy 80.752475 -4.999736)
			(xy 90.607899 -4.999736) (xy 90.611934 -4.924032) (xy 90.623993 -4.849187) (xy 90.643939 -4.776046)
			(xy 90.671546 -4.705441) (xy 90.706502 -4.63817) (xy 90.74841 -4.574995) (xy 90.796796 -4.516633)
			(xy 90.851112 -4.463745) (xy 90.910741 -4.41693) (xy 90.975009 -4.376718) (xy 91.043186 -4.343566)
			(xy 91.114502 -4.317848) (xy 91.188147 -4.299856) (xy 91.263287 -4.289794) (xy 91.339071 -4.287775)
			(xy 91.414641 -4.293824) (xy 91.489139 -4.307871) (xy 91.561722 -4.329757) (xy 91.631568 -4.359234)
			(xy 91.697885 -4.395969) (xy 91.759921 -4.439544) (xy 91.816974 -4.489466) (xy 91.868398 -4.54517)
			(xy 91.913609 -4.606025) (xy 91.952096 -4.67134) (xy 91.983422 -4.740376) (xy 92.007232 -4.812351)
			(xy 92.023257 -4.886449) (xy 92.031316 -4.96183) (xy 92.03182 -4.999736) (xy 92.607895 -4.999736)
			(xy 92.61193 -4.924032) (xy 92.623989 -4.849187) (xy 92.643935 -4.776046) (xy 92.671542 -4.705441)
			(xy 92.706498 -4.63817) (xy 92.748406 -4.574995) (xy 92.796792 -4.516633) (xy 92.851108 -4.463745)
			(xy 92.910737 -4.41693) (xy 92.975005 -4.376718) (xy 93.043182 -4.343566) (xy 93.114498 -4.317848)
			(xy 93.188143 -4.299856) (xy 93.263283 -4.289794) (xy 93.339067 -4.287775) (xy 93.414637 -4.293824)
			(xy 93.489135 -4.307871) (xy 93.561718 -4.329757) (xy 93.631564 -4.359234) (xy 93.697881 -4.395969)
			(xy 93.759917 -4.439544) (xy 93.81697 -4.489466) (xy 93.868394 -4.54517) (xy 93.913605 -4.606025)
			(xy 93.952092 -4.67134) (xy 93.983418 -4.740376) (xy 94.007228 -4.812351) (xy 94.023253 -4.886449)
			(xy 94.031312 -4.96183) (xy 94.031816 -4.999736) (xy 94.031312 -5.037642) (xy 94.023253 -5.113023)
			(xy 94.007228 -5.187121) (xy 93.983418 -5.259096) (xy 93.952092 -5.328132) (xy 93.913605 -5.393447)
			(xy 93.868394 -5.454302) (xy 93.81697 -5.510006) (xy 93.759917 -5.559928) (xy 93.697881 -5.603503)
			(xy 93.631564 -5.640238) (xy 93.561718 -5.669715) (xy 93.489135 -5.691601) (xy 93.414637 -5.705648)
			(xy 93.339067 -5.711697) (xy 93.263283 -5.709678) (xy 93.188143 -5.699616) (xy 93.114498 -5.681624)
			(xy 93.043182 -5.655906) (xy 92.975005 -5.622754) (xy 92.910737 -5.582542) (xy 92.851108 -5.535727)
			(xy 92.796792 -5.482839) (xy 92.748406 -5.424477) (xy 92.706498 -5.361302) (xy 92.671542 -5.294031)
			(xy 92.643935 -5.223426) (xy 92.623989 -5.150285) (xy 92.61193 -5.07544) (xy 92.607895 -4.999736)
			(xy 92.03182 -4.999736) (xy 92.031316 -5.037642) (xy 92.023257 -5.113023) (xy 92.007232 -5.187121)
			(xy 91.983422 -5.259096) (xy 91.952096 -5.328132) (xy 91.913609 -5.393447) (xy 91.868398 -5.454302)
			(xy 91.816974 -5.510006) (xy 91.759921 -5.559928) (xy 91.697885 -5.603503) (xy 91.631568 -5.640238)
			(xy 91.561722 -5.669715) (xy 91.489139 -5.691601) (xy 91.414641 -5.705648) (xy 91.339071 -5.711697)
			(xy 91.263287 -5.709678) (xy 91.188147 -5.699616) (xy 91.114502 -5.681624) (xy 91.043186 -5.655906)
			(xy 90.975009 -5.622754) (xy 90.910741 -5.582542) (xy 90.851112 -5.535727) (xy 90.796796 -5.482839)
			(xy 90.74841 -5.424477) (xy 90.706502 -5.361302) (xy 90.671546 -5.294031) (xy 90.643939 -5.223426)
			(xy 90.623993 -5.150285) (xy 90.611934 -5.07544) (xy 90.607899 -4.999736) (xy 80.752475 -4.999736)
			(xy 80.752928 -5.047824) (xy 80.746492 -5.196738) (xy 80.732234 -5.345108) (xy 80.710193 -5.492523)
			(xy 80.68043 -5.638574) (xy 80.643027 -5.782859) (xy 80.598088 -5.924976) (xy 80.545737 -6.064534)
			(xy 80.486118 -6.201145) (xy 80.419398 -6.334432) (xy 80.345761 -6.464025) (xy 80.26541 -6.589566)
			(xy 80.178568 -6.710708) (xy 80.085475 -6.827116) (xy 79.986389 -6.938466) (xy 79.925805 -6.999732)
			(xy 90.607899 -6.999732) (xy 90.611934 -6.924028) (xy 90.623993 -6.849183) (xy 90.643939 -6.776042)
			(xy 90.671546 -6.705437) (xy 90.706502 -6.638166) (xy 90.74841 -6.574991) (xy 90.796796 -6.516629)
			(xy 90.851112 -6.463741) (xy 90.910741 -6.416926) (xy 90.975009 -6.376714) (xy 91.043186 -6.343562)
			(xy 91.114502 -6.317844) (xy 91.188147 -6.299852) (xy 91.263287 -6.28979) (xy 91.339071 -6.287771)
			(xy 91.414641 -6.29382) (xy 91.489139 -6.307867) (xy 91.561722 -6.329753) (xy 91.631568 -6.35923)
			(xy 91.697885 -6.395965) (xy 91.759921 -6.43954) (xy 91.816974 -6.489462) (xy 91.868398 -6.545166)
			(xy 91.913609 -6.606021) (xy 91.952096 -6.671336) (xy 91.983422 -6.740372) (xy 92.007232 -6.812347)
			(xy 92.023257 -6.886445) (xy 92.031316 -6.961826) (xy 92.03182 -6.999732) (xy 92.607895 -6.999732)
			(xy 92.61193 -6.924028) (xy 92.623989 -6.849183) (xy 92.643935 -6.776042) (xy 92.671542 -6.705437)
			(xy 92.706498 -6.638166) (xy 92.748406 -6.574991) (xy 92.796792 -6.516629) (xy 92.851108 -6.463741)
			(xy 92.910737 -6.416926) (xy 92.975005 -6.376714) (xy 93.043182 -6.343562) (xy 93.114498 -6.317844)
			(xy 93.188143 -6.299852) (xy 93.263283 -6.28979) (xy 93.339067 -6.287771) (xy 93.414637 -6.29382)
			(xy 93.489135 -6.307867) (xy 93.561718 -6.329753) (xy 93.631564 -6.35923) (xy 93.697881 -6.395965)
			(xy 93.759917 -6.43954) (xy 93.81697 -6.489462) (xy 93.868394 -6.545166) (xy 93.913605 -6.606021)
			(xy 93.952092 -6.671336) (xy 93.983418 -6.740372) (xy 94.007228 -6.812347) (xy 94.023253 -6.886445)
			(xy 94.031312 -6.961826) (xy 94.031816 -6.999732) (xy 94.031312 -7.037638) (xy 94.023253 -7.113019)
			(xy 94.007228 -7.187117) (xy 93.983418 -7.259092) (xy 93.952092 -7.328128) (xy 93.913605 -7.393443)
			(xy 93.868394 -7.454298) (xy 93.81697 -7.510002) (xy 93.759917 -7.559924) (xy 93.697881 -7.603499)
			(xy 93.631564 -7.640234) (xy 93.561718 -7.669711) (xy 93.489135 -7.691597) (xy 93.414637 -7.705644)
			(xy 93.339067 -7.711693) (xy 93.263283 -7.709674) (xy 93.188143 -7.699612) (xy 93.114498 -7.68162)
			(xy 93.043182 -7.655902) (xy 92.975005 -7.62275) (xy 92.910737 -7.582538) (xy 92.851108 -7.535723)
			(xy 92.796792 -7.482835) (xy 92.748406 -7.424473) (xy 92.706498 -7.361298) (xy 92.671542 -7.294027)
			(xy 92.643935 -7.223422) (xy 92.623989 -7.150281) (xy 92.61193 -7.075436) (xy 92.607895 -6.999732)
			(xy 92.03182 -6.999732) (xy 92.031316 -7.037638) (xy 92.023257 -7.113019) (xy 92.007232 -7.187117)
			(xy 91.983422 -7.259092) (xy 91.952096 -7.328128) (xy 91.913609 -7.393443) (xy 91.868398 -7.454298)
			(xy 91.816974 -7.510002) (xy 91.759921 -7.559924) (xy 91.697885 -7.603499) (xy 91.631568 -7.640234)
			(xy 91.561722 -7.669711) (xy 91.489139 -7.691597) (xy 91.414641 -7.705644) (xy 91.339071 -7.711693)
			(xy 91.263287 -7.709674) (xy 91.188147 -7.699612) (xy 91.114502 -7.68162) (xy 91.043186 -7.655902)
			(xy 90.975009 -7.62275) (xy 90.910741 -7.582538) (xy 90.851112 -7.535723) (xy 90.796796 -7.482835)
			(xy 90.74841 -7.424473) (xy 90.706502 -7.361298) (xy 90.671546 -7.294027) (xy 90.643939 -7.223422)
			(xy 90.623993 -7.150281) (xy 90.611934 -7.075436) (xy 90.607899 -6.999732) (xy 79.925805 -6.999732)
			(xy 79.881584 -7.044451) (xy 79.77135 -7.144778) (xy 79.655993 -7.239169) (xy 79.535831 -7.327362)
			(xy 79.411197 -7.409114) (xy 79.282436 -7.484198) (xy 79.149905 -7.552407) (xy 79.082138 -7.583424)
			(xy 79.061865 -7.593054) (xy 79.024797 -7.618351) (xy 78.992754 -7.649772) (xy 78.966735 -7.686336)
			(xy 78.947549 -7.726905) (xy 78.935794 -7.770216) (xy 78.931837 -7.814918) (xy 78.9358 -7.85962)
			(xy 78.947561 -7.902929) (xy 78.966753 -7.943496) (xy 78.992778 -7.980056) (xy 79.024826 -8.011472)
			(xy 79.061897 -8.036764) (xy 79.082138 -8.046466) (xy 79.150802 -8.077896) (xy 79.285041 -8.147102)
			(xy 79.415402 -8.223363) (xy 79.541513 -8.306462) (xy 79.663017 -8.396163) (xy 79.779569 -8.492211)
			(xy 79.890837 -8.594333) (xy 79.996505 -8.70224) (xy 80.096274 -8.815623) (xy 80.189858 -8.934162)
			(xy 80.276993 -9.057519) (xy 80.357431 -9.185344) (xy 80.430944 -9.317274) (xy 80.497322 -9.452934)
			(xy 80.540334 -9.554177) (xy 87.833696 -9.554177) (xy 87.833696 -9.445531) (xy 87.841627 -9.337174)
			(xy 87.857446 -9.229685) (xy 87.881069 -9.123638) (xy 87.91237 -9.019598) (xy 87.951182 -8.91812)
			(xy 87.997297 -8.819746) (xy 88.050471 -8.725001) (xy 88.110419 -8.63439) (xy 88.176821 -8.548396)
			(xy 88.249323 -8.467479) (xy 88.327538 -8.392071) (xy 88.411049 -8.322572) (xy 88.49941 -8.259355)
			(xy 88.59215 -8.202757) (xy 88.688774 -8.153079) (xy 88.788766 -8.110587) (xy 88.891594 -8.075507)
			(xy 88.996708 -8.048027) (xy 89.103547 -8.028292) (xy 89.211542 -8.016409) (xy 89.320116 -8.012442)
			(xy 89.42869 -8.016409) (xy 89.536685 -8.028292) (xy 89.643524 -8.048027) (xy 89.748638 -8.075507)
			(xy 89.851466 -8.110587) (xy 89.951458 -8.153079) (xy 90.048082 -8.202757) (xy 90.140822 -8.259355)
			(xy 90.229183 -8.322572) (xy 90.312694 -8.392071) (xy 90.390909 -8.467479) (xy 90.463411 -8.548396)
			(xy 90.529813 -8.63439) (xy 90.589761 -8.725001) (xy 90.642935 -8.819746) (xy 90.68905 -8.91812)
			(xy 90.727862 -9.019598) (xy 90.759163 -9.123638) (xy 90.782786 -9.229685) (xy 90.798605 -9.337174)
			(xy 90.806536 -9.445531) (xy 90.807032 -9.499854) (xy 90.806536 -9.554177) (xy 90.798605 -9.662534)
			(xy 90.782786 -9.770023) (xy 90.759163 -9.87607) (xy 90.727862 -9.98011) (xy 90.68905 -10.081588)
			(xy 90.642935 -10.179962) (xy 90.589761 -10.274707) (xy 90.529813 -10.365318) (xy 90.463411 -10.451312)
			(xy 90.390909 -10.532229) (xy 90.312694 -10.607637) (xy 90.229183 -10.677136) (xy 90.140822 -10.740353)
			(xy 90.048082 -10.796951) (xy 89.951458 -10.846629) (xy 89.851466 -10.889121) (xy 89.748638 -10.924201)
			(xy 89.643524 -10.951681) (xy 89.536685 -10.971416) (xy 89.42869 -10.983299) (xy 89.320116 -10.987267)
			(xy 89.211542 -10.983299) (xy 89.103547 -10.971416) (xy 88.996708 -10.951681) (xy 88.891594 -10.924201)
			(xy 88.788766 -10.889121) (xy 88.688774 -10.846629) (xy 88.59215 -10.796951) (xy 88.49941 -10.740353)
			(xy 88.411049 -10.677136) (xy 88.327538 -10.607637) (xy 88.249323 -10.532229) (xy 88.176821 -10.451312)
			(xy 88.110419 -10.365318) (xy 88.050471 -10.274707) (xy 87.997297 -10.179962) (xy 87.951182 -10.081588)
			(xy 87.91237 -9.98011) (xy 87.881069 -9.87607) (xy 87.857446 -9.770023) (xy 87.841627 -9.662534)
			(xy 87.833696 -9.554177) (xy 80.540334 -9.554177) (xy 80.556377 -9.591938) (xy 80.607941 -9.733891)
			(xy 80.651867 -9.87839) (xy 80.688031 -10.025025) (xy 80.71633 -10.173378) (xy 80.736684 -10.323029)
			(xy 80.749035 -10.473551) (xy 80.753347 -10.624518) (xy 80.749608 -10.7755) (xy 80.73783 -10.926068)
			(xy 80.728097 -10.999724) (xy 90.607899 -10.999724) (xy 90.611934 -10.92402) (xy 90.623993 -10.849175)
			(xy 90.643939 -10.776034) (xy 90.671546 -10.705429) (xy 90.706502 -10.638158) (xy 90.74841 -10.574983)
			(xy 90.796796 -10.516621) (xy 90.851112 -10.463733) (xy 90.910741 -10.416918) (xy 90.975009 -10.376706)
			(xy 91.043186 -10.343554) (xy 91.114502 -10.317836) (xy 91.188147 -10.299844) (xy 91.263287 -10.289782)
			(xy 91.339071 -10.287763) (xy 91.414641 -10.293812) (xy 91.489139 -10.307859) (xy 91.561722 -10.329745)
			(xy 91.631568 -10.359222) (xy 91.697885 -10.395957) (xy 91.759921 -10.439532) (xy 91.816974 -10.489454)
			(xy 91.868398 -10.545158) (xy 91.913609 -10.606013) (xy 91.952096 -10.671328) (xy 91.983422 -10.740364)
			(xy 92.007232 -10.812339) (xy 92.023257 -10.886437) (xy 92.031316 -10.961818) (xy 92.03182 -10.999724)
			(xy 92.607895 -10.999724) (xy 92.61193 -10.92402) (xy 92.623989 -10.849175) (xy 92.643935 -10.776034)
			(xy 92.671542 -10.705429) (xy 92.706498 -10.638158) (xy 92.748406 -10.574983) (xy 92.796792 -10.516621)
			(xy 92.851108 -10.463733) (xy 92.910737 -10.416918) (xy 92.975005 -10.376706) (xy 93.043182 -10.343554)
			(xy 93.114498 -10.317836) (xy 93.188143 -10.299844) (xy 93.263283 -10.289782) (xy 93.339067 -10.287763)
			(xy 93.414637 -10.293812) (xy 93.489135 -10.307859) (xy 93.561718 -10.329745) (xy 93.631564 -10.359222)
			(xy 93.697881 -10.395957) (xy 93.759917 -10.439532) (xy 93.81697 -10.489454) (xy 93.868394 -10.545158)
			(xy 93.913605 -10.606013) (xy 93.952092 -10.671328) (xy 93.983418 -10.740364) (xy 94.007228 -10.812339)
			(xy 94.023253 -10.886437) (xy 94.031312 -10.961818) (xy 94.031816 -10.999724) (xy 94.031312 -11.03763)
			(xy 94.023253 -11.113011) (xy 94.007228 -11.187109) (xy 93.983418 -11.259084) (xy 93.952092 -11.32812)
			(xy 93.913605 -11.393435) (xy 93.868394 -11.45429) (xy 93.81697 -11.509994) (xy 93.759917 -11.559916)
			(xy 93.697881 -11.603491) (xy 93.631564 -11.640226) (xy 93.561718 -11.669703) (xy 93.489135 -11.691589)
			(xy 93.414637 -11.705636) (xy 93.339067 -11.711685) (xy 93.263283 -11.709666) (xy 93.188143 -11.699604)
			(xy 93.114498 -11.681612) (xy 93.043182 -11.655894) (xy 92.975005 -11.622742) (xy 92.910737 -11.58253)
			(xy 92.851108 -11.535715) (xy 92.796792 -11.482827) (xy 92.748406 -11.424465) (xy 92.706498 -11.36129)
			(xy 92.671542 -11.294019) (xy 92.643935 -11.223414) (xy 92.623989 -11.150273) (xy 92.61193 -11.075428)
			(xy 92.607895 -10.999724) (xy 92.03182 -10.999724) (xy 92.031316 -11.03763) (xy 92.023257 -11.113011)
			(xy 92.007232 -11.187109) (xy 91.983422 -11.259084) (xy 91.952096 -11.32812) (xy 91.913609 -11.393435)
			(xy 91.868398 -11.45429) (xy 91.816974 -11.509994) (xy 91.759921 -11.559916) (xy 91.697885 -11.603491)
			(xy 91.631568 -11.640226) (xy 91.561722 -11.669703) (xy 91.489139 -11.691589) (xy 91.414641 -11.705636)
			(xy 91.339071 -11.711685) (xy 91.263287 -11.709666) (xy 91.188147 -11.699604) (xy 91.114502 -11.681612)
			(xy 91.043186 -11.655894) (xy 90.975009 -11.622742) (xy 90.910741 -11.58253) (xy 90.851112 -11.535715)
			(xy 90.796796 -11.482827) (xy 90.74841 -11.424465) (xy 90.706502 -11.36129) (xy 90.671546 -11.294019)
			(xy 90.643939 -11.223414) (xy 90.623993 -11.150273) (xy 90.611934 -11.075428) (xy 90.607899 -10.999724)
			(xy 80.728097 -10.999724) (xy 80.718045 -11.075795) (xy 80.690309 -11.224255) (xy 80.654703 -11.371026)
			(xy 80.611325 -11.515691) (xy 80.560301 -11.657839) (xy 80.501775 -11.797066) (xy 80.435913 -11.932977)
			(xy 80.362902 -12.065185) (xy 80.28295 -12.193315) (xy 80.196285 -12.317002) (xy 80.103151 -12.435896)
			(xy 80.003814 -12.549658) (xy 79.898557 -12.657964) (xy 79.787677 -12.760509) (xy 79.671491 -12.856999)
			(xy 79.550329 -12.947161) (xy 79.471221 -12.99972) (xy 90.607899 -12.99972) (xy 90.611934 -12.924016)
			(xy 90.623993 -12.849171) (xy 90.643939 -12.77603) (xy 90.671546 -12.705425) (xy 90.706502 -12.638154)
			(xy 90.74841 -12.574979) (xy 90.796796 -12.516617) (xy 90.851112 -12.463729) (xy 90.910741 -12.416914)
			(xy 90.975009 -12.376702) (xy 91.043186 -12.34355) (xy 91.114502 -12.317832) (xy 91.188147 -12.29984)
			(xy 91.263287 -12.289778) (xy 91.339071 -12.287759) (xy 91.414641 -12.293808) (xy 91.489139 -12.307855)
			(xy 91.561722 -12.329741) (xy 91.631568 -12.359218) (xy 91.697885 -12.395953) (xy 91.759921 -12.439528)
			(xy 91.816974 -12.48945) (xy 91.868398 -12.545154) (xy 91.913609 -12.606009) (xy 91.952096 -12.671324)
			(xy 91.983422 -12.74036) (xy 92.007232 -12.812335) (xy 92.023257 -12.886433) (xy 92.031316 -12.961814)
			(xy 92.03182 -12.99972) (xy 92.607895 -12.99972) (xy 92.61193 -12.924016) (xy 92.623989 -12.849171)
			(xy 92.643935 -12.77603) (xy 92.671542 -12.705425) (xy 92.706498 -12.638154) (xy 92.748406 -12.574979)
			(xy 92.796792 -12.516617) (xy 92.851108 -12.463729) (xy 92.910737 -12.416914) (xy 92.975005 -12.376702)
			(xy 93.043182 -12.34355) (xy 93.114498 -12.317832) (xy 93.188143 -12.29984) (xy 93.263283 -12.289778)
			(xy 93.339067 -12.287759) (xy 93.414637 -12.293808) (xy 93.489135 -12.307855) (xy 93.561718 -12.329741)
			(xy 93.631564 -12.359218) (xy 93.697881 -12.395953) (xy 93.759917 -12.439528) (xy 93.81697 -12.48945)
			(xy 93.868394 -12.545154) (xy 93.913605 -12.606009) (xy 93.952092 -12.671324) (xy 93.983418 -12.74036)
			(xy 94.007228 -12.812335) (xy 94.023253 -12.886433) (xy 94.031312 -12.961814) (xy 94.031816 -12.99972)
			(xy 94.031312 -13.037626) (xy 94.023253 -13.113007) (xy 94.007228 -13.187105) (xy 93.983418 -13.25908)
			(xy 93.952092 -13.328116) (xy 93.913605 -13.393431) (xy 93.868394 -13.454286) (xy 93.81697 -13.50999)
			(xy 93.759917 -13.559912) (xy 93.697881 -13.603487) (xy 93.631564 -13.640222) (xy 93.561718 -13.669699)
			(xy 93.489135 -13.691585) (xy 93.414637 -13.705632) (xy 93.339067 -13.711681) (xy 93.263283 -13.709662)
			(xy 93.188143 -13.6996) (xy 93.114498 -13.681608) (xy 93.043182 -13.65589) (xy 92.975005 -13.622738)
			(xy 92.910737 -13.582526) (xy 92.851108 -13.535711) (xy 92.796792 -13.482823) (xy 92.748406 -13.424461)
			(xy 92.706498 -13.361286) (xy 92.671542 -13.294015) (xy 92.643935 -13.22341) (xy 92.623989 -13.150269)
			(xy 92.61193 -13.075424) (xy 92.607895 -12.99972) (xy 92.03182 -12.99972) (xy 92.031316 -13.037626)
			(xy 92.023257 -13.113007) (xy 92.007232 -13.187105) (xy 91.983422 -13.25908) (xy 91.952096 -13.328116)
			(xy 91.913609 -13.393431) (xy 91.868398 -13.454286) (xy 91.816974 -13.50999) (xy 91.759921 -13.559912)
			(xy 91.697885 -13.603487) (xy 91.631568 -13.640222) (xy 91.561722 -13.669699) (xy 91.489139 -13.691585)
			(xy 91.414641 -13.705632) (xy 91.339071 -13.711681) (xy 91.263287 -13.709662) (xy 91.188147 -13.6996)
			(xy 91.114502 -13.681608) (xy 91.043186 -13.65589) (xy 90.975009 -13.622738) (xy 90.910741 -13.582526)
			(xy 90.851112 -13.535711) (xy 90.796796 -13.482823) (xy 90.74841 -13.424461) (xy 90.706502 -13.361286)
			(xy 90.671546 -13.294015) (xy 90.643939 -13.22341) (xy 90.623993 -13.150269) (xy 90.611934 -13.075424)
			(xy 90.607899 -12.99972) (xy 79.471221 -12.99972) (xy 79.424534 -13.030739) (xy 79.294464 -13.107494)
			(xy 79.16049 -13.17721) (xy 79.02299 -13.239688) (xy 78.882357 -13.294749) (xy 78.738989 -13.342239)
			(xy 78.593295 -13.382022) (xy 78.445687 -13.413985) (xy 78.296587 -13.438037) (xy 78.146416 -13.45411)
			(xy 77.995602 -13.462157) (xy 77.844574 -13.462157) (xy 77.69376 -13.45411) (xy 77.543589 -13.438037)
			(xy 77.394489 -13.413985) (xy 77.246881 -13.382022) (xy 77.101187 -13.342239) (xy 76.957819 -13.294749)
			(xy 76.817186 -13.239688) (xy 76.679686 -13.17721) (xy 76.545712 -13.107494) (xy 76.415642 -13.030739)
			(xy 76.289847 -12.947161) (xy 76.168685 -12.856999) (xy 76.052499 -12.760509) (xy 75.941619 -12.657964)
			(xy 75.836362 -12.549658) (xy 75.737025 -12.435896) (xy 75.643891 -12.317002) (xy 75.557226 -12.193315)
			(xy 75.477274 -12.065185) (xy 75.404263 -11.932977) (xy 75.338401 -11.797066) (xy 75.279875 -11.657839)
			(xy 75.228851 -11.515691) (xy 75.185473 -11.371026) (xy 75.149867 -11.224255) (xy 75.122131 -11.075795)
			(xy 75.102346 -10.926068) (xy 75.090568 -10.7755) (xy 75.086829 -10.624518) (xy 75.091141 -10.473551)
			(xy 75.103492 -10.323029) (xy 75.123846 -10.173378) (xy 75.152145 -10.025025) (xy 75.188309 -9.87839)
			(xy 75.232235 -9.733891) (xy 75.283799 -9.591938) (xy 75.342854 -9.452934) (xy 75.409232 -9.317274)
			(xy 75.482745 -9.185344) (xy 75.563183 -9.057519) (xy 75.650318 -8.934162) (xy 75.743902 -8.815623)
			(xy 75.843671 -8.70224) (xy 75.949339 -8.594333) (xy 76.060607 -8.492211) (xy 76.177159 -8.396163)
			(xy 76.298663 -8.306462) (xy 76.424774 -8.223363) (xy 76.555135 -8.147102) (xy 76.689374 -8.077896)
			(xy 76.758038 -8.046466) (xy 76.778295 -8.036815) (xy 76.815329 -8.011487) (xy 76.847339 -7.980049)
			(xy 76.873331 -7.943479) (xy 76.892497 -7.902912) (xy 76.904242 -7.85961) (xy 76.9082 -7.814919)
			(xy 76.904249 -7.770226) (xy 76.89251 -7.726923) (xy 76.87335 -7.686353) (xy 76.847363 -7.649779)
			(xy 76.815357 -7.618336) (xy 76.778327 -7.593003) (xy 76.758038 -7.583424) (xy 76.690271 -7.552407)
			(xy 76.55774 -7.484198) (xy 76.428981 -7.409113) (xy 76.304348 -7.327361) (xy 76.184187 -7.239167)
			(xy 76.06883 -7.144776) (xy 75.958597 -7.044449) (xy 75.853793 -6.938463) (xy 75.754708 -6.827113)
			(xy 75.661616 -6.710706) (xy 75.574775 -6.589564) (xy 75.494424 -6.464022) (xy 75.420787 -6.334429)
			(xy 75.354068 -6.201142) (xy 75.29445 -6.064532) (xy 75.2421 -5.924974) (xy 75.197161 -5.782857)
			(xy 75.159758 -5.638573) (xy 75.129995 -5.492522) (xy 75.107954 -5.345108) (xy 75.093696 -5.196738)
			(xy 75.087261 -5.047824) (xy 75.088666 -4.898778) (xy 75.097908 -4.750011) (xy 75.11496 -4.601937)
			(xy 75.139776 -4.454964) (xy 75.172287 -4.3095) (xy 75.212404 -4.165947) (xy 75.260014 -4.024702)
			(xy 75.314986 -3.886157) (xy 75.377169 -3.750694) (xy 75.446389 -3.618689) (xy 75.522456 -3.490507)
			(xy 75.605159 -3.366503) (xy 75.694269 -3.24702) (xy 75.789539 -3.132388) (xy 75.890706 -3.022925)
			(xy 75.99749 -2.918935) (xy 76.109594 -2.820704) (xy 76.22671 -2.728504) (xy 76.348512 -2.642591)
			(xy 76.411328 -2.602484) (xy 76.429564 -2.590454) (xy 76.461994 -2.561185) (xy 76.488939 -2.5268)
			(xy 76.509607 -2.488314) (xy 76.523389 -2.446861) (xy 76.529877 -2.403661) (xy 76.528882 -2.359988)
			(xy 76.520433 -2.317128) (xy 76.504777 -2.276345) (xy 76.482378 -2.23884) (xy 76.453894 -2.205719)
			(xy 76.420165 -2.177957) (xy 76.382185 -2.156373) (xy 76.341074 -2.141602) (xy 76.298042 -2.13408)
			(xy 76.2762 -2.1336) (xy 9.8044 -2.1336) (xy 9.017 -2.921) (xy 9.017 -5.166461) (xy 18.897592 -5.166461)
			(xy 18.897592 -5.095139) (xy 18.905578 -5.024265) (xy 18.921448 -4.95473) (xy 18.945005 -4.88741)
			(xy 18.97595 -4.823151) (xy 19.013896 -4.76276) (xy 19.058365 -4.706998) (xy 19.108798 -4.656565)
			(xy 19.16456 -4.612096) (xy 19.224951 -4.57415) (xy 19.28921 -4.543205) (xy 19.35653 -4.519648) (xy 19.426065 -4.503778)
			(xy 19.496939 -4.495792) (xy 19.568261 -4.495792) (xy 19.639135 -4.503778) (xy 19.70867 -4.519648)
			(xy 19.77599 -4.543205) (xy 19.840249 -4.57415) (xy 19.90064 -4.612096) (xy 19.956402 -4.656565)
			(xy 20.006835 -4.706998) (xy 20.051304 -4.76276) (xy 20.08925 -4.823151) (xy 20.120195 -4.88741)
			(xy 20.137849 -4.937861) (xy 26.593792 -4.937861) (xy 26.593792 -4.866539) (xy 26.601778 -4.795665)
			(xy 26.617648 -4.72613) (xy 26.641205 -4.65881) (xy 26.67215 -4.594551) (xy 26.710096 -4.53416) (xy 26.754565 -4.478398)
			(xy 26.804998 -4.427965) (xy 26.86076 -4.383496) (xy 26.921151 -4.34555) (xy 26.98541 -4.314605)
			(xy 27.05273 -4.291048) (xy 27.122265 -4.275178) (xy 27.193139 -4.267192) (xy 27.264461 -4.267192)
			(xy 27.335335 -4.275178) (xy 27.40487 -4.291048) (xy 27.47219 -4.314605) (xy 27.536449 -4.34555)
			(xy 27.59684 -4.383496) (xy 27.652602 -4.427965) (xy 27.703035 -4.478398) (xy 27.747504 -4.53416)
			(xy 27.78545 -4.594551) (xy 27.816395 -4.65881) (xy 27.839952 -4.72613) (xy 27.855822 -4.795665)
			(xy 27.863808 -4.866539) (xy 27.864308 -4.9022) (xy 27.863808 -4.937861) (xy 27.860946 -4.963261)
			(xy 41.427392 -4.963261) (xy 41.427392 -4.891939) (xy 41.435378 -4.821065) (xy 41.451248 -4.75153)
			(xy 41.474805 -4.68421) (xy 41.50575 -4.619951) (xy 41.543696 -4.55956) (xy 41.588165 -4.503798)
			(xy 41.638598 -4.453365) (xy 41.69436 -4.408896) (xy 41.754751 -4.37095) (xy 41.81901 -4.340005)
			(xy 41.88633 -4.316448) (xy 41.955865 -4.300578) (xy 42.026739 -4.292592) (xy 42.098061 -4.292592)
			(xy 42.168935 -4.300578) (xy 42.23847 -4.316448) (xy 42.30579 -4.340005) (xy 42.370049 -4.37095)
			(xy 42.43044 -4.408896) (xy 42.486202 -4.453365) (xy 42.536635 -4.503798) (xy 42.581104 -4.55956)
			(xy 42.61905 -4.619951) (xy 42.649995 -4.68421) (xy 42.673552 -4.75153) (xy 42.689422 -4.821065)
			(xy 42.697408 -4.891939) (xy 42.697908 -4.9276) (xy 42.697408 -4.963261) (xy 42.689422 -5.034135)
			(xy 42.673552 -5.10367) (xy 42.65158 -5.166461) (xy 48.742592 -5.166461) (xy 48.742592 -5.095139)
			(xy 48.750578 -5.024265) (xy 48.766448 -4.95473) (xy 48.790005 -4.88741) (xy 48.82095 -4.823151)
			(xy 48.858896 -4.76276) (xy 48.903365 -4.706998) (xy 48.953798 -4.656565) (xy 49.00956 -4.612096)
			(xy 49.069951 -4.57415) (xy 49.13421 -4.543205) (xy 49.20153 -4.519648) (xy 49.271065 -4.503778)
			(xy 49.341939 -4.495792) (xy 49.413261 -4.495792) (xy 49.484135 -4.503778) (xy 49.55367 -4.519648)
			(xy 49.62099 -4.543205) (xy 49.685249 -4.57415) (xy 49.74564 -4.612096) (xy 49.801402 -4.656565)
			(xy 49.851835 -4.706998) (xy 49.896304 -4.76276) (xy 49.93425 -4.823151) (xy 49.965195 -4.88741)
			(xy 49.988752 -4.95473) (xy 50.002293 -5.014061) (xy 56.718192 -5.014061) (xy 56.718192 -4.942739)
			(xy 56.726178 -4.871865) (xy 56.742048 -4.80233) (xy 56.765605 -4.73501) (xy 56.79655 -4.670751)
			(xy 56.834496 -4.61036) (xy 56.878965 -4.554598) (xy 56.929398 -4.504165) (xy 56.98516 -4.459696)
			(xy 57.045551 -4.42175) (xy 57.10981 -4.390805) (xy 57.17713 -4.367248) (xy 57.246665 -4.351378)
			(xy 57.317539 -4.343392) (xy 57.388861 -4.343392) (xy 57.459735 -4.351378) (xy 57.52927 -4.367248)
			(xy 57.59659 -4.390805) (xy 57.660849 -4.42175) (xy 57.72124 -4.459696) (xy 57.777002 -4.504165)
			(xy 57.827435 -4.554598) (xy 57.871904 -4.61036) (xy 57.90985 -4.670751) (xy 57.940795 -4.73501)
			(xy 57.964352 -4.80233) (xy 57.980222 -4.871865) (xy 57.984796 -4.912461) (xy 63.982592 -4.912461)
			(xy 63.982592 -4.841139) (xy 63.990578 -4.770265) (xy 64.006448 -4.70073) (xy 64.030005 -4.63341)
			(xy 64.06095 -4.569151) (xy 64.098896 -4.50876) (xy 64.143365 -4.452998) (xy 64.193798 -4.402565)
			(xy 64.24956 -4.358096) (xy 64.309951 -4.32015) (xy 64.37421 -4.289205) (xy 64.44153 -4.265648) (xy 64.511065 -4.249778)
			(xy 64.581939 -4.241792) (xy 64.653261 -4.241792) (xy 64.724135 -4.249778) (xy 64.79367 -4.265648)
			(xy 64.86099 -4.289205) (xy 64.925249 -4.32015) (xy 64.98564 -4.358096) (xy 65.041402 -4.402565)
			(xy 65.091835 -4.452998) (xy 65.136304 -4.50876) (xy 65.17425 -4.569151) (xy 65.205195 -4.63341)
			(xy 65.228752 -4.70073) (xy 65.244622 -4.770265) (xy 65.252608 -4.841139) (xy 65.253108 -4.8768)
			(xy 65.252608 -4.912461) (xy 65.244622 -4.983335) (xy 65.228752 -5.05287) (xy 65.205195 -5.12019)
			(xy 65.17425 -5.184449) (xy 65.136304 -5.24484) (xy 65.091835 -5.300602) (xy 65.041402 -5.351035)
			(xy 64.98564 -5.395504) (xy 64.925249 -5.43345) (xy 64.86099 -5.464395) (xy 64.79367 -5.487952) (xy 64.724135 -5.503822)
			(xy 64.653261 -5.511808) (xy 64.581939 -5.511808) (xy 64.511065 -5.503822) (xy 64.44153 -5.487952)
			(xy 64.37421 -5.464395) (xy 64.309951 -5.43345) (xy 64.24956 -5.395504) (xy 64.193798 -5.351035)
			(xy 64.143365 -5.300602) (xy 64.098896 -5.24484) (xy 64.06095 -5.184449) (xy 64.030005 -5.12019)
			(xy 64.006448 -5.05287) (xy 63.990578 -4.983335) (xy 63.982592 -4.912461) (xy 57.984796 -4.912461)
			(xy 57.988208 -4.942739) (xy 57.988708 -4.9784) (xy 57.988208 -5.014061) (xy 57.980222 -5.084935)
			(xy 57.964352 -5.15447) (xy 57.940795 -5.22179) (xy 57.90985 -5.286049) (xy 57.871904 -5.34644) (xy 57.827435 -5.402202)
			(xy 57.777002 -5.452635) (xy 57.72124 -5.497104) (xy 57.660849 -5.53505) (xy 57.59659 -5.565995)
			(xy 57.52927 -5.589552) (xy 57.459735 -5.605422) (xy 57.388861 -5.613408) (xy 57.317539 -5.613408)
			(xy 57.246665 -5.605422) (xy 57.17713 -5.589552) (xy 57.10981 -5.565995) (xy 57.045551 -5.53505)
			(xy 56.98516 -5.497104) (xy 56.929398 -5.452635) (xy 56.878965 -5.402202) (xy 56.834496 -5.34644)
			(xy 56.79655 -5.286049) (xy 56.765605 -5.22179) (xy 56.742048 -5.15447) (xy 56.726178 -5.084935)
			(xy 56.718192 -5.014061) (xy 50.002293 -5.014061) (xy 50.004622 -5.024265) (xy 50.012608 -5.095139)
			(xy 50.013108 -5.1308) (xy 50.012608 -5.166461) (xy 50.004622 -5.237335) (xy 49.988752 -5.30687)
			(xy 49.965195 -5.37419) (xy 49.93425 -5.438449) (xy 49.896304 -5.49884) (xy 49.851835 -5.554602)
			(xy 49.801402 -5.605035) (xy 49.74564 -5.649504) (xy 49.685249 -5.68745) (xy 49.62099 -5.718395)
			(xy 49.55367 -5.741952) (xy 49.484135 -5.757822) (xy 49.413261 -5.765808) (xy 49.341939 -5.765808)
			(xy 49.271065 -5.757822) (xy 49.20153 -5.741952) (xy 49.13421 -5.718395) (xy 49.069951 -5.68745)
			(xy 49.00956 -5.649504) (xy 48.953798 -5.605035) (xy 48.903365 -5.554602) (xy 48.858896 -5.49884)
			(xy 48.82095 -5.438449) (xy 48.790005 -5.37419) (xy 48.766448 -5.30687) (xy 48.750578 -5.237335)
			(xy 48.742592 -5.166461) (xy 42.65158 -5.166461) (xy 42.649995 -5.17099) (xy 42.61905 -5.235249)
			(xy 42.581104 -5.29564) (xy 42.536635 -5.351402) (xy 42.486202 -5.401835) (xy 42.43044 -5.446304)
			(xy 42.370049 -5.48425) (xy 42.30579 -5.515195) (xy 42.23847 -5.538752) (xy 42.168935 -5.554622)
			(xy 42.098061 -5.562608) (xy 42.026739 -5.562608) (xy 41.955865 -5.554622) (xy 41.88633 -5.538752)
			(xy 41.81901 -5.515195) (xy 41.754751 -5.48425) (xy 41.69436 -5.446304) (xy 41.638598 -5.401835)
			(xy 41.588165 -5.351402) (xy 41.543696 -5.29564) (xy 41.50575 -5.235249) (xy 41.474805 -5.17099)
			(xy 41.451248 -5.10367) (xy 41.435378 -5.034135) (xy 41.427392 -4.963261) (xy 27.860946 -4.963261)
			(xy 27.855822 -5.008735) (xy 27.839952 -5.07827) (xy 27.816395 -5.14559) (xy 27.78545 -5.209849)
			(xy 27.747504 -5.27024) (xy 27.703035 -5.326002) (xy 27.652602 -5.376435) (xy 27.59684 -5.420904)
			(xy 27.536449 -5.45885) (xy 27.47219 -5.489795) (xy 27.40487 -5.513352) (xy 27.335335 -5.529222)
			(xy 27.264461 -5.537208) (xy 27.193139 -5.537208) (xy 27.122265 -5.529222) (xy 27.05273 -5.513352)
			(xy 26.98541 -5.489795) (xy 26.921151 -5.45885) (xy 26.86076 -5.420904) (xy 26.804998 -5.376435)
			(xy 26.754565 -5.326002) (xy 26.710096 -5.27024) (xy 26.67215 -5.209849) (xy 26.641205 -5.14559)
			(xy 26.617648 -5.07827) (xy 26.601778 -5.008735) (xy 26.593792 -4.937861) (xy 20.137849 -4.937861)
			(xy 20.143752 -4.95473) (xy 20.159622 -5.024265) (xy 20.167608 -5.095139) (xy 20.168108 -5.1308)
			(xy 20.167608 -5.166461) (xy 20.159622 -5.237335) (xy 20.143752 -5.30687) (xy 20.120195 -5.37419)
			(xy 20.08925 -5.438449) (xy 20.051304 -5.49884) (xy 20.006835 -5.554602) (xy 19.956402 -5.605035)
			(xy 19.90064 -5.649504) (xy 19.840249 -5.68745) (xy 19.77599 -5.718395) (xy 19.756369 -5.725261)
			(xy 22.275792 -5.725261) (xy 22.275792 -5.653939) (xy 22.283778 -5.583065) (xy 22.299648 -5.51353)
			(xy 22.323205 -5.44621) (xy 22.35415 -5.381951) (xy 22.392096 -5.32156) (xy 22.436565 -5.265798)
			(xy 22.486998 -5.215365) (xy 22.54276 -5.170896) (xy 22.603151 -5.13295) (xy 22.66741 -5.102005)
			(xy 22.73473 -5.078448) (xy 22.804265 -5.062578) (xy 22.875139 -5.054592) (xy 22.946461 -5.054592)
			(xy 23.017335 -5.062578) (xy 23.08687 -5.078448) (xy 23.15419 -5.102005) (xy 23.218449 -5.13295)
			(xy 23.27884 -5.170896) (xy 23.334602 -5.215365) (xy 23.385035 -5.265798) (xy 23.429504 -5.32156)
			(xy 23.46745 -5.381951) (xy 23.498395 -5.44621) (xy 23.521952 -5.51353) (xy 23.537822 -5.583065)
			(xy 23.545808 -5.653939) (xy 23.546308 -5.6896) (xy 23.545808 -5.725261) (xy 23.537822 -5.796135)
			(xy 23.521952 -5.86567) (xy 23.498395 -5.93299) (xy 23.46745 -5.997249) (xy 23.429504 -6.05764) (xy 23.385035 -6.113402)
			(xy 23.334602 -6.163835) (xy 23.27884 -6.208304) (xy 23.218449 -6.24625) (xy 23.15419 -6.277195)
			(xy 23.08687 -6.300752) (xy 23.017335 -6.316622) (xy 22.946461 -6.324608) (xy 22.875139 -6.324608)
			(xy 22.804265 -6.316622) (xy 22.73473 -6.300752) (xy 22.66741 -6.277195) (xy 22.603151 -6.24625)
			(xy 22.54276 -6.208304) (xy 22.486998 -6.163835) (xy 22.436565 -6.113402) (xy 22.392096 -6.05764)
			(xy 22.35415 -5.997249) (xy 22.323205 -5.93299) (xy 22.299648 -5.86567) (xy 22.283778 -5.796135)
			(xy 22.275792 -5.725261) (xy 19.756369 -5.725261) (xy 19.70867 -5.741952) (xy 19.639135 -5.757822)
			(xy 19.568261 -5.765808) (xy 19.496939 -5.765808) (xy 19.426065 -5.757822) (xy 19.35653 -5.741952)
			(xy 19.28921 -5.718395) (xy 19.224951 -5.68745) (xy 19.16456 -5.649504) (xy 19.108798 -5.605035)
			(xy 19.058365 -5.554602) (xy 19.013896 -5.49884) (xy 18.97595 -5.438449) (xy 18.945005 -5.37419)
			(xy 18.921448 -5.30687) (xy 18.905578 -5.237335) (xy 18.897592 -5.166461) (xy 9.017 -5.166461) (xy 9.017 -7.1374)
			(xy 8.654288 -7.500112) (xy 9.403341 -7.500112) (xy 9.407346 -7.412204) (xy 9.419329 -7.325024) (xy 9.439189 -7.239295)
			(xy 9.466764 -7.155727) (xy 9.501823 -7.075013) (xy 9.544076 -6.997821) (xy 9.593174 -6.924792) (xy 9.64871 -6.85653)
			(xy 9.710222 -6.7936) (xy 9.777203 -6.736526) (xy 9.849096 -6.685778) (xy 9.925305 -6.641778) (xy 10.0052 -6.604891)
			(xy 10.088119 -6.575422) (xy 10.173374 -6.553615) (xy 10.260258 -6.539651) (xy 10.348052 -6.533645)
			(xy 10.436029 -6.535649) (xy 10.523459 -6.545644) (xy 10.609618 -6.563548) (xy 10.693792 -6.589212)
			(xy 10.775283 -6.622425) (xy 10.853417 -6.662911) (xy 10.927545 -6.710333) (xy 10.997053 -6.7643)
			(xy 11.061367 -6.824365) (xy 11.119951 -6.890029) (xy 11.172322 -6.960748) (xy 11.218045 -7.035936)
			(xy 11.256742 -7.114971) (xy 11.288091 -7.197197) (xy 11.311833 -7.281933) (xy 11.327771 -7.368477)
			(xy 11.335773 -7.456112) (xy 11.336274 -7.500112) (xy 11.336238 -7.503261) (xy 25.399992 -7.503261)
			(xy 25.399992 -7.431939) (xy 25.407978 -7.361065) (xy 25.423848 -7.29153) (xy 25.447405 -7.22421)
			(xy 25.47835 -7.159951) (xy 25.516296 -7.09956) (xy 25.560765 -7.043798) (xy 25.611198 -6.993365)
			(xy 25.66696 -6.948896) (xy 25.727351 -6.91095) (xy 25.79161 -6.880005) (xy 25.85893 -6.856448) (xy 25.928465 -6.840578)
			(xy 25.999339 -6.832592) (xy 26.070661 -6.832592) (xy 26.141535 -6.840578) (xy 26.21107 -6.856448)
			(xy 26.27839 -6.880005) (xy 26.342649 -6.91095) (xy 26.40304 -6.948896) (xy 26.458802 -6.993365)
			(xy 26.509235 -7.043798) (xy 26.553704 -7.09956) (xy 26.59165 -7.159951) (xy 26.622595 -7.22421)
			(xy 26.646152 -7.29153) (xy 26.662022 -7.361065) (xy 26.670008 -7.431939) (xy 26.670508 -7.4676)
			(xy 26.670008 -7.503261) (xy 26.662022 -7.574135) (xy 26.646152 -7.64367) (xy 26.622595 -7.71099)
			(xy 26.59165 -7.775249) (xy 26.553704 -7.83564) (xy 26.51493 -7.884261) (xy 49.606192 -7.884261)
			(xy 49.606192 -7.812939) (xy 49.614178 -7.742065) (xy 49.630048 -7.67253) (xy 49.653605 -7.60521)
			(xy 49.68455 -7.540951) (xy 49.722496 -7.48056) (xy 49.766965 -7.424798) (xy 49.817398 -7.374365)
			(xy 49.87316 -7.329896) (xy 49.933551 -7.29195) (xy 49.99781 -7.261005) (xy 50.06513 -7.237448) (xy 50.134665 -7.221578)
			(xy 50.205539 -7.213592) (xy 50.276861 -7.213592) (xy 50.347735 -7.221578) (xy 50.41727 -7.237448)
			(xy 50.48459 -7.261005) (xy 50.548849 -7.29195) (xy 50.60924 -7.329896) (xy 50.665002 -7.374365)
			(xy 50.715435 -7.424798) (xy 50.759904 -7.48056) (xy 50.79785 -7.540951) (xy 50.828795 -7.60521)
			(xy 50.852352 -7.67253) (xy 50.868222 -7.742065) (xy 50.876208 -7.812939) (xy 50.876708 -7.8486)
			(xy 50.876208 -7.884261) (xy 57.581792 -7.884261) (xy 57.581792 -7.812939) (xy 57.589778 -7.742065)
			(xy 57.605648 -7.67253) (xy 57.629205 -7.60521) (xy 57.66015 -7.540951) (xy 57.698096 -7.48056) (xy 57.742565 -7.424798)
			(xy 57.792998 -7.374365) (xy 57.84876 -7.329896) (xy 57.909151 -7.29195) (xy 57.97341 -7.261005)
			(xy 58.04073 -7.237448) (xy 58.110265 -7.221578) (xy 58.181139 -7.213592) (xy 58.252461 -7.213592)
			(xy 58.323335 -7.221578) (xy 58.39287 -7.237448) (xy 58.46019 -7.261005) (xy 58.524449 -7.29195)
			(xy 58.58484 -7.329896) (xy 58.640602 -7.374365) (xy 58.691035 -7.424798) (xy 58.735504 -7.48056)
			(xy 58.77345 -7.540951) (xy 58.804395 -7.60521) (xy 58.827952 -7.67253) (xy 58.843822 -7.742065)
			(xy 58.851808 -7.812939) (xy 58.852308 -7.8486) (xy 58.851808 -7.884261) (xy 58.843822 -7.955135)
			(xy 58.827952 -8.02467) (xy 58.804395 -8.09199) (xy 58.77345 -8.156249) (xy 58.735504 -8.21664) (xy 58.691035 -8.272402)
			(xy 58.640602 -8.322835) (xy 58.58484 -8.367304) (xy 58.524449 -8.40525) (xy 58.46019 -8.436195)
			(xy 58.39287 -8.459752) (xy 58.323335 -8.475622) (xy 58.252461 -8.483608) (xy 58.181139 -8.483608)
			(xy 58.110265 -8.475622) (xy 58.04073 -8.459752) (xy 57.97341 -8.436195) (xy 57.909151 -8.40525)
			(xy 57.84876 -8.367304) (xy 57.792998 -8.322835) (xy 57.742565 -8.272402) (xy 57.698096 -8.21664)
			(xy 57.66015 -8.156249) (xy 57.629205 -8.09199) (xy 57.605648 -8.02467) (xy 57.589778 -7.955135)
			(xy 57.581792 -7.884261) (xy 50.876208 -7.884261) (xy 50.868222 -7.955135) (xy 50.852352 -8.02467)
			(xy 50.828795 -8.09199) (xy 50.79785 -8.156249) (xy 50.759904 -8.21664) (xy 50.715435 -8.272402)
			(xy 50.665002 -8.322835) (xy 50.60924 -8.367304) (xy 50.548849 -8.40525) (xy 50.48459 -8.436195)
			(xy 50.41727 -8.459752) (xy 50.347735 -8.475622) (xy 50.276861 -8.483608) (xy 50.205539 -8.483608)
			(xy 50.134665 -8.475622) (xy 50.06513 -8.459752) (xy 49.99781 -8.436195) (xy 49.933551 -8.40525)
			(xy 49.87316 -8.367304) (xy 49.817398 -8.322835) (xy 49.766965 -8.272402) (xy 49.722496 -8.21664)
			(xy 49.68455 -8.156249) (xy 49.653605 -8.09199) (xy 49.630048 -8.02467) (xy 49.614178 -7.955135)
			(xy 49.606192 -7.884261) (xy 26.51493 -7.884261) (xy 26.509235 -7.891402) (xy 26.458802 -7.941835)
			(xy 26.40304 -7.986304) (xy 26.342649 -8.02425) (xy 26.27839 -8.055195) (xy 26.21107 -8.078752) (xy 26.141535 -8.094622)
			(xy 26.070661 -8.102608) (xy 25.999339 -8.102608) (xy 25.928465 -8.094622) (xy 25.85893 -8.078752)
			(xy 25.79161 -8.055195) (xy 25.727351 -8.02425) (xy 25.66696 -7.986304) (xy 25.611198 -7.941835)
			(xy 25.560765 -7.891402) (xy 25.516296 -7.83564) (xy 25.47835 -7.775249) (xy 25.447405 -7.71099)
			(xy 25.423848 -7.64367) (xy 25.407978 -7.574135) (xy 25.399992 -7.503261) (xy 11.336238 -7.503261)
			(xy 11.335773 -7.544112) (xy 11.327771 -7.631747) (xy 11.311833 -7.718291) (xy 11.288091 -7.803027)
			(xy 11.256742 -7.885253) (xy 11.218045 -7.964288) (xy 11.172322 -8.039476) (xy 11.119951 -8.110195)
			(xy 11.061367 -8.175859) (xy 10.997053 -8.235924) (xy 10.927545 -8.289891) (xy 10.853417 -8.337313)
			(xy 10.775283 -8.377799) (xy 10.693792 -8.411012) (xy 10.609618 -8.436676) (xy 10.523459 -8.45458)
			(xy 10.436029 -8.464575) (xy 10.348052 -8.466579) (xy 10.260258 -8.460573) (xy 10.173374 -8.446609)
			(xy 10.088119 -8.424802) (xy 10.0052 -8.395333) (xy 9.925305 -8.358446) (xy 9.849096 -8.314446) (xy 9.777203 -8.263698)
			(xy 9.710222 -8.206624) (xy 9.64871 -8.143694) (xy 9.593174 -8.075432) (xy 9.544076 -8.002403) (xy 9.501823 -7.925211)
			(xy 9.466764 -7.844497) (xy 9.439189 -7.760929) (xy 9.419329 -7.6752) (xy 9.407346 -7.58802) (xy 9.403341 -7.500112)
			(xy 8.654288 -7.500112) (xy 7.508139 -8.646261) (xy 30.149792 -8.646261) (xy 30.149792 -8.574939)
			(xy 30.157778 -8.504065) (xy 30.173648 -8.43453) (xy 30.197205 -8.36721) (xy 30.22815 -8.302951)
			(xy 30.266096 -8.24256) (xy 30.310565 -8.186798) (xy 30.360998 -8.136365) (xy 30.41676 -8.091896)
			(xy 30.477151 -8.05395) (xy 30.54141 -8.023005) (xy 30.60873 -7.999448) (xy 30.678265 -7.983578)
			(xy 30.749139 -7.975592) (xy 30.820461 -7.975592) (xy 30.891335 -7.983578) (xy 30.96087 -7.999448)
			(xy 31.02819 -8.023005) (xy 31.092449 -8.05395) (xy 31.15284 -8.091896) (xy 31.208602 -8.136365)
			(xy 31.259035 -8.186798) (xy 31.303504 -8.24256) (xy 31.34145 -8.302951) (xy 31.372395 -8.36721)
			(xy 31.395952 -8.43453) (xy 31.411822 -8.504065) (xy 31.419808 -8.574939) (xy 31.420308 -8.6106)
			(xy 31.419808 -8.646261) (xy 31.411822 -8.717135) (xy 31.395952 -8.78667) (xy 31.372395 -8.85399)
			(xy 31.34145 -8.918249) (xy 31.303504 -8.97864) (xy 31.259035 -9.034402) (xy 31.208602 -9.084835)
			(xy 31.153396 -9.128861) (xy 37.845992 -9.128861) (xy 37.845992 -9.057539) (xy 37.853978 -8.986665)
			(xy 37.869848 -8.91713) (xy 37.893405 -8.84981) (xy 37.92435 -8.785551) (xy 37.962296 -8.72516) (xy 38.006765 -8.669398)
			(xy 38.057198 -8.618965) (xy 38.11296 -8.574496) (xy 38.173351 -8.53655) (xy 38.23761 -8.505605)
			(xy 38.30493 -8.482048) (xy 38.374465 -8.466178) (xy 38.445339 -8.458192) (xy 38.516661 -8.458192)
			(xy 38.587535 -8.466178) (xy 38.65707 -8.482048) (xy 38.72439 -8.505605) (xy 38.788649 -8.53655)
			(xy 38.84904 -8.574496) (xy 38.904802 -8.618965) (xy 38.955235 -8.669398) (xy 38.999704 -8.72516)
			(xy 39.03765 -8.785551) (xy 39.068595 -8.84981) (xy 39.092152 -8.91713) (xy 39.108022 -8.986665)
			(xy 39.116008 -9.057539) (xy 39.116508 -9.0932) (xy 39.116008 -9.128861) (xy 39.108022 -9.199735)
			(xy 39.092152 -9.26927) (xy 39.07018 -9.332061) (xy 46.126392 -9.332061) (xy 46.126392 -9.260739)
			(xy 46.134378 -9.189865) (xy 46.150248 -9.12033) (xy 46.173805 -9.05301) (xy 46.20475 -8.988751)
			(xy 46.242696 -8.92836) (xy 46.287165 -8.872598) (xy 46.337598 -8.822165) (xy 46.39336 -8.777696)
			(xy 46.453751 -8.73975) (xy 46.51801 -8.708805) (xy 46.58533 -8.685248) (xy 46.654865 -8.669378)
			(xy 46.725739 -8.661392) (xy 46.797061 -8.661392) (xy 46.867935 -8.669378) (xy 46.93747 -8.685248)
			(xy 47.00479 -8.708805) (xy 47.069049 -8.73975) (xy 47.12944 -8.777696) (xy 47.185202 -8.822165)
			(xy 47.235635 -8.872598) (xy 47.280104 -8.92836) (xy 47.31805 -8.988751) (xy 47.348995 -9.05301)
			(xy 47.372552 -9.12033) (xy 47.374499 -9.128861) (xy 53.898792 -9.128861) (xy 53.898792 -9.057539)
			(xy 53.906778 -8.986665) (xy 53.922648 -8.91713) (xy 53.946205 -8.84981) (xy 53.97715 -8.785551)
			(xy 54.015096 -8.72516) (xy 54.059565 -8.669398) (xy 54.109998 -8.618965) (xy 54.16576 -8.574496)
			(xy 54.226151 -8.53655) (xy 54.29041 -8.505605) (xy 54.35773 -8.482048) (xy 54.427265 -8.466178)
			(xy 54.498139 -8.458192) (xy 54.569461 -8.458192) (xy 54.640335 -8.466178) (xy 54.70987 -8.482048)
			(xy 54.77719 -8.505605) (xy 54.841449 -8.53655) (xy 54.90184 -8.574496) (xy 54.957602 -8.618965)
			(xy 55.008035 -8.669398) (xy 55.052504 -8.72516) (xy 55.09045 -8.785551) (xy 55.121395 -8.84981)
			(xy 55.144952 -8.91713) (xy 55.160822 -8.986665) (xy 55.168808 -9.057539) (xy 55.169308 -9.0932)
			(xy 55.168808 -9.128861) (xy 55.160822 -9.199735) (xy 55.144952 -9.26927) (xy 55.12298 -9.332061)
			(xy 61.569592 -9.332061) (xy 61.569592 -9.260739) (xy 61.577578 -9.189865) (xy 61.593448 -9.12033)
			(xy 61.617005 -9.05301) (xy 61.64795 -8.988751) (xy 61.685896 -8.92836) (xy 61.730365 -8.872598)
			(xy 61.780798 -8.822165) (xy 61.83656 -8.777696) (xy 61.896951 -8.73975) (xy 61.96121 -8.708805)
			(xy 62.02853 -8.685248) (xy 62.098065 -8.669378) (xy 62.168939 -8.661392) (xy 62.240261 -8.661392)
			(xy 62.311135 -8.669378) (xy 62.38067 -8.685248) (xy 62.44799 -8.708805) (xy 62.512249 -8.73975)
			(xy 62.57264 -8.777696) (xy 62.628402 -8.822165) (xy 62.678835 -8.872598) (xy 62.723304 -8.92836)
			(xy 62.76125 -8.988751) (xy 62.792195 -9.05301) (xy 62.815752 -9.12033) (xy 62.831622 -9.189865)
			(xy 62.836196 -9.230461) (xy 67.513192 -9.230461) (xy 67.513192 -9.159139) (xy 67.521178 -9.088265)
			(xy 67.537048 -9.01873) (xy 67.560605 -8.95141) (xy 67.59155 -8.887151) (xy 67.629496 -8.82676) (xy 67.673965 -8.770998)
			(xy 67.724398 -8.720565) (xy 67.78016 -8.676096) (xy 67.840551 -8.63815) (xy 67.90481 -8.607205)
			(xy 67.97213 -8.583648) (xy 68.041665 -8.567778) (xy 68.112539 -8.559792) (xy 68.183861 -8.559792)
			(xy 68.254735 -8.567778) (xy 68.32427 -8.583648) (xy 68.39159 -8.607205) (xy 68.455849 -8.63815)
			(xy 68.51624 -8.676096) (xy 68.572002 -8.720565) (xy 68.622435 -8.770998) (xy 68.666904 -8.82676)
			(xy 68.70485 -8.887151) (xy 68.735795 -8.95141) (xy 68.759352 -9.01873) (xy 68.775222 -9.088265)
			(xy 68.783208 -9.159139) (xy 68.783708 -9.1948) (xy 68.783208 -9.230461) (xy 68.775222 -9.301335)
			(xy 68.759352 -9.37087) (xy 68.735795 -9.43819) (xy 68.70485 -9.502449) (xy 68.666904 -9.56284) (xy 68.622435 -9.618602)
			(xy 68.572002 -9.669035) (xy 68.51624 -9.713504) (xy 68.455849 -9.75145) (xy 68.39159 -9.782395)
			(xy 68.32427 -9.805952) (xy 68.254735 -9.821822) (xy 68.183861 -9.829808) (xy 68.112539 -9.829808)
			(xy 68.041665 -9.821822) (xy 67.97213 -9.805952) (xy 67.90481 -9.782395) (xy 67.840551 -9.75145)
			(xy 67.78016 -9.713504) (xy 67.724398 -9.669035) (xy 67.673965 -9.618602) (xy 67.629496 -9.56284)
			(xy 67.59155 -9.502449) (xy 67.560605 -9.43819) (xy 67.537048 -9.37087) (xy 67.521178 -9.301335)
			(xy 67.513192 -9.230461) (xy 62.836196 -9.230461) (xy 62.839608 -9.260739) (xy 62.840108 -9.2964)
			(xy 62.839608 -9.332061) (xy 62.831622 -9.402935) (xy 62.815752 -9.47247) (xy 62.792195 -9.53979)
			(xy 62.76125 -9.604049) (xy 62.723304 -9.66444) (xy 62.678835 -9.720202) (xy 62.628402 -9.770635)
			(xy 62.57264 -9.815104) (xy 62.512249 -9.85305) (xy 62.44799 -9.883995) (xy 62.38067 -9.907552) (xy 62.311135 -9.923422)
			(xy 62.240261 -9.931408) (xy 62.168939 -9.931408) (xy 62.098065 -9.923422) (xy 62.02853 -9.907552)
			(xy 61.96121 -9.883995) (xy 61.896951 -9.85305) (xy 61.83656 -9.815104) (xy 61.780798 -9.770635)
			(xy 61.730365 -9.720202) (xy 61.685896 -9.66444) (xy 61.64795 -9.604049) (xy 61.617005 -9.53979)
			(xy 61.593448 -9.47247) (xy 61.577578 -9.402935) (xy 61.569592 -9.332061) (xy 55.12298 -9.332061)
			(xy 55.121395 -9.33659) (xy 55.09045 -9.400849) (xy 55.052504 -9.46124) (xy 55.008035 -9.517002)
			(xy 54.957602 -9.567435) (xy 54.90184 -9.611904) (xy 54.841449 -9.64985) (xy 54.77719 -9.680795)
			(xy 54.70987 -9.704352) (xy 54.640335 -9.720222) (xy 54.569461 -9.728208) (xy 54.498139 -9.728208)
			(xy 54.427265 -9.720222) (xy 54.35773 -9.704352) (xy 54.29041 -9.680795) (xy 54.226151 -9.64985)
			(xy 54.16576 -9.611904) (xy 54.109998 -9.567435) (xy 54.059565 -9.517002) (xy 54.015096 -9.46124)
			(xy 53.97715 -9.400849) (xy 53.946205 -9.33659) (xy 53.922648 -9.26927) (xy 53.906778 -9.199735)
			(xy 53.898792 -9.128861) (xy 47.374499 -9.128861) (xy 47.388422 -9.189865) (xy 47.396408 -9.260739)
			(xy 47.396908 -9.2964) (xy 47.396408 -9.332061) (xy 47.388422 -9.402935) (xy 47.372552 -9.47247)
			(xy 47.348995 -9.53979) (xy 47.31805 -9.604049) (xy 47.280104 -9.66444) (xy 47.235635 -9.720202)
			(xy 47.185202 -9.770635) (xy 47.12944 -9.815104) (xy 47.069049 -9.85305) (xy 47.00479 -9.883995)
			(xy 46.93747 -9.907552) (xy 46.867935 -9.923422) (xy 46.797061 -9.931408) (xy 46.725739 -9.931408)
			(xy 46.654865 -9.923422) (xy 46.58533 -9.907552) (xy 46.51801 -9.883995) (xy 46.453751 -9.85305)
			(xy 46.39336 -9.815104) (xy 46.337598 -9.770635) (xy 46.287165 -9.720202) (xy 46.242696 -9.66444)
			(xy 46.20475 -9.604049) (xy 46.173805 -9.53979) (xy 46.150248 -9.47247) (xy 46.134378 -9.402935)
			(xy 46.126392 -9.332061) (xy 39.07018 -9.332061) (xy 39.068595 -9.33659) (xy 39.03765 -9.400849)
			(xy 38.999704 -9.46124) (xy 38.955235 -9.517002) (xy 38.904802 -9.567435) (xy 38.84904 -9.611904)
			(xy 38.788649 -9.64985) (xy 38.72439 -9.680795) (xy 38.65707 -9.704352) (xy 38.587535 -9.720222)
			(xy 38.516661 -9.728208) (xy 38.445339 -9.728208) (xy 38.374465 -9.720222) (xy 38.30493 -9.704352)
			(xy 38.23761 -9.680795) (xy 38.173351 -9.64985) (xy 38.11296 -9.611904) (xy 38.057198 -9.567435)
			(xy 38.006765 -9.517002) (xy 37.962296 -9.46124) (xy 37.92435 -9.400849) (xy 37.893405 -9.33659)
			(xy 37.869848 -9.26927) (xy 37.853978 -9.199735) (xy 37.845992 -9.128861) (xy 31.153396 -9.128861)
			(xy 31.15284 -9.129304) (xy 31.092449 -9.16725) (xy 31.02819 -9.198195) (xy 30.96087 -9.221752) (xy 30.891335 -9.237622)
			(xy 30.820461 -9.245608) (xy 30.749139 -9.245608) (xy 30.678265 -9.237622) (xy 30.60873 -9.221752)
			(xy 30.54141 -9.198195) (xy 30.477151 -9.16725) (xy 30.41676 -9.129304) (xy 30.360998 -9.084835)
			(xy 30.310565 -9.034402) (xy 30.266096 -8.97864) (xy 30.22815 -8.918249) (xy 30.197205 -8.85399)
			(xy 30.173648 -8.78667) (xy 30.157778 -8.717135) (xy 30.149792 -8.646261) (xy 7.508139 -8.646261)
			(xy 7.0612 -9.0932) (xy 2.0574 -9.0932) (xy 1.4732 -9.6774) (xy 1.4732 -10.542969) (xy 10.382999 -10.542969)
			(xy 10.382999 -10.457243) (xy 10.390909 -10.371883) (xy 10.406661 -10.287616) (xy 10.430121 -10.205163)
			(xy 10.461089 -10.125226) (xy 10.4993 -10.048487) (xy 10.544429 -9.975601) (xy 10.59609 -9.90719)
			(xy 10.653844 -9.843838) (xy 10.717196 -9.786084) (xy 10.785607 -9.734423) (xy 10.858493 -9.689294)
			(xy 10.935232 -9.651083) (xy 11.015169 -9.620115) (xy 11.097622 -9.596655) (xy 11.181889 -9.580903)
			(xy 11.267249 -9.572993) (xy 11.352975 -9.572993) (xy 11.438335 -9.580903) (xy 11.522602 -9.596655)
			(xy 11.605055 -9.620115) (xy 11.684992 -9.651083) (xy 11.761731 -9.689294) (xy 11.834617 -9.734423)
			(xy 11.903028 -9.786084) (xy 11.96638 -9.843838) (xy 12.024134 -9.90719) (xy 12.075795 -9.975601)
			(xy 12.120924 -10.048487) (xy 12.159135 -10.125226) (xy 12.190103 -10.205163) (xy 12.213563 -10.287616)
			(xy 12.229315 -10.371883) (xy 12.236522 -10.449661) (xy 30.835592 -10.449661) (xy 30.835592 -10.378339)
			(xy 30.843578 -10.307465) (xy 30.859448 -10.23793) (xy 30.883005 -10.17061) (xy 30.91395 -10.106351)
			(xy 30.951896 -10.04596) (xy 30.996365 -9.990198) (xy 31.046798 -9.939765) (xy 31.10256 -9.895296)
			(xy 31.162951 -9.85735) (xy 31.22721 -9.826405) (xy 31.29453 -9.802848) (xy 31.364065 -9.786978)
			(xy 31.434939 -9.778992) (xy 31.506261 -9.778992) (xy 31.577135 -9.786978) (xy 31.64667 -9.802848)
			(xy 31.71399 -9.826405) (xy 31.778249 -9.85735) (xy 31.83864 -9.895296) (xy 31.894402 -9.939765)
			(xy 31.944835 -9.990198) (xy 31.989304 -10.04596) (xy 32.02725 -10.106351) (xy 32.058195 -10.17061)
			(xy 32.081752 -10.23793) (xy 32.097622 -10.307465) (xy 32.105608 -10.378339) (xy 32.106108 -10.414)
			(xy 32.105608 -10.449661) (xy 32.097622 -10.520535) (xy 32.081752 -10.59007) (xy 32.058195 -10.65739)
			(xy 32.02725 -10.721649) (xy 31.989304 -10.78204) (xy 31.944835 -10.837802) (xy 31.894402 -10.888235)
			(xy 31.83864 -10.932704) (xy 31.778249 -10.97065) (xy 31.71399 -11.001595) (xy 31.64667 -11.025152)
			(xy 31.577135 -11.041022) (xy 31.506261 -11.049008) (xy 31.434939 -11.049008) (xy 31.364065 -11.041022)
			(xy 31.29453 -11.025152) (xy 31.22721 -11.001595) (xy 31.162951 -10.97065) (xy 31.10256 -10.932704)
			(xy 31.046798 -10.888235) (xy 30.996365 -10.837802) (xy 30.951896 -10.78204) (xy 30.91395 -10.721649)
			(xy 30.883005 -10.65739) (xy 30.859448 -10.59007) (xy 30.843578 -10.520535) (xy 30.835592 -10.449661)
			(xy 12.236522 -10.449661) (xy 12.237225 -10.457243) (xy 12.23772 -10.500106) (xy 12.237225 -10.542969)
			(xy 12.229315 -10.628329) (xy 12.213563 -10.712596) (xy 12.190103 -10.795049) (xy 12.159135 -10.874986)
			(xy 12.120924 -10.951725) (xy 12.075795 -11.024611) (xy 12.024134 -11.093022) (xy 11.96638 -11.156374)
			(xy 11.903028 -11.214128) (xy 11.834617 -11.265789) (xy 11.761731 -11.310918) (xy 11.684992 -11.349129)
			(xy 11.605055 -11.380097) (xy 11.522602 -11.403557) (xy 11.438335 -11.419309) (xy 11.352975 -11.427219)
			(xy 11.267249 -11.427219) (xy 11.181889 -11.419309) (xy 11.097622 -11.403557) (xy 11.015169 -11.380097)
			(xy 10.935232 -11.349129) (xy 10.858493 -11.310918) (xy 10.785607 -11.265789) (xy 10.717196 -11.214128)
			(xy 10.653844 -11.156374) (xy 10.59609 -11.093022) (xy 10.544429 -11.024611) (xy 10.4993 -10.951725)
			(xy 10.461089 -10.874986) (xy 10.430121 -10.795049) (xy 10.406661 -10.712596) (xy 10.390909 -10.628329)
			(xy 10.382999 -10.542969) (xy 1.4732 -10.542969) (xy 1.4732 -12.329261) (xy 42.062392 -12.329261)
			(xy 42.062392 -12.257939) (xy 42.070378 -12.187065) (xy 42.086248 -12.11753) (xy 42.109805 -12.05021)
			(xy 42.14075 -11.985951) (xy 42.178696 -11.92556) (xy 42.223165 -11.869798) (xy 42.273598 -11.819365)
			(xy 42.32936 -11.774896) (xy 42.389751 -11.73695) (xy 42.45401 -11.706005) (xy 42.52133 -11.682448)
			(xy 42.590865 -11.666578) (xy 42.661739 -11.658592) (xy 42.733061 -11.658592) (xy 42.803935 -11.666578)
			(xy 42.87347 -11.682448) (xy 42.94079 -11.706005) (xy 43.005049 -11.73695) (xy 43.06544 -11.774896)
			(xy 43.121202 -11.819365) (xy 43.171635 -11.869798) (xy 43.216104 -11.92556) (xy 43.25405 -11.985951)
			(xy 43.284995 -12.05021) (xy 43.308552 -12.11753) (xy 43.324422 -12.187065) (xy 43.328996 -12.227661)
			(xy 49.606192 -12.227661) (xy 49.606192 -12.156339) (xy 49.614178 -12.085465) (xy 49.630048 -12.01593)
			(xy 49.653605 -11.94861) (xy 49.68455 -11.884351) (xy 49.722496 -11.82396) (xy 49.766965 -11.768198)
			(xy 49.817398 -11.717765) (xy 49.87316 -11.673296) (xy 49.933551 -11.63535) (xy 49.99781 -11.604405)
			(xy 50.06513 -11.580848) (xy 50.134665 -11.564978) (xy 50.205539 -11.556992) (xy 50.276861 -11.556992)
			(xy 50.347735 -11.564978) (xy 50.41727 -11.580848) (xy 50.48459 -11.604405) (xy 50.548849 -11.63535)
			(xy 50.60924 -11.673296) (xy 50.665002 -11.717765) (xy 50.715435 -11.768198) (xy 50.759904 -11.82396)
			(xy 50.79785 -11.884351) (xy 50.828795 -11.94861) (xy 50.852352 -12.01593) (xy 50.868222 -12.085465)
			(xy 50.876208 -12.156339) (xy 50.876708 -12.192) (xy 50.876208 -12.227661) (xy 50.868222 -12.298535)
			(xy 50.852352 -12.36807) (xy 50.828795 -12.43539) (xy 50.79785 -12.499649) (xy 50.759904 -12.56004)
			(xy 50.715435 -12.615802) (xy 50.665002 -12.666235) (xy 50.60924 -12.710704) (xy 50.548849 -12.74865)
			(xy 50.48459 -12.779595) (xy 50.41727 -12.803152) (xy 50.347735 -12.819022) (xy 50.276861 -12.827008)
			(xy 50.205539 -12.827008) (xy 50.134665 -12.819022) (xy 50.06513 -12.803152) (xy 49.99781 -12.779595)
			(xy 49.933551 -12.74865) (xy 49.87316 -12.710704) (xy 49.817398 -12.666235) (xy 49.766965 -12.615802)
			(xy 49.722496 -12.56004) (xy 49.68455 -12.499649) (xy 49.653605 -12.43539) (xy 49.630048 -12.36807)
			(xy 49.614178 -12.298535) (xy 49.606192 -12.227661) (xy 43.328996 -12.227661) (xy 43.332408 -12.257939)
			(xy 43.332908 -12.2936) (xy 43.332408 -12.329261) (xy 43.324422 -12.400135) (xy 43.308552 -12.46967)
			(xy 43.284995 -12.53699) (xy 43.25405 -12.601249) (xy 43.216104 -12.66164) (xy 43.171635 -12.717402)
			(xy 43.121202 -12.767835) (xy 43.06544 -12.812304) (xy 43.005049 -12.85025) (xy 42.94079 -12.881195)
			(xy 42.87347 -12.904752) (xy 42.803935 -12.920622) (xy 42.733061 -12.928608) (xy 42.661739 -12.928608)
			(xy 42.590865 -12.920622) (xy 42.52133 -12.904752) (xy 42.45401 -12.881195) (xy 42.389751 -12.85025)
			(xy 42.32936 -12.812304) (xy 42.273598 -12.767835) (xy 42.223165 -12.717402) (xy 42.178696 -12.66164)
			(xy 42.14075 -12.601249) (xy 42.109805 -12.53699) (xy 42.086248 -12.46967) (xy 42.070378 -12.400135)
			(xy 42.062392 -12.329261) (xy 1.4732 -12.329261) (xy 1.4732 -13.542963) (xy 10.382999 -13.542963)
			(xy 10.382999 -13.457237) (xy 10.390909 -13.371877) (xy 10.406661 -13.28761) (xy 10.430121 -13.205157)
			(xy 10.461089 -13.12522) (xy 10.4993 -13.048481) (xy 10.544429 -12.975595) (xy 10.59609 -12.907184)
			(xy 10.653844 -12.843832) (xy 10.717196 -12.786078) (xy 10.785607 -12.734417) (xy 10.858493 -12.689288)
			(xy 10.935232 -12.651077) (xy 11.015169 -12.620109) (xy 11.097622 -12.596649) (xy 11.181889 -12.580897)
			(xy 11.267249 -12.572987) (xy 11.352975 -12.572987) (xy 11.438335 -12.580897) (xy 11.522602 -12.596649)
			(xy 11.605055 -12.620109) (xy 11.684992 -12.651077) (xy 11.761731 -12.689288) (xy 11.834617 -12.734417)
			(xy 11.903028 -12.786078) (xy 11.96638 -12.843832) (xy 12.024134 -12.907184) (xy 12.075795 -12.975595)
			(xy 12.115958 -13.040461) (xy 64.846192 -13.040461) (xy 64.846192 -12.969139) (xy 64.854178 -12.898265)
			(xy 64.870048 -12.82873) (xy 64.893605 -12.76141) (xy 64.92455 -12.697151) (xy 64.962496 -12.63676)
			(xy 65.006965 -12.580998) (xy 65.057398 -12.530565) (xy 65.11316 -12.486096) (xy 65.173551 -12.44815)
			(xy 65.23781 -12.417205) (xy 65.30513 -12.393648) (xy 65.374665 -12.377778) (xy 65.445539 -12.369792)
			(xy 65.516861 -12.369792) (xy 65.587735 -12.377778) (xy 65.65727 -12.393648) (xy 65.72459 -12.417205)
			(xy 65.788849 -12.44815) (xy 65.84924 -12.486096) (xy 65.905002 -12.530565) (xy 65.955435 -12.580998)
			(xy 65.999904 -12.63676) (xy 66.03785 -12.697151) (xy 66.068795 -12.76141) (xy 66.092352 -12.82873)
			(xy 66.108222 -12.898265) (xy 66.116208 -12.969139) (xy 66.116708 -13.0048) (xy 66.116208 -13.040461)
			(xy 66.108222 -13.111335) (xy 66.092352 -13.18087) (xy 66.068795 -13.24819) (xy 66.03785 -13.312449)
			(xy 65.999904 -13.37284) (xy 65.955435 -13.428602) (xy 65.905002 -13.479035) (xy 65.84924 -13.523504)
			(xy 65.788849 -13.56145) (xy 65.72459 -13.592395) (xy 65.65727 -13.615952) (xy 65.587735 -13.631822)
			(xy 65.516861 -13.639808) (xy 65.445539 -13.639808) (xy 65.374665 -13.631822) (xy 65.30513 -13.615952)
			(xy 65.23781 -13.592395) (xy 65.173551 -13.56145) (xy 65.11316 -13.523504) (xy 65.057398 -13.479035)
			(xy 65.006965 -13.428602) (xy 64.962496 -13.37284) (xy 64.92455 -13.312449) (xy 64.893605 -13.24819)
			(xy 64.870048 -13.18087) (xy 64.854178 -13.111335) (xy 64.846192 -13.040461) (xy 12.115958 -13.040461)
			(xy 12.120924 -13.048481) (xy 12.159135 -13.12522) (xy 12.190103 -13.205157) (xy 12.213563 -13.28761)
			(xy 12.229315 -13.371877) (xy 12.237225 -13.457237) (xy 12.23772 -13.5001) (xy 12.237225 -13.542963)
			(xy 12.229315 -13.628323) (xy 12.213563 -13.71259) (xy 12.190103 -13.795043) (xy 12.159135 -13.87498)
			(xy 12.120924 -13.951719) (xy 12.075795 -14.024605) (xy 12.024134 -14.093016) (xy 11.96638 -14.156368)
			(xy 11.903028 -14.214122) (xy 11.834617 -14.265783) (xy 11.761731 -14.310912) (xy 11.684992 -14.349123)
			(xy 11.605055 -14.380091) (xy 11.522602 -14.403551) (xy 11.438335 -14.419303) (xy 11.352975 -14.427213)
			(xy 11.267249 -14.427213) (xy 11.181889 -14.419303) (xy 11.097622 -14.403551) (xy 11.015169 -14.380091)
			(xy 10.935232 -14.349123) (xy 10.858493 -14.310912) (xy 10.785607 -14.265783) (xy 10.717196 -14.214122)
			(xy 10.653844 -14.156368) (xy 10.59609 -14.093016) (xy 10.544429 -14.024605) (xy 10.4993 -13.951719)
			(xy 10.461089 -13.87498) (xy 10.430121 -13.795043) (xy 10.406661 -13.71259) (xy 10.390909 -13.628323)
			(xy 10.382999 -13.542963) (xy 1.4732 -13.542963) (xy 1.4732 -14.999716) (xy 90.607899 -14.999716)
			(xy 90.611934 -14.924012) (xy 90.623993 -14.849167) (xy 90.643939 -14.776026) (xy 90.671546 -14.705421)
			(xy 90.706502 -14.63815) (xy 90.74841 -14.574975) (xy 90.796796 -14.516613) (xy 90.851112 -14.463725)
			(xy 90.910741 -14.41691) (xy 90.975009 -14.376698) (xy 91.043186 -14.343546) (xy 91.114502 -14.317828)
			(xy 91.188147 -14.299836) (xy 91.263287 -14.289774) (xy 91.339071 -14.287755) (xy 91.414641 -14.293804)
			(xy 91.489139 -14.307851) (xy 91.561722 -14.329737) (xy 91.631568 -14.359214) (xy 91.697885 -14.395949)
			(xy 91.759921 -14.439524) (xy 91.816974 -14.489446) (xy 91.868398 -14.54515) (xy 91.913609 -14.606005)
			(xy 91.952096 -14.67132) (xy 91.983422 -14.740356) (xy 92.007232 -14.812331) (xy 92.023257 -14.886429)
			(xy 92.031316 -14.96181) (xy 92.03182 -14.999716) (xy 92.607895 -14.999716) (xy 92.61193 -14.924012)
			(xy 92.623989 -14.849167) (xy 92.643935 -14.776026) (xy 92.671542 -14.705421) (xy 92.706498 -14.63815)
			(xy 92.748406 -14.574975) (xy 92.796792 -14.516613) (xy 92.851108 -14.463725) (xy 92.910737 -14.41691)
			(xy 92.975005 -14.376698) (xy 93.043182 -14.343546) (xy 93.114498 -14.317828) (xy 93.188143 -14.299836)
			(xy 93.263283 -14.289774) (xy 93.339067 -14.287755) (xy 93.414637 -14.293804) (xy 93.489135 -14.307851)
			(xy 93.561718 -14.329737) (xy 93.631564 -14.359214) (xy 93.697881 -14.395949) (xy 93.759917 -14.439524)
			(xy 93.81697 -14.489446) (xy 93.868394 -14.54515) (xy 93.913605 -14.606005) (xy 93.952092 -14.67132)
			(xy 93.983418 -14.740356) (xy 94.007228 -14.812331) (xy 94.023253 -14.886429) (xy 94.031312 -14.96181)
			(xy 94.031816 -14.999716) (xy 94.031312 -15.037622) (xy 94.023253 -15.113003) (xy 94.007228 -15.187101)
			(xy 93.983418 -15.259076) (xy 93.952092 -15.328112) (xy 93.913605 -15.393427) (xy 93.868394 -15.454282)
			(xy 93.81697 -15.509986) (xy 93.759917 -15.559908) (xy 93.697881 -15.603483) (xy 93.631564 -15.640218)
			(xy 93.561718 -15.669695) (xy 93.489135 -15.691581) (xy 93.414637 -15.705628) (xy 93.339067 -15.711677)
			(xy 93.263283 -15.709658) (xy 93.188143 -15.699596) (xy 93.114498 -15.681604) (xy 93.043182 -15.655886)
			(xy 92.975005 -15.622734) (xy 92.910737 -15.582522) (xy 92.851108 -15.535707) (xy 92.796792 -15.482819)
			(xy 92.748406 -15.424457) (xy 92.706498 -15.361282) (xy 92.671542 -15.294011) (xy 92.643935 -15.223406)
			(xy 92.623989 -15.150265) (xy 92.61193 -15.07542) (xy 92.607895 -14.999716) (xy 92.03182 -14.999716)
			(xy 92.031316 -15.037622) (xy 92.023257 -15.113003) (xy 92.007232 -15.187101) (xy 91.983422 -15.259076)
			(xy 91.952096 -15.328112) (xy 91.913609 -15.393427) (xy 91.868398 -15.454282) (xy 91.816974 -15.509986)
			(xy 91.759921 -15.559908) (xy 91.697885 -15.603483) (xy 91.631568 -15.640218) (xy 91.561722 -15.669695)
			(xy 91.489139 -15.691581) (xy 91.414641 -15.705628) (xy 91.339071 -15.711677) (xy 91.263287 -15.709658)
			(xy 91.188147 -15.699596) (xy 91.114502 -15.681604) (xy 91.043186 -15.655886) (xy 90.975009 -15.622734)
			(xy 90.910741 -15.582522) (xy 90.851112 -15.535707) (xy 90.796796 -15.482819) (xy 90.74841 -15.424457)
			(xy 90.706502 -15.361282) (xy 90.671546 -15.294011) (xy 90.643939 -15.223406) (xy 90.623993 -15.150265)
			(xy 90.611934 -15.07542) (xy 90.607899 -14.999716) (xy 1.4732 -14.999716) (xy 1.4732 -16.542957)
			(xy 10.382999 -16.542957) (xy 10.382999 -16.457231) (xy 10.390909 -16.371871) (xy 10.406661 -16.287604)
			(xy 10.430121 -16.205151) (xy 10.461089 -16.125214) (xy 10.4993 -16.048475) (xy 10.544429 -15.975589)
			(xy 10.59609 -15.907178) (xy 10.653844 -15.843826) (xy 10.717196 -15.786072) (xy 10.785607 -15.734411)
			(xy 10.858493 -15.689282) (xy 10.935232 -15.651071) (xy 11.015169 -15.620103) (xy 11.097622 -15.596643)
			(xy 11.181889 -15.580891) (xy 11.267249 -15.572981) (xy 11.352975 -15.572981) (xy 11.438335 -15.580891)
			(xy 11.522602 -15.596643) (xy 11.605055 -15.620103) (xy 11.684992 -15.651071) (xy 11.761731 -15.689282)
			(xy 11.834617 -15.734411) (xy 11.903028 -15.786072) (xy 11.96638 -15.843826) (xy 12.024134 -15.907178)
			(xy 12.075795 -15.975589) (xy 12.120924 -16.048475) (xy 12.159135 -16.125214) (xy 12.174417 -16.164661)
			(xy 34.594792 -16.164661) (xy 34.594792 -16.093339) (xy 34.602778 -16.022465) (xy 34.618648 -15.95293)
			(xy 34.642205 -15.88561) (xy 34.67315 -15.821351) (xy 34.711096 -15.76096) (xy 34.755565 -15.705198)
			(xy 34.805998 -15.654765) (xy 34.86176 -15.610296) (xy 34.922151 -15.57235) (xy 34.98641 -15.541405)
			(xy 35.05373 -15.517848) (xy 35.123265 -15.501978) (xy 35.194139 -15.493992) (xy 35.265461 -15.493992)
			(xy 35.336335 -15.501978) (xy 35.40587 -15.517848) (xy 35.47319 -15.541405) (xy 35.537449 -15.57235)
			(xy 35.59784 -15.610296) (xy 35.653602 -15.654765) (xy 35.704035 -15.705198) (xy 35.748504 -15.76096)
			(xy 35.78645 -15.821351) (xy 35.817395 -15.88561) (xy 35.840952 -15.95293) (xy 35.856822 -16.022465)
			(xy 35.864808 -16.093339) (xy 35.865308 -16.129) (xy 35.864808 -16.164661) (xy 35.856822 -16.235535)
			(xy 35.840952 -16.30507) (xy 35.817395 -16.37239) (xy 35.78645 -16.436649) (xy 35.748504 -16.49704)
			(xy 35.704035 -16.552802) (xy 35.685776 -16.571061) (xy 39.954192 -16.571061) (xy 39.954192 -16.499739)
			(xy 39.962178 -16.428865) (xy 39.978048 -16.35933) (xy 40.001605 -16.29201) (xy 40.03255 -16.227751)
			(xy 40.070496 -16.16736) (xy 40.114965 -16.111598) (xy 40.165398 -16.061165) (xy 40.22116 -16.016696)
			(xy 40.281551 -15.97875) (xy 40.34581 -15.947805) (xy 40.41313 -15.924248) (xy 40.482665 -15.908378)
			(xy 40.553539 -15.900392) (xy 40.624861 -15.900392) (xy 40.695735 -15.908378) (xy 40.76527 -15.924248)
			(xy 40.83259 -15.947805) (xy 40.896849 -15.97875) (xy 40.95724 -16.016696) (xy 41.013002 -16.061165)
			(xy 41.063435 -16.111598) (xy 41.107904 -16.16736) (xy 41.14585 -16.227751) (xy 41.176795 -16.29201)
			(xy 41.185561 -16.317061) (xy 49.047392 -16.317061) (xy 49.047392 -16.245739) (xy 49.055378 -16.174865)
			(xy 49.071248 -16.10533) (xy 49.094805 -16.03801) (xy 49.12575 -15.973751) (xy 49.163696 -15.91336)
			(xy 49.208165 -15.857598) (xy 49.258598 -15.807165) (xy 49.31436 -15.762696) (xy 49.374751 -15.72475)
			(xy 49.43901 -15.693805) (xy 49.50633 -15.670248) (xy 49.575865 -15.654378) (xy 49.646739 -15.646392)
			(xy 49.718061 -15.646392) (xy 49.788935 -15.654378) (xy 49.85847 -15.670248) (xy 49.92579 -15.693805)
			(xy 49.990049 -15.72475) (xy 50.05044 -15.762696) (xy 50.106202 -15.807165) (xy 50.156635 -15.857598)
			(xy 50.201104 -15.91336) (xy 50.23905 -15.973751) (xy 50.269995 -16.03801) (xy 50.293552 -16.10533)
			(xy 50.309422 -16.174865) (xy 50.317408 -16.245739) (xy 50.317908 -16.2814) (xy 50.317408 -16.317061)
			(xy 50.309422 -16.387935) (xy 50.293552 -16.45747) (xy 50.269995 -16.52479) (xy 50.23905 -16.589049)
			(xy 50.201104 -16.64944) (xy 50.156635 -16.705202) (xy 50.106202 -16.755635) (xy 50.05044 -16.800104)
			(xy 49.990049 -16.83805) (xy 49.92579 -16.868995) (xy 49.85847 -16.892552) (xy 49.788935 -16.908422)
			(xy 49.718061 -16.916408) (xy 49.646739 -16.916408) (xy 49.575865 -16.908422) (xy 49.50633 -16.892552)
			(xy 49.43901 -16.868995) (xy 49.374751 -16.83805) (xy 49.31436 -16.800104) (xy 49.258598 -16.755635)
			(xy 49.208165 -16.705202) (xy 49.163696 -16.64944) (xy 49.12575 -16.589049) (xy 49.094805 -16.52479)
			(xy 49.071248 -16.45747) (xy 49.055378 -16.387935) (xy 49.047392 -16.317061) (xy 41.185561 -16.317061)
			(xy 41.200352 -16.35933) (xy 41.216222 -16.428865) (xy 41.224208 -16.499739) (xy 41.224708 -16.5354)
			(xy 41.224208 -16.571061) (xy 41.216222 -16.641935) (xy 41.200352 -16.71147) (xy 41.176795 -16.77879)
			(xy 41.14585 -16.843049) (xy 41.107904 -16.90344) (xy 41.063435 -16.959202) (xy 41.013002 -17.009635)
			(xy 40.95724 -17.054104) (xy 40.896849 -17.09205) (xy 40.83259 -17.122995) (xy 40.76527 -17.146552)
			(xy 40.695735 -17.162422) (xy 40.624861 -17.170408) (xy 40.553539 -17.170408) (xy 40.482665 -17.162422)
			(xy 40.41313 -17.146552) (xy 40.34581 -17.122995) (xy 40.281551 -17.09205) (xy 40.22116 -17.054104)
			(xy 40.165398 -17.009635) (xy 40.114965 -16.959202) (xy 40.070496 -16.90344) (xy 40.03255 -16.843049)
			(xy 40.001605 -16.77879) (xy 39.978048 -16.71147) (xy 39.962178 -16.641935) (xy 39.954192 -16.571061)
			(xy 35.685776 -16.571061) (xy 35.653602 -16.603235) (xy 35.59784 -16.647704) (xy 35.537449 -16.68565)
			(xy 35.47319 -16.716595) (xy 35.40587 -16.740152) (xy 35.336335 -16.756022) (xy 35.265461 -16.764008)
			(xy 35.194139 -16.764008) (xy 35.123265 -16.756022) (xy 35.05373 -16.740152) (xy 34.98641 -16.716595)
			(xy 34.922151 -16.68565) (xy 34.86176 -16.647704) (xy 34.805998 -16.603235) (xy 34.755565 -16.552802)
			(xy 34.711096 -16.49704) (xy 34.67315 -16.436649) (xy 34.642205 -16.37239) (xy 34.618648 -16.30507)
			(xy 34.602778 -16.235535) (xy 34.594792 -16.164661) (xy 12.174417 -16.164661) (xy 12.190103 -16.205151)
			(xy 12.213563 -16.287604) (xy 12.229315 -16.371871) (xy 12.237225 -16.457231) (xy 12.23772 -16.500094)
			(xy 12.237225 -16.542957) (xy 12.229315 -16.628317) (xy 12.213563 -16.712584) (xy 12.190103 -16.795037)
			(xy 12.159135 -16.874974) (xy 12.120924 -16.951713) (xy 12.075795 -17.024599) (xy 12.024134 -17.09301)
			(xy 11.96638 -17.156362) (xy 11.903028 -17.214116) (xy 11.834617 -17.265777) (xy 11.761731 -17.310906)
			(xy 11.684992 -17.349117) (xy 11.605055 -17.380085) (xy 11.522602 -17.403545) (xy 11.438335 -17.419297)
			(xy 11.352975 -17.427207) (xy 11.267249 -17.427207) (xy 11.181889 -17.419297) (xy 11.097622 -17.403545)
			(xy 11.015169 -17.380085) (xy 10.935232 -17.349117) (xy 10.858493 -17.310906) (xy 10.785607 -17.265777)
			(xy 10.717196 -17.214116) (xy 10.653844 -17.156362) (xy 10.59609 -17.09301) (xy 10.544429 -17.024599)
			(xy 10.4993 -16.951713) (xy 10.461089 -16.874974) (xy 10.430121 -16.795037) (xy 10.406661 -16.712584)
			(xy 10.390909 -16.628317) (xy 10.382999 -16.542957) (xy 1.4732 -16.542957) (xy 1.4732 -19.287744)
			(xy 1.473654 -19.309634) (xy 1.481151 -19.352768) (xy 1.495933 -19.393977) (xy 1.517562 -19.432041)
			(xy 1.545397 -19.465833) (xy 1.578614 -19.494352) (xy 1.616229 -19.516753) (xy 1.657128 -19.532373)
			(xy 1.7001 -19.540748) (xy 1.743871 -19.541632) (xy 1.787146 -19.534997) (xy 1.828642 -19.52104)
			(xy 1.848104 -19.51101) (xy 1.887364 -19.490303) (xy 1.968955 -19.455343) (xy 2.05341 -19.428017)
			(xy 2.140016 -19.408556) (xy 2.228042 -19.397124) (xy 2.316746 -19.393818) (xy 2.405379 -19.398665)
			(xy 2.493194 -19.411624) (xy 2.579448 -19.432587) (xy 2.663416 -19.461376) (xy 2.744387 -19.497748)
			(xy 2.82168 -19.541396) (xy 2.894641 -19.591953) (xy 2.962655 -19.648992) (xy 3.025149 -19.71203)
			(xy 3.081594 -19.780538) (xy 3.131516 -19.853935) (xy 3.174491 -19.931604) (xy 3.210159 -20.012888)
			(xy 3.238217 -20.097103) (xy 3.25843 -20.183536) (xy 3.270626 -20.27146) (xy 3.274703 -20.360132)
			(xy 3.270626 -20.448804) (xy 3.25843 -20.536728) (xy 3.238217 -20.623161) (xy 3.210159 -20.707376)
			(xy 3.174491 -20.78866) (xy 3.131516 -20.866329) (xy 3.081594 -20.939726) (xy 3.025149 -21.008234)
			(xy 2.962655 -21.071272) (xy 2.894641 -21.128311) (xy 2.82168 -21.178868) (xy 2.744387 -21.222516)
			(xy 2.663416 -21.258888) (xy 2.579448 -21.287677) (xy 2.493194 -21.30864) (xy 2.405379 -21.321599)
			(xy 2.316746 -21.326446) (xy 2.228042 -21.32314) (xy 2.140016 -21.311708) (xy 2.05341 -21.292247)
			(xy 1.968955 -21.264921) (xy 1.887364 -21.229961) (xy 1.848104 -21.209254) (xy 1.828641 -21.199239)
			(xy 1.787149 -21.185307) (xy 1.743883 -21.178692) (xy 1.700124 -21.179589) (xy 1.657166 -21.187972)
			(xy 1.61628 -21.203592) (xy 1.578676 -21.225988) (xy 1.545466 -21.254497) (xy 1.517633 -21.288276)
			(xy 1.496 -21.326325) (xy 1.481208 -21.367517) (xy 1.473694 -21.410636) (xy 1.4732 -21.43252) (xy 1.4732 -22.284944)
			(xy 1.473654 -22.306834) (xy 1.481151 -22.349968) (xy 1.495933 -22.391177) (xy 1.517562 -22.429241)
			(xy 1.545397 -22.463033) (xy 1.578614 -22.491552) (xy 1.616229 -22.513953) (xy 1.657128 -22.529573)
			(xy 1.7001 -22.537948) (xy 1.743871 -22.538832) (xy 1.787146 -22.532197) (xy 1.828642 -22.51824)
			(xy 1.848104 -22.50821) (xy 1.890063 -22.486145) (xy 1.97745 -22.449375) (xy 2.068017 -22.42134)
			(xy 2.160895 -22.40231) (xy 2.25519 -22.392468) (xy 2.349996 -22.391908) (xy 2.397252 -22.395688)
			(xy 2.440557 -22.400187) (xy 2.526181 -22.415998) (xy 2.610034 -22.439451) (xy 2.691436 -22.470355)
			(xy 2.769727 -22.50846) (xy 2.844271 -22.553455) (xy 2.914463 -22.604977) (xy 2.947416 -22.633432)
			(xy 2.964789 -22.647058) (xy 3.003256 -22.668722) (xy 3.044889 -22.683413) (xy 3.088434 -22.690687)
			(xy 3.132581 -22.690327) (xy 3.176001 -22.682344) (xy 3.217388 -22.666976) (xy 3.255497 -22.644688)
			(xy 3.289181 -22.616149) (xy 3.317427 -22.582219) (xy 3.339383 -22.543918) (xy 3.354391 -22.502398)
			(xy 3.361997 -22.45891) (xy 3.362452 -22.436836) (xy 3.362452 -21.356828) (xy 3.93319 -20.78609)
			(xy 3.949446 -20.714716) (xy 3.937254 -20.680172) (xy 3.923102 -20.6384) (xy 3.90158 -20.552862)
			(xy 3.887949 -20.465718) (xy 3.882322 -20.377694) (xy 3.884746 -20.289524) (xy 3.8952 -20.201942)
			(xy 3.913597 -20.115679) (xy 3.939785 -20.031453) (xy 3.973545 -19.949966) (xy 4.014595 -19.871897)
			(xy 4.062594 -19.797897) (xy 4.117141 -19.728583) (xy 4.177782 -19.664531) (xy 4.244011 -19.606277)
			(xy 4.315277 -19.554306) (xy 4.390986 -19.50905) (xy 4.470506 -19.470887) (xy 4.553175 -19.440135)
			(xy 4.638304 -19.41705) (xy 4.725184 -19.401825) (xy 4.81309 -19.394586) (xy 4.901289 -19.395394)
			(xy 4.989048 -19.404242) (xy 5.075634 -19.421056) (xy 5.160326 -19.445696) (xy 5.242418 -19.477957)
			(xy 5.321226 -19.51757) (xy 5.361972 -19.542951) (xy 10.382999 -19.542951) (xy 10.382999 -19.457225)
			(xy 10.390909 -19.371865) (xy 10.406661 -19.287598) (xy 10.430121 -19.205145) (xy 10.461089 -19.125208)
			(xy 10.4993 -19.048469) (xy 10.544429 -18.975583) (xy 10.59609 -18.907172) (xy 10.653844 -18.84382)
			(xy 10.717196 -18.786066) (xy 10.785607 -18.734405) (xy 10.858493 -18.689276) (xy 10.935232 -18.651065)
			(xy 11.015169 -18.620097) (xy 11.097622 -18.596637) (xy 11.181889 -18.580885) (xy 11.267249 -18.572975)
			(xy 11.352975 -18.572975) (xy 11.438335 -18.580885) (xy 11.522602 -18.596637) (xy 11.605055 -18.620097)
			(xy 11.684992 -18.651065) (xy 11.761731 -18.689276) (xy 11.834617 -18.734405) (xy 11.903028 -18.786066)
			(xy 11.96638 -18.84382) (xy 12.024134 -18.907172) (xy 12.075795 -18.975583) (xy 12.120924 -19.048469)
			(xy 12.159135 -19.125208) (xy 12.190103 -19.205145) (xy 12.213563 -19.287598) (xy 12.229315 -19.371865)
			(xy 12.237225 -19.457225) (xy 12.23772 -19.500088) (xy 12.237351 -19.532039) (xy 19.996681 -19.532039)
			(xy 19.997529 -19.451093) (xy 20.006414 -19.370631) (xy 20.023247 -19.29145) (xy 20.047863 -19.214333)
			(xy 20.080018 -19.140042) (xy 20.119394 -19.069313) (xy 20.165601 -19.002846) (xy 20.218182 -18.941297)
			(xy 20.276617 -18.885276) (xy 20.340329 -18.835337) (xy 20.408686 -18.791974) (xy 20.481012 -18.755616)
			(xy 20.556592 -18.726622) (xy 20.634679 -18.70528) (xy 20.7145 -18.6918) (xy 20.754848 -18.688558)
			(xy 20.771336 -18.686912) (xy 20.802703 -18.676276) (xy 20.830275 -18.657924) (xy 20.852194 -18.633092)
			(xy 20.866981 -18.603455) (xy 20.87364 -18.57101) (xy 20.873212 -18.554446) (xy 20.871761 -18.527225)
			(xy 20.871635 -18.472707) (xy 20.872958 -18.44548) (xy 20.873378 -18.428951) (xy 20.866724 -18.396577)
			(xy 20.851966 -18.367004) (xy 20.830099 -18.342221) (xy 20.802594 -18.323896) (xy 20.7713 -18.313263)
			(xy 20.754848 -18.311622) (xy 20.714506 -18.308351) (xy 20.634695 -18.294868) (xy 20.556618 -18.273525)
			(xy 20.481047 -18.244531) (xy 20.40873 -18.208175) (xy 20.340382 -18.164816) (xy 20.276678 -18.114881)
			(xy 20.21825 -18.058866) (xy 20.165674 -17.997325) (xy 20.119472 -17.930865) (xy 20.080099 -17.860145)
			(xy 20.047946 -17.785864) (xy 20.023329 -17.708756) (xy 20.006494 -17.629585) (xy 19.997606 -17.549133)
			(xy 19.996753 -17.468195) (xy 20.003944 -17.387574) (xy 20.019108 -17.308065) (xy 20.042094 -17.230456)
			(xy 20.072675 -17.155514) (xy 20.110549 -17.08398) (xy 20.155341 -17.016561) (xy 20.206608 -16.953926)
			(xy 20.263844 -16.896692) (xy 20.326481 -16.845427) (xy 20.3939 -16.800637) (xy 20.465435 -16.762765)
			(xy 20.540379 -16.732186) (xy 20.617989 -16.709202) (xy 20.697498 -16.694041) (xy 20.77812 -16.686852)
			(xy 20.859057 -16.687708) (xy 20.939509 -16.696598) (xy 21.01868 -16.713436) (xy 21.095787 -16.738054)
			(xy 21.170067 -16.77021) (xy 21.240786 -16.809585) (xy 21.307244 -16.855789) (xy 21.368784 -16.908367)
			(xy 21.424797 -16.966797) (xy 21.47473 -17.030502) (xy 21.518087 -17.098851) (xy 21.554441 -17.17117)
			(xy 21.583432 -17.246741) (xy 21.604773 -17.324819) (xy 21.618253 -17.40463) (xy 21.621496 -17.444974)
			(xy 21.623168 -17.461457) (xy 21.633805 -17.492818) (xy 21.652154 -17.520386) (xy 21.67698 -17.542303)
			(xy 21.706609 -17.557093) (xy 21.739047 -17.56376) (xy 21.755608 -17.563338) (xy 21.782769 -17.561958)
			(xy 21.837159 -17.561958) (xy 21.86432 -17.563338) (xy 21.880887 -17.563732) (xy 21.91334 -17.557097)
			(xy 21.942986 -17.542324) (xy 21.967825 -17.52041) (xy 21.986179 -17.492837) (xy 21.996807 -17.461465)
			(xy 21.998432 -17.444974) (xy 22.001723 -17.404632) (xy 22.015204 -17.324816) (xy 22.036546 -17.246735)
			(xy 22.065538 -17.171159) (xy 22.101894 -17.098838) (xy 22.145254 -17.030485) (xy 22.195189 -16.966777)
			(xy 22.251206 -16.908345) (xy 22.312749 -16.855765) (xy 22.379211 -16.809559) (xy 22.449934 -16.770184)
			(xy 22.524219 -16.738028) (xy 22.60133 -16.713409) (xy 22.680505 -16.696573) (xy 22.760961 -16.687684)
			(xy 22.841902 -16.68683) (xy 22.922528 -16.694021) (xy 23.00204 -16.709186) (xy 23.079653 -16.732173)
			(xy 23.154599 -16.762756) (xy 23.226137 -16.800632) (xy 23.293558 -16.845427) (xy 23.356196 -16.896697)
			(xy 23.413432 -16.953936) (xy 23.464699 -17.016577) (xy 23.50949 -17.084) (xy 23.547362 -17.15554)
			(xy 23.577941 -17.230487) (xy 23.600925 -17.308101) (xy 23.616084 -17.387614) (xy 23.617099 -17.399)
			(xy 26.785314 -17.399) (xy 26.789385 -17.343378) (xy 26.801511 -17.288941) (xy 26.821434 -17.23685)
			(xy 26.84873 -17.188215) (xy 26.882816 -17.144072) (xy 26.922965 -17.105363) (xy 26.968323 -17.072912)
			(xy 27.017923 -17.047411) (xy 27.070707 -17.029404) (xy 27.12555 -17.019274) (xy 27.181284 -17.017237)
			(xy 27.236721 -17.023337) (xy 27.290678 -17.037443) (xy 27.342007 -17.059255) (xy 27.389613 -17.088309)
			(xy 27.432481 -17.123984) (xy 27.469698 -17.165521) (xy 27.500471 -17.212034) (xy 27.524143 -17.262531)
			(xy 27.540211 -17.315938) (xy 27.548331 -17.371114) (xy 27.54884 -17.399) (xy 27.548331 -17.426886)
			(xy 27.540211 -17.482062) (xy 27.524143 -17.535469) (xy 27.500471 -17.585966) (xy 27.469698 -17.632479)
			(xy 27.432481 -17.674016) (xy 27.389613 -17.709691) (xy 27.342007 -17.738745) (xy 27.290678 -17.760557)
			(xy 27.236721 -17.774663) (xy 27.181284 -17.780763) (xy 27.12555 -17.778726) (xy 27.070707 -17.768596)
			(xy 27.017923 -17.750589) (xy 26.968323 -17.725088) (xy 26.922965 -17.692637) (xy 26.882816 -17.653928)
			(xy 26.84873 -17.609785) (xy 26.821434 -17.56115) (xy 26.801511 -17.509059) (xy 26.789385 -17.454622)
			(xy 26.785314 -17.399) (xy 23.617099 -17.399) (xy 23.623271 -17.46824) (xy 23.622414 -17.549181)
			(xy 23.613521 -17.629637) (xy 23.59668 -17.708811) (xy 23.572057 -17.785921) (xy 23.539897 -17.860204)
			(xy 23.500518 -17.930925) (xy 23.454308 -17.997385) (xy 23.401726 -18.058925) (xy 23.34329 -18.114939)
			(xy 23.27958 -18.16487) (xy 23.211225 -18.208227) (xy 23.138901 -18.244579) (xy 23.063324 -18.273567)
			(xy 22.985242 -18.294905) (xy 22.905426 -18.308382) (xy 22.86508 -18.311622) (xy 22.848612 -18.31324)
			(xy 22.817287 -18.323865) (xy 22.789744 -18.342184) (xy 22.767834 -18.366966) (xy 22.753028 -18.396546)
			(xy 22.746321 -18.428937) (xy 22.746716 -18.44548) (xy 22.74824 -18.50009) (xy 22.746716 -18.554446)
			(xy 22.746248 -18.571015) (xy 22.752892 -18.603476) (xy 22.767678 -18.633129) (xy 22.789607 -18.65797)
			(xy 22.817196 -18.67632) (xy 22.848583 -18.68694) (xy 22.86508 -18.688558) (xy 22.905431 -18.691788)
			(xy 22.985256 -18.705267) (xy 23.063347 -18.726608) (xy 23.138932 -18.755601) (xy 23.211262 -18.791959)
			(xy 23.279623 -18.835323) (xy 23.343339 -18.885263) (xy 23.401778 -18.941285) (xy 23.454363 -19.002836)
			(xy 23.500573 -19.069306) (xy 23.539952 -19.140037) (xy 23.57211 -19.214331) (xy 23.596728 -19.291452)
			(xy 23.613563 -19.370636) (xy 23.622449 -19.451102) (xy 23.623298 -19.532052) (xy 23.616101 -19.612686)
			(xy 23.60093 -19.692206) (xy 23.577934 -19.769826) (xy 23.547341 -19.844778) (xy 23.509454 -19.916319)
			(xy 23.464648 -19.983744) (xy 23.413365 -20.046383) (xy 23.356113 -20.103619) (xy 23.293459 -20.154884)
			(xy 23.226022 -20.199671) (xy 23.15447 -20.237538) (xy 23.07951 -20.26811) (xy 23.001883 -20.291084)
			(xy 22.922359 -20.306233) (xy 22.841723 -20.313407) (xy 22.760773 -20.312536) (xy 22.68031 -20.303627)
			(xy 22.60113 -20.286769) (xy 22.524016 -20.262129) (xy 22.449732 -20.22995) (xy 22.379011 -20.190552)
			(xy 22.312554 -20.144323) (xy 22.251019 -20.09172) (xy 22.195013 -20.033265) (xy 22.145091 -19.969536)
			(xy 22.101746 -19.901163) (xy 22.065408 -19.828822) (xy 22.036436 -19.753229) (xy 22.015117 -19.675132)
			(xy 22.001662 -19.595303) (xy 21.998432 -19.554952) (xy 21.996701 -19.538497) (xy 21.986024 -19.507197)
			(xy 21.967663 -19.479692) (xy 21.942851 -19.457828) (xy 21.913253 -19.443074) (xy 21.880858 -19.436422)
			(xy 21.86432 -19.436842) (xy 21.837159 -19.438222) (xy 21.782769 -19.438222) (xy 21.755608 -19.436842)
			(xy 21.739058 -19.436381) (xy 21.706631 -19.442996) (xy 21.677 -19.457738) (xy 21.652164 -19.479613)
			(xy 21.633798 -19.507145) (xy 21.623141 -19.538478) (xy 21.621496 -19.554952) (xy 21.618257 -19.595301)
			(xy 21.6048 -19.675125) (xy 21.58348 -19.753218) (xy 21.554508 -19.828807) (xy 21.51817 -19.901143)
			(xy 21.474827 -19.969512) (xy 21.424906 -20.033238) (xy 21.368901 -20.091689) (xy 21.307367 -20.144288)
			(xy 21.240913 -20.190514) (xy 21.170195 -20.229909) (xy 21.095914 -20.262085) (xy 21.018804 -20.286723)
			(xy 20.939627 -20.303579) (xy 20.859168 -20.312487) (xy 20.778222 -20.313358) (xy 20.69759 -20.306183)
			(xy 20.618069 -20.291035) (xy 20.540447 -20.268061) (xy 20.46549 -20.237491) (xy 20.393941 -20.199626)
			(xy 20.326508 -20.15484) (xy 20.263856 -20.103578) (xy 20.206608 -20.046345) (xy 20.155327 -19.983708)
			(xy 20.110522 -19.916288) (xy 20.072637 -19.844749) (xy 20.042045 -19.769802) (xy 20.01905 -19.692186)
			(xy 20.003879 -19.612669) (xy 19.996681 -19.532039) (xy 12.237351 -19.532039) (xy 12.237225 -19.542951)
			(xy 12.229315 -19.628311) (xy 12.213563 -19.712578) (xy 12.190103 -19.795031) (xy 12.159135 -19.874968)
			(xy 12.120924 -19.951707) (xy 12.075795 -20.024593) (xy 12.024134 -20.093004) (xy 11.96638 -20.156356)
			(xy 11.903028 -20.21411) (xy 11.834617 -20.265771) (xy 11.761731 -20.3109) (xy 11.684992 -20.349111)
			(xy 11.605055 -20.380079) (xy 11.522602 -20.403539) (xy 11.438335 -20.419291) (xy 11.352975 -20.427201)
			(xy 11.267249 -20.427201) (xy 11.181889 -20.419291) (xy 11.097622 -20.403539) (xy 11.015169 -20.380079)
			(xy 10.935232 -20.349111) (xy 10.858493 -20.3109) (xy 10.785607 -20.265771) (xy 10.717196 -20.21411)
			(xy 10.653844 -20.156356) (xy 10.59609 -20.093004) (xy 10.544429 -20.024593) (xy 10.4993 -19.951707)
			(xy 10.461089 -19.874968) (xy 10.430121 -19.795031) (xy 10.406661 -19.712578) (xy 10.390909 -19.628311)
			(xy 10.382999 -19.542951) (xy 5.361972 -19.542951) (xy 5.396093 -19.564205) (xy 5.466395 -19.617473)
			(xy 5.531546 -19.67693) (xy 5.591004 -19.742081) (xy 5.644272 -19.812383) (xy 5.690907 -19.88725)
			(xy 5.730521 -19.966057) (xy 5.762782 -20.048149) (xy 5.787423 -20.132841) (xy 5.804238 -20.219427)
			(xy 5.813086 -20.307185) (xy 5.813894 -20.395385) (xy 5.806656 -20.483291) (xy 5.791431 -20.570171)
			(xy 5.768346 -20.6553) (xy 5.737595 -20.737969) (xy 5.699432 -20.81749) (xy 5.654177 -20.893198)
			(xy 5.602206 -20.964465) (xy 5.543952 -21.030694) (xy 5.479901 -21.091336) (xy 5.410587 -21.145883)
			(xy 5.336588 -21.193882) (xy 5.258519 -21.234933) (xy 5.177032 -21.268693) (xy 5.092806 -21.294881)
			(xy 5.006543 -21.313279) (xy 4.918961 -21.323734) (xy 4.830791 -21.326158) (xy 4.742767 -21.320531)
			(xy 4.655623 -21.306901) (xy 4.570085 -21.28538) (xy 4.528312 -21.27123) (xy 4.493768 -21.259038)
			(xy 4.422394 -21.275294) (xy 4.197604 -21.500084) (xy 19.996152 -21.500084) (xy 20.000196 -21.419054)
			(xy 20.012288 -21.33883) (xy 20.032307 -21.260208) (xy 20.060056 -21.18397) (xy 20.095257 -21.110874)
			(xy 20.137561 -21.041646) (xy 20.186548 -20.976974) (xy 20.241731 -20.917502) (xy 20.302561 -20.863819)
			(xy 20.368434 -20.816459) (xy 20.438695 -20.775894) (xy 20.512646 -20.742526) (xy 20.589552 -20.716687)
			(xy 20.668649 -20.698634) (xy 20.74915 -20.688546) (xy 20.830255 -20.686523) (xy 20.911159 -20.692586)
			(xy 20.991057 -20.706674) (xy 21.069155 -20.728647) (xy 21.144677 -20.758288) (xy 21.216873 -20.7953)
			(xy 21.285025 -20.839317) (xy 21.348455 -20.889902) (xy 21.406534 -20.94655) (xy 21.458684 -21.0087)
			(xy 21.504386 -21.075733) (xy 21.543187 -21.146983) (xy 21.574701 -21.221743) (xy 21.598615 -21.299269)
			(xy 21.61469 -21.378791) (xy 21.622768 -21.459519) (xy 21.623274 -21.500084) (xy 21.996148 -21.500084)
			(xy 22.000192 -21.419054) (xy 22.012284 -21.33883) (xy 22.032303 -21.260208) (xy 22.060052 -21.18397)
			(xy 22.095253 -21.110874) (xy 22.137557 -21.041646) (xy 22.186544 -20.976974) (xy 22.241727 -20.917502)
			(xy 22.302557 -20.863819) (xy 22.36843 -20.816459) (xy 22.438691 -20.775894) (xy 22.512642 -20.742526)
			(xy 22.589548 -20.716687) (xy 22.668645 -20.698634) (xy 22.749146 -20.688546) (xy 22.830251 -20.686523)
			(xy 22.911155 -20.692586) (xy 22.991053 -20.706674) (xy 23.069151 -20.728647) (xy 23.144673 -20.758288)
			(xy 23.216869 -20.7953) (xy 23.285021 -20.839317) (xy 23.348451 -20.889902) (xy 23.40653 -20.94655)
			(xy 23.45868 -21.0087) (xy 23.504382 -21.075733) (xy 23.543183 -21.146983) (xy 23.574697 -21.221743)
			(xy 23.598611 -21.299269) (xy 23.614686 -21.378791) (xy 23.622764 -21.459519) (xy 23.62327 -21.500084)
			(xy 23.622764 -21.540649) (xy 23.614686 -21.621377) (xy 23.598611 -21.700899) (xy 23.574697 -21.778425)
			(xy 23.543183 -21.853185) (xy 23.504382 -21.924435) (xy 23.45868 -21.991468) (xy 23.40653 -22.053618)
			(xy 23.348451 -22.110266) (xy 23.285021 -22.160851) (xy 23.216869 -22.204868) (xy 23.144673 -22.24188)
			(xy 23.069151 -22.271521) (xy 22.991053 -22.293494) (xy 22.911155 -22.307582) (xy 22.830251 -22.313645)
			(xy 22.749146 -22.311622) (xy 22.668645 -22.301534) (xy 22.589548 -22.283481) (xy 22.512642 -22.257642)
			(xy 22.438691 -22.224274) (xy 22.36843 -22.183709) (xy 22.302557 -22.136349) (xy 22.241727 -22.082666)
			(xy 22.186544 -22.023194) (xy 22.137557 -21.958522) (xy 22.095253 -21.889294) (xy 22.060052 -21.816198)
			(xy 22.032303 -21.73996) (xy 22.012284 -21.661338) (xy 22.000192 -21.581114) (xy 21.996148 -21.500084)
			(xy 21.623274 -21.500084) (xy 21.622768 -21.540649) (xy 21.61469 -21.621377) (xy 21.598615 -21.700899)
			(xy 21.574701 -21.778425) (xy 21.543187 -21.853185) (xy 21.504386 -21.924435) (xy 21.458684 -21.991468)
			(xy 21.406534 -22.053618) (xy 21.348455 -22.110266) (xy 21.285025 -22.160851) (xy 21.216873 -22.204868)
			(xy 21.144677 -22.24188) (xy 21.069155 -22.271521) (xy 20.991057 -22.293494) (xy 20.911159 -22.307582)
			(xy 20.830255 -22.313645) (xy 20.74915 -22.311622) (xy 20.668649 -22.301534) (xy 20.589552 -22.283481)
			(xy 20.512646 -22.257642) (xy 20.438695 -22.224274) (xy 20.368434 -22.183709) (xy 20.302561 -22.136349)
			(xy 20.241731 -22.082666) (xy 20.186548 -22.023194) (xy 20.137561 -21.958522) (xy 20.095257 -21.889294)
			(xy 20.060056 -21.816198) (xy 20.032307 -21.73996) (xy 20.012288 -21.661338) (xy 20.000196 -21.581114)
			(xy 19.996152 -21.500084) (xy 4.197604 -21.500084) (xy 4.054348 -21.64334) (xy 4.054348 -22.263862)
			(xy 4.054908 -22.287288) (xy 4.063541 -22.333339) (xy 4.080469 -22.377027) (xy 4.105118 -22.416873)
			(xy 4.136652 -22.451525) (xy 4.174004 -22.47981) (xy 4.215908 -22.50077) (xy 4.260943 -22.513694)
			(xy 4.307584 -22.518145) (xy 4.354251 -22.513971) (xy 4.399363 -22.501315) (xy 4.420616 -22.491446)
			(xy 4.460675 -22.472221) (xy 4.543624 -22.440349) (xy 4.629151 -22.416232) (xy 4.716531 -22.400075)
			(xy 4.805026 -22.392013) (xy 4.893887 -22.392115) (xy 4.982364 -22.40038) (xy 5.069707 -22.416738)
			(xy 5.155177 -22.44105) (xy 5.238053 -22.473112) (xy 5.317633 -22.512652) (xy 5.393244 -22.559336)
			(xy 5.464247 -22.612768) (xy 5.53004 -22.672497) (xy 5.590069 -22.738018) (xy 5.643824 -22.808777)
			(xy 5.690851 -22.884174) (xy 5.730753 -22.963573) (xy 5.763192 -23.046302) (xy 5.787894 -23.131661)
			(xy 5.80465 -23.218929) (xy 5.809488 -23.263098) (xy 5.811467 -23.278595) (xy 5.821988 -23.308003)
			(xy 5.839347 -23.333968) (xy 5.8625 -23.35493) (xy 5.890057 -23.36963) (xy 5.920363 -23.377185) (xy 5.93598 -23.377652)
			(xy 10.306558 -23.377652) (xy 10.329087 -23.377169) (xy 10.373439 -23.36923) (xy 10.415695 -23.353593)
			(xy 10.454532 -23.330747) (xy 10.48873 -23.301411) (xy 10.517218 -23.266503) (xy 10.539102 -23.227117)
			(xy 10.553697 -23.184489) (xy 10.560545 -23.139955) (xy 10.559431 -23.094912) (xy 10.550391 -23.050771)
			(xy 10.533706 -23.008917) (xy 10.522204 -22.98954) (xy 10.49998 -22.952853) (xy 10.461635 -22.876117)
			(xy 10.43054 -22.796169) (xy 10.406958 -22.713692) (xy 10.391093 -22.629389) (xy 10.38308 -22.543982)
			(xy 10.382987 -22.4582) (xy 10.390814 -22.372775) (xy 10.406496 -22.288438) (xy 10.429897 -22.20591)
			(xy 10.460819 -22.125894) (xy 10.498996 -22.049075) (xy 10.544104 -21.97611) (xy 10.595755 -21.907621)
			(xy 10.65351 -21.844194) (xy 10.716874 -21.78637) (xy 10.785307 -21.734644) (xy 10.858223 -21.689458)
			(xy 10.935 -21.651197) (xy 11.014982 -21.620188) (xy 11.097485 -21.596697) (xy 11.181805 -21.580923)
			(xy 11.267221 -21.573003) (xy 11.353003 -21.573003) (xy 11.438419 -21.580923) (xy 11.522739 -21.596697)
			(xy 11.605242 -21.620188) (xy 11.685224 -21.651197) (xy 11.762001 -21.689458) (xy 11.834917 -21.734644)
			(xy 11.90335 -21.78637) (xy 11.966714 -21.844194) (xy 12.024469 -21.907621) (xy 12.07612 -21.97611)
			(xy 12.121228 -22.049075) (xy 12.159405 -22.125894) (xy 12.190327 -22.20591) (xy 12.213728 -22.288438)
			(xy 12.22941 -22.372775) (xy 12.237237 -22.4582) (xy 12.237144 -22.543982) (xy 12.229131 -22.629389)
			(xy 12.213266 -22.713692) (xy 12.189684 -22.796169) (xy 12.158589 -22.876117) (xy 12.120244 -22.952853)
			(xy 12.09802 -22.98954) (xy 12.086539 -23.008925) (xy 12.069872 -23.050777) (xy 12.060844 -23.094912)
			(xy 12.059738 -23.139947) (xy 12.06659 -23.184472) (xy 12.081185 -23.227091) (xy 12.103065 -23.26647)
			(xy 12.131544 -23.301374) (xy 12.165732 -23.33071) (xy 12.204556 -23.35356) (xy 12.2468 -23.369206)
			(xy 12.291142 -23.37716) (xy 12.313666 -23.377652) (xy 13.306552 -23.377652) (xy 13.329073 -23.377179)
			(xy 13.373414 -23.36926) (xy 13.415663 -23.353645) (xy 13.454495 -23.330823) (xy 13.488692 -23.301509)
			(xy 13.517184 -23.266623) (xy 13.539075 -23.227258) (xy 13.55368 -23.184649) (xy 13.56054 -23.140133)
			(xy 13.559441 -23.095104) (xy 13.550417 -23.050975) (xy 13.533751 -23.00913) (xy 13.522198 -22.989794)
			(xy 13.499841 -22.952893) (xy 13.461293 -22.875697) (xy 13.430079 -22.795254) (xy 13.406471 -22.712261)
			(xy 13.390671 -22.627435) (xy 13.382816 -22.541507) (xy 13.382975 -22.455222) (xy 13.391146 -22.369324)
			(xy 13.407257 -22.284556) (xy 13.431171 -22.20165) (xy 13.46268 -22.121324) (xy 13.501512 -22.04427)
			(xy 13.547332 -21.971155) (xy 13.599743 -21.902611) (xy 13.658293 -21.839231) (xy 13.722475 -21.781561)
			(xy 13.791736 -21.7301) (xy 13.865475 -21.685293) (xy 13.943057 -21.647527) (xy 14.023811 -21.617129)
			(xy 14.107039 -21.594361) (xy 14.192021 -21.57942) (xy 14.278023 -21.572435) (xy 14.364303 -21.573466)
			(xy 14.450113 -21.582505) (xy 14.534714 -21.599473) (xy 14.617374 -21.624224) (xy 14.697378 -21.656544)
			(xy 14.774035 -21.696154) (xy 14.846682 -21.742711) (xy 14.914692 -21.795812) (xy 14.977478 -21.855)
			(xy 15.034496 -21.919763) (xy 15.085253 -21.98954) (xy 15.129312 -22.063729) (xy 15.166291 -22.141689)
			(xy 15.195871 -22.222746) (xy 15.217796 -22.306199) (xy 15.231877 -22.391328) (xy 15.237992 -22.477397)
			(xy 15.236088 -22.563662) (xy 15.226182 -22.649377) (xy 15.208359 -22.733801) (xy 15.182773 -22.816206)
			(xy 15.149645 -22.895879) (xy 15.109263 -22.972132) (xy 15.061973 -23.044305) (xy 15.008187 -23.111774)
			(xy 14.978634 -23.14321) (xy 14.961616 -23.16099) (xy 14.944598 -23.203154) (xy 14.939194 -23.217735)
			(xy 14.934878 -23.248521) (xy 14.93814 -23.279437) (xy 14.948783 -23.308646) (xy 14.966177 -23.334412)
			(xy 14.989288 -23.355204) (xy 15.016743 -23.369788) (xy 15.04691 -23.377296) (xy 15.062454 -23.377652)
			(xy 15.078456 -23.377652) (xy 15.200884 -23.50008) (xy 19.996152 -23.50008) (xy 20.000196 -23.41905)
			(xy 20.012288 -23.338826) (xy 20.032307 -23.260204) (xy 20.060056 -23.183966) (xy 20.095257 -23.11087)
			(xy 20.137561 -23.041642) (xy 20.186548 -22.97697) (xy 20.241731 -22.917498) (xy 20.302561 -22.863815)
			(xy 20.368434 -22.816455) (xy 20.438695 -22.77589) (xy 20.512646 -22.742522) (xy 20.589552 -22.716683)
			(xy 20.668649 -22.69863) (xy 20.74915 -22.688542) (xy 20.830255 -22.686519) (xy 20.911159 -22.692582)
			(xy 20.991057 -22.70667) (xy 21.069155 -22.728643) (xy 21.144677 -22.758284) (xy 21.216873 -22.795296)
			(xy 21.285025 -22.839313) (xy 21.348455 -22.889898) (xy 21.406534 -22.946546) (xy 21.458684 -23.008696)
			(xy 21.504386 -23.075729) (xy 21.543187 -23.146979) (xy 21.574701 -23.221739) (xy 21.598615 -23.299265)
			(xy 21.61469 -23.378787) (xy 21.622768 -23.459515) (xy 21.623274 -23.50008) (xy 21.996148 -23.50008)
			(xy 22.000192 -23.41905) (xy 22.012284 -23.338826) (xy 22.032303 -23.260204) (xy 22.060052 -23.183966)
			(xy 22.095253 -23.11087) (xy 22.137557 -23.041642) (xy 22.186544 -22.97697) (xy 22.241727 -22.917498)
			(xy 22.302557 -22.863815) (xy 22.36843 -22.816455) (xy 22.438691 -22.77589) (xy 22.512642 -22.742522)
			(xy 22.589548 -22.716683) (xy 22.668645 -22.69863) (xy 22.749146 -22.688542) (xy 22.830251 -22.686519)
			(xy 22.911155 -22.692582) (xy 22.991053 -22.70667) (xy 23.069151 -22.728643) (xy 23.144673 -22.758284)
			(xy 23.216869 -22.795296) (xy 23.285021 -22.839313) (xy 23.348451 -22.889898) (xy 23.40653 -22.946546)
			(xy 23.45868 -23.008696) (xy 23.504382 -23.075729) (xy 23.543183 -23.146979) (xy 23.574697 -23.221739)
			(xy 23.598611 -23.299265) (xy 23.614686 -23.378787) (xy 23.622764 -23.459515) (xy 23.62327 -23.50008)
			(xy 23.622764 -23.540645) (xy 23.614686 -23.621373) (xy 23.598611 -23.700895) (xy 23.574697 -23.778421)
			(xy 23.543183 -23.853181) (xy 23.504382 -23.924431) (xy 23.45868 -23.991464) (xy 23.40653 -24.053614)
			(xy 23.348451 -24.110262) (xy 23.285021 -24.160847) (xy 23.216869 -24.204864) (xy 23.144673 -24.241876)
			(xy 23.069151 -24.271517) (xy 22.991053 -24.29349) (xy 22.911155 -24.307578) (xy 22.830251 -24.313641)
			(xy 22.749146 -24.311618) (xy 22.668645 -24.30153) (xy 22.589548 -24.283477) (xy 22.512642 -24.257638)
			(xy 22.438691 -24.22427) (xy 22.36843 -24.183705) (xy 22.302557 -24.136345) (xy 22.241727 -24.082662)
			(xy 22.186544 -24.02319) (xy 22.137557 -23.958518) (xy 22.095253 -23.88929) (xy 22.060052 -23.816194)
			(xy 22.032303 -23.739956) (xy 22.012284 -23.661334) (xy 22.000192 -23.58111) (xy 21.996148 -23.50008)
			(xy 21.623274 -23.50008) (xy 21.622768 -23.540645) (xy 21.61469 -23.621373) (xy 21.598615 -23.700895)
			(xy 21.574701 -23.778421) (xy 21.543187 -23.853181) (xy 21.504386 -23.924431) (xy 21.458684 -23.991464)
			(xy 21.406534 -24.053614) (xy 21.348455 -24.110262) (xy 21.285025 -24.160847) (xy 21.216873 -24.204864)
			(xy 21.144677 -24.241876) (xy 21.069155 -24.271517) (xy 20.991057 -24.29349) (xy 20.911159 -24.307578)
			(xy 20.830255 -24.313641) (xy 20.74915 -24.311618) (xy 20.668649 -24.30153) (xy 20.589552 -24.283477)
			(xy 20.512646 -24.257638) (xy 20.438695 -24.22427) (xy 20.368434 -24.183705) (xy 20.302561 -24.136345)
			(xy 20.241731 -24.082662) (xy 20.186548 -24.02319) (xy 20.137561 -23.958518) (xy 20.095257 -23.88929)
			(xy 20.060056 -23.816194) (xy 20.032307 -23.739956) (xy 20.012288 -23.661334) (xy 20.000196 -23.58111)
			(xy 19.996152 -23.50008) (xy 15.200884 -23.50008) (xy 19.232835 -27.532031) (xy 19.996675 -27.532031)
			(xy 19.997523 -27.451084) (xy 20.006408 -27.370622) (xy 20.023241 -27.29144) (xy 20.047857 -27.214322)
			(xy 20.080012 -27.14003) (xy 20.119388 -27.069301) (xy 20.165596 -27.002833) (xy 20.218177 -26.941283)
			(xy 20.276613 -26.885262) (xy 20.340325 -26.835322) (xy 20.408682 -26.791959) (xy 20.481009 -26.7556)
			(xy 20.55659 -26.726606) (xy 20.634678 -26.705264) (xy 20.714499 -26.691784) (xy 20.754848 -26.688542)
			(xy 20.771338 -26.686913) (xy 20.802708 -26.676275) (xy 20.830281 -26.65792) (xy 20.8522 -26.633085)
			(xy 20.866986 -26.603444) (xy 20.873642 -26.570995) (xy 20.873212 -26.55443) (xy 20.871759 -26.527209)
			(xy 20.871634 -26.472691) (xy 20.872958 -26.445464) (xy 20.873393 -26.428936) (xy 20.866735 -26.396561)
			(xy 20.851974 -26.366987) (xy 20.830104 -26.342204) (xy 20.802596 -26.32388) (xy 20.771301 -26.313247)
			(xy 20.754848 -26.311606) (xy 20.714505 -26.308352) (xy 20.634695 -26.294869) (xy 20.556618 -26.273526)
			(xy 20.481047 -26.244533) (xy 20.40873 -26.208177) (xy 20.340382 -26.164817) (xy 20.276679 -26.114883)
			(xy 20.21825 -26.058868) (xy 20.165675 -25.997327) (xy 20.119472 -25.930868) (xy 20.080099 -25.860148)
			(xy 20.047946 -25.785867) (xy 20.023329 -25.70876) (xy 20.006494 -25.629589) (xy 19.997605 -25.549137)
			(xy 19.996752 -25.4682) (xy 20.003942 -25.387579) (xy 20.019105 -25.30807) (xy 20.042091 -25.230461)
			(xy 20.072671 -25.155519) (xy 20.110545 -25.083985) (xy 20.155336 -25.016566) (xy 20.206603 -24.95393)
			(xy 20.263837 -24.896696) (xy 20.326474 -24.845431) (xy 20.393893 -24.80064) (xy 20.465427 -24.762767)
			(xy 20.54037 -24.732188) (xy 20.617979 -24.709203) (xy 20.697488 -24.694041) (xy 20.778109 -24.686852)
			(xy 20.859046 -24.687706) (xy 20.939498 -24.696595) (xy 21.018669 -24.713432) (xy 21.095776 -24.738049)
			(xy 21.170057 -24.770203) (xy 21.240776 -24.809577) (xy 21.307235 -24.855781) (xy 21.368775 -24.908357)
			(xy 21.424789 -24.966786) (xy 21.474722 -25.03049) (xy 21.518081 -25.098838) (xy 21.554436 -25.171156)
			(xy 21.583429 -25.246727) (xy 21.604771 -25.324804) (xy 21.618253 -25.404614) (xy 21.621496 -25.444958)
			(xy 21.623181 -25.46144) (xy 21.633814 -25.492801) (xy 21.65216 -25.520368) (xy 21.676984 -25.542286)
			(xy 21.706611 -25.557077) (xy 21.739048 -25.563744) (xy 21.755608 -25.563322) (xy 21.782769 -25.561942)
			(xy 21.837159 -25.561942) (xy 21.86432 -25.563322) (xy 21.880888 -25.563731) (xy 21.913342 -25.557095)
			(xy 21.942991 -25.54232) (xy 21.96783 -25.520403) (xy 21.986183 -25.492826) (xy 21.996809 -25.46145)
			(xy 21.998432 -25.444958) (xy 22.001677 -25.404612) (xy 22.015157 -25.324797) (xy 22.036498 -25.246716)
			(xy 22.06549 -25.171141) (xy 22.101846 -25.098819) (xy 22.145205 -25.030466) (xy 22.19514 -24.966758)
			(xy 22.251156 -24.908325) (xy 22.312699 -24.855745) (xy 22.37916 -24.809539) (xy 22.449882 -24.770162)
			(xy 22.524166 -24.738005) (xy 22.601277 -24.713386) (xy 22.680452 -24.696548) (xy 22.760907 -24.687658)
			(xy 22.841848 -24.686803) (xy 22.922474 -24.693993) (xy 23.001987 -24.709155) (xy 23.0796 -24.732141)
			(xy 23.154546 -24.762722) (xy 23.226084 -24.800597) (xy 23.293506 -24.84539) (xy 23.356146 -24.896659)
			(xy 23.413383 -24.953896) (xy 23.464651 -25.016535) (xy 23.509444 -25.083957) (xy 23.547319 -25.155495)
			(xy 23.5779 -25.230442) (xy 23.600885 -25.308055) (xy 23.616048 -25.387568) (xy 23.623237 -25.468193)
			(xy 23.622382 -25.549134) (xy 23.613492 -25.62959) (xy 23.596654 -25.708765) (xy 23.572034 -25.785875)
			(xy 23.539877 -25.860159) (xy 23.5005 -25.930882) (xy 23.454294 -25.997343) (xy 23.401714 -26.058886)
			(xy 23.343281 -26.114901) (xy 23.279573 -26.164836) (xy 23.21122 -26.208195) (xy 23.138898 -26.24455)
			(xy 23.063322 -26.273542) (xy 22.985241 -26.294884) (xy 22.905426 -26.308364) (xy 22.86508 -26.311606)
			(xy 22.848615 -26.313241) (xy 22.817291 -26.323864) (xy 22.78975 -26.34218) (xy 22.76784 -26.366958)
			(xy 22.753033 -26.396534) (xy 22.746323 -26.428922) (xy 22.746716 -26.445464) (xy 22.74824 -26.500074)
			(xy 22.747727 -26.545195) (xy 22.739125 -26.635025) (xy 22.72193 -26.723613) (xy 22.709632 -26.767028)
			(xy 22.458172 -26.767028) (xy 22.399498 -26.80081) (xy 22.38248 -26.830528) (xy 22.364155 -26.861233)
			(xy 22.321887 -26.91891) (xy 22.273644 -26.971692) (xy 22.21999 -27.018963) (xy 22.161551 -27.060171)
			(xy 22.130512 -27.077924) (xy 22.115946 -27.086618) (xy 22.091669 -27.110292) (xy 22.07446 -27.13951)
			(xy 22.065525 -27.172222) (xy 22.06498 -27.189176) (xy 22.06498 -27.403044) (xy 22.027257 -27.413294)
			(xy 21.95052 -27.428226) (xy 21.872805 -27.436711) (xy 21.794654 -27.438692) (xy 21.755608 -27.436826)
			(xy 21.739059 -27.43638) (xy 21.706633 -27.442994) (xy 21.677004 -27.457734) (xy 21.652169 -27.479605)
			(xy 21.633802 -27.507134) (xy 21.623143 -27.538463) (xy 21.621496 -27.554936) (xy 21.618264 -27.595286)
			(xy 21.604807 -27.675111) (xy 21.583488 -27.753204) (xy 21.554516 -27.828794) (xy 21.518178 -27.901132)
			(xy 21.474834 -27.969502) (xy 21.424913 -28.033228) (xy 21.368909 -28.09168) (xy 21.307375 -28.144279)
			(xy 21.24092 -28.190506) (xy 21.170202 -28.229903) (xy 21.09592 -28.262079) (xy 21.018809 -28.286718)
			(xy 20.939632 -28.303575) (xy 20.859172 -28.312483) (xy 20.778226 -28.313354) (xy 20.697593 -28.30618)
			(xy 20.618071 -28.291031) (xy 20.540448 -28.268058) (xy 20.465491 -28.237488) (xy 20.393941 -28.199623)
			(xy 20.326506 -28.154837) (xy 20.263855 -28.103574) (xy 20.206605 -28.046341) (xy 20.155324 -27.983704)
			(xy 20.110519 -27.916283) (xy 20.072632 -27.844744) (xy 20.04204 -27.769796) (xy 20.019045 -27.692179)
			(xy 20.003873 -27.612662) (xy 19.996675 -27.532031) (xy 19.232835 -27.532031) (xy 21.083524 -29.38272)
			(xy 25.675842 -29.38272) (xy 25.679913 -29.327098) (xy 25.692039 -29.272661) (xy 25.711962 -29.22057)
			(xy 25.739258 -29.171935) (xy 25.773344 -29.127792) (xy 25.813493 -29.089083) (xy 25.858851 -29.056632)
			(xy 25.908451 -29.031131) (xy 25.961235 -29.013124) (xy 26.016078 -29.002994) (xy 26.071812 -29.000957)
			(xy 26.127249 -29.007057) (xy 26.181206 -29.021163) (xy 26.232535 -29.042975) (xy 26.280141 -29.072029)
			(xy 26.323009 -29.107704) (xy 26.360226 -29.149241) (xy 26.390999 -29.195754) (xy 26.414671 -29.246251)
			(xy 26.430739 -29.299658) (xy 26.438859 -29.354834) (xy 26.439368 -29.38272) (xy 26.438859 -29.410606)
			(xy 26.430739 -29.465782) (xy 26.414671 -29.519189) (xy 26.390999 -29.569686) (xy 26.360226 -29.616199)
			(xy 26.323009 -29.657736) (xy 26.280141 -29.693411) (xy 26.232535 -29.722465) (xy 26.181206 -29.744277)
			(xy 26.127249 -29.758383) (xy 26.071812 -29.764483) (xy 26.016078 -29.762446) (xy 25.961235 -29.752316)
			(xy 25.908451 -29.734309) (xy 25.858851 -29.708808) (xy 25.813493 -29.676357) (xy 25.773344 -29.637648)
			(xy 25.739258 -29.593505) (xy 25.711962 -29.54487) (xy 25.692039 -29.492779) (xy 25.679913 -29.438342)
			(xy 25.675842 -29.38272) (xy 21.083524 -29.38272) (xy 21.903436 -30.202632) (xy 29.148786 -30.202632)
			(xy 29.171138 -30.193742) (xy 29.196927 -30.184054) (xy 29.250531 -30.171354) (xy 29.305404 -30.166494)
			(xy 29.360406 -30.169573) (xy 29.414394 -30.180528) (xy 29.466245 -30.199131) (xy 29.514884 -30.224996)
			(xy 29.559298 -30.257585) (xy 29.598565 -30.296222) (xy 29.631869 -30.340103) (xy 29.658519 -30.388316)
			(xy 29.677959 -30.439859) (xy 29.689787 -30.493663) (xy 29.693757 -30.548607) (xy 29.689785 -30.603552)
			(xy 29.677955 -30.657355) (xy 29.658513 -30.708898) (xy 29.631861 -30.75711) (xy 29.598555 -30.800989)
			(xy 29.559287 -30.839624) (xy 29.514871 -30.872212) (xy 29.466232 -30.898075) (xy 29.414379 -30.916676)
			(xy 29.360391 -30.927629) (xy 29.305389 -30.930706) (xy 29.250516 -30.925843) (xy 29.196913 -30.913141)
			(xy 29.171138 -30.903418) (xy 29.148786 -30.894528) (xy 28.212034 -30.894528) (xy 28.189249 -30.895042)
			(xy 28.144411 -30.903178) (xy 28.101741 -30.919177) (xy 28.062608 -30.942528) (xy 28.028264 -30.97248)
			(xy 27.999811 -31.008076) (xy 27.978159 -31.048174) (xy 27.964003 -31.09149) (xy 27.957796 -31.136636)
			(xy 27.959737 -31.182165) (xy 27.969764 -31.226618) (xy 27.987555 -31.268572) (xy 28.012541 -31.306682)
			(xy 28.027884 -31.323534) (xy 28.078176 -31.373572) (xy 28.133548 -31.428944) (xy 28.133548 -32.362648)
			(xy 28.134067 -32.385927) (xy 28.142546 -32.431705) (xy 28.159228 -32.47517) (xy 28.183556 -32.514866)
			(xy 28.214712 -32.549461) (xy 28.251654 -32.577796) (xy 28.293142 -32.598921) (xy 28.337786 -32.612128)
			(xy 28.360878 -32.615124) (xy 28.386672 -32.618258) (xy 28.437139 -32.630622) (xy 28.461462 -32.639762)
			(xy 28.484068 -32.648652) (xy 29.625544 -32.648652) (xy 30.108144 -32.166052) (xy 30.123852 -32.149633)
			(xy 30.149754 -32.112305) (xy 30.168603 -32.070965) (xy 30.179799 -32.026931) (xy 30.182985 -31.981608)
			(xy 30.178059 -31.936442) (xy 30.165179 -31.892871) (xy 30.144754 -31.852286) (xy 30.131512 -31.83382)
			(xy 30.114439 -31.811755) (xy 30.086246 -31.763613) (xy 30.065364 -31.711879) (xy 30.052237 -31.657655)
			(xy 30.047146 -31.602098) (xy 30.050199 -31.546392) (xy 30.061331 -31.491724) (xy 30.080305 -31.43926)
			(xy 30.106715 -31.390118) (xy 30.14 -31.345345) (xy 30.17945 -31.305896) (xy 30.224223 -31.272612)
			(xy 30.273366 -31.246202) (xy 30.32583 -31.22723) (xy 30.380498 -31.216099) (xy 30.436205 -31.213046)
			(xy 30.491761 -31.218138) (xy 30.545985 -31.231266) (xy 30.597718 -31.252149) (xy 30.64586 -31.280342)
			(xy 30.66796 -31.297372) (xy 30.686417 -31.310624) (xy 30.727004 -31.331038) (xy 30.770575 -31.34391)
			(xy 30.81574 -31.348829) (xy 30.86106 -31.345638) (xy 30.90509 -31.33444) (xy 30.946427 -31.315591)
			(xy 30.983754 -31.289691) (xy 31.000192 -31.274004) (xy 31.048452 -31.225744) (xy 31.048452 -29.404056)
			(xy 29.864812 -28.220162) (xy 28.889452 -27.244802) (xy 28.888143 -27.222097) (xy 28.878475 -27.177661)
			(xy 28.861056 -27.135654) (xy 28.836442 -27.097416) (xy 28.80542 -27.064166) (xy 28.768977 -27.036964)
			(xy 28.728277 -27.016679) (xy 28.684618 -27.003957) (xy 28.639391 -26.999205) (xy 28.594041 -27.002573)
			(xy 28.550013 -27.013954) (xy 28.508712 -27.032986) (xy 28.471455 -27.059061) (xy 28.455112 -27.074876)
			(xy 28.424423 -27.106092) (xy 28.358288 -27.163454) (xy 28.287234 -27.214595) (xy 28.211842 -27.259095)
			(xy 28.132732 -27.296588) (xy 28.050553 -27.326767) (xy 27.96598 -27.349384) (xy 27.879707 -27.364253)
			(xy 27.792442 -27.371252) (xy 27.704902 -27.370325) (xy 27.617805 -27.361477) (xy 27.531866 -27.344783)
			(xy 27.447791 -27.320379) (xy 27.36627 -27.288465) (xy 27.287973 -27.249304) (xy 27.213541 -27.203217)
			(xy 27.143586 -27.150582) (xy 27.078682 -27.091831) (xy 27.019362 -27.027447) (xy 26.966114 -26.957958)
			(xy 26.919373 -26.883934) (xy 26.879524 -26.805984) (xy 26.846894 -26.724747) (xy 26.821751 -26.640891)
			(xy 26.804301 -26.555102) (xy 26.794688 -26.468087) (xy 26.79299 -26.380558) (xy 26.799221 -26.293235)
			(xy 26.813331 -26.206834) (xy 26.835202 -26.122065) (xy 26.864657 -26.039624) (xy 26.882598 -25.999694)
			(xy 26.901907 -25.959225) (xy 26.94698 -25.881704) (xy 26.999044 -25.808695) (xy 27.057651 -25.740825)
			(xy 27.089608 -25.709372) (xy 27.105437 -25.693455) (xy 27.131784 -25.657117) (xy 27.151336 -25.616715)
			(xy 27.163485 -25.573506) (xy 27.167854 -25.528834) (xy 27.164306 -25.48409) (xy 27.152951 -25.440665)
			(xy 27.134143 -25.399911) (xy 27.108467 -25.363095) (xy 27.09291 -25.346914) (xy 26.298652 -24.552656)
			(xy 26.298652 -22.615144) (xy 27.340052 -21.573744) (xy 27.340052 -21.494242) (xy 27.339541 -21.471337)
			(xy 27.331289 -21.426275) (xy 27.315098 -21.383421) (xy 27.291492 -21.34416) (xy 27.261236 -21.309763)
			(xy 27.225306 -21.281342) (xy 27.184867 -21.259817) (xy 27.141226 -21.245885) (xy 27.118564 -21.242528)
			(xy 27.091314 -21.238532) (xy 27.038271 -21.223717) (xy 26.987908 -21.20143) (xy 26.941273 -21.172134)
			(xy 26.899335 -21.136437) (xy 26.862964 -21.095081) (xy 26.832917 -21.048926) (xy 26.809818 -20.998931)
			(xy 26.794147 -20.946134) (xy 26.78623 -20.891633) (xy 26.78623 -20.836559) (xy 26.794149 -20.782058)
			(xy 26.809821 -20.729261) (xy 26.832921 -20.679266) (xy 26.862969 -20.633112) (xy 26.899341 -20.591757)
			(xy 26.94128 -20.556062) (xy 26.987916 -20.526766) (xy 27.038279 -20.50448) (xy 27.091323 -20.489667)
			(xy 27.118564 -20.485608) (xy 27.14122 -20.482195) (xy 27.184873 -20.468289) (xy 27.225325 -20.446784)
			(xy 27.261267 -20.418375) (xy 27.291534 -20.383983) (xy 27.315146 -20.344723) (xy 27.331338 -20.301866)
			(xy 27.339585 -20.2568) (xy 27.340052 -20.233894) (xy 27.340052 -19.302476) (xy 27.74442 -18.898108)
			(xy 28.077668 -18.565114) (xy 28.08732 -18.542762) (xy 28.098705 -18.517701) (xy 28.127621 -18.470864)
			(xy 28.162969 -18.428671) (xy 28.204016 -18.391996) (xy 28.249908 -18.361603) (xy 28.299692 -18.338123)
			(xy 28.352335 -18.322042) (xy 28.406742 -18.313696) (xy 28.461784 -18.313257) (xy 28.516317 -18.320735)
			(xy 28.569209 -18.335974) (xy 28.619362 -18.358658) (xy 28.665732 -18.388315) (xy 28.707358 -18.42433)
			(xy 28.743375 -18.465954) (xy 28.773035 -18.512324) (xy 28.79572 -18.562475) (xy 28.810962 -18.615367)
			(xy 28.818442 -18.6699) (xy 28.818005 -18.724942) (xy 28.809661 -18.779349) (xy 28.793583 -18.831992)
			(xy 28.770105 -18.881778) (xy 28.739714 -18.927671) (xy 28.703041 -18.968719) (xy 28.660849 -19.004069)
			(xy 28.614014 -19.032988) (xy 28.58897 -19.044412) (xy 28.566618 -19.054064) (xy 28.325064 -19.295618)
			(xy 28.031948 -19.588988) (xy 28.031948 -20.31238) (xy 28.032404 -20.334266) (xy 28.039903 -20.377391)
			(xy 28.054683 -20.418592) (xy 28.076306 -20.456651) (xy 28.104131 -20.49044) (xy 28.137337 -20.51896)
			(xy 28.174939 -20.541367) (xy 28.215826 -20.556997) (xy 28.258786 -20.565388) (xy 28.302549 -20.566292)
			(xy 28.345819 -20.559681) (xy 28.36672 -20.553172) (xy 28.392214 -20.545113) (xy 28.444789 -20.535385)
			(xy 28.498207 -20.533086) (xy 28.551424 -20.538261) (xy 28.603398 -20.550808) (xy 28.653114 -20.570484)
			(xy 28.699599 -20.596902) (xy 28.72105 -20.612862) (xy 28.728162 -20.61845) (xy 28.746196 -20.632928)
			(xy 28.791408 -20.650708) (xy 28.805229 -20.655608) (xy 28.834267 -20.659638) (xy 28.863455 -20.656906)
			(xy 28.891241 -20.647558) (xy 28.916145 -20.632091) (xy 28.92679 -20.622006) (xy 29.361384 -20.187412)
			(xy 29.361384 -17.587214) (xy 29.352494 -17.564862) (xy 29.342806 -17.539075) (xy 29.330106 -17.485474)
			(xy 29.325244 -17.430603) (xy 29.328322 -17.375604) (xy 29.339276 -17.321619) (xy 29.357877 -17.269769)
			(xy 29.38374 -17.221133) (xy 29.416327 -17.17672) (xy 29.454961 -17.137454) (xy 29.498838 -17.10415)
			(xy 29.547049 -17.077501) (xy 29.59859 -17.058061) (xy 29.65239 -17.046232) (xy 29.707332 -17.042262)
			(xy 29.762274 -17.046232) (xy 29.816074 -17.058061) (xy 29.867615 -17.077501) (xy 29.915826 -17.10415)
			(xy 29.959703 -17.137454) (xy 29.998337 -17.17672) (xy 30.030924 -17.221133) (xy 30.056787 -17.269769)
			(xy 30.075388 -17.321619) (xy 30.086342 -17.375604) (xy 30.08942 -17.430603) (xy 30.084558 -17.485474)
			(xy 30.071858 -17.539075) (xy 30.06217 -17.564862) (xy 30.05328 -17.587214) (xy 30.05328 -18.0086)
			(xy 30.595314 -18.0086) (xy 30.599385 -17.952978) (xy 30.611511 -17.898541) (xy 30.631434 -17.84645)
			(xy 30.65873 -17.797815) (xy 30.692816 -17.753672) (xy 30.732965 -17.714963) (xy 30.778323 -17.682512)
			(xy 30.827923 -17.657011) (xy 30.880707 -17.639004) (xy 30.93555 -17.628874) (xy 30.991284 -17.626837)
			(xy 31.046721 -17.632937) (xy 31.100678 -17.647043) (xy 31.152007 -17.668855) (xy 31.18446 -17.688661)
			(xy 71.399392 -17.688661) (xy 71.399392 -17.617339) (xy 71.407378 -17.546465) (xy 71.423248 -17.47693)
			(xy 71.446805 -17.40961) (xy 71.47775 -17.345351) (xy 71.515696 -17.28496) (xy 71.560165 -17.229198)
			(xy 71.610598 -17.178765) (xy 71.66636 -17.134296) (xy 71.726751 -17.09635) (xy 71.79101 -17.065405)
			(xy 71.85833 -17.041848) (xy 71.927865 -17.025978) (xy 71.998739 -17.017992) (xy 72.070061 -17.017992)
			(xy 72.140935 -17.025978) (xy 72.21047 -17.041848) (xy 72.27779 -17.065405) (xy 72.342049 -17.09635)
			(xy 72.40244 -17.134296) (xy 72.458202 -17.178765) (xy 72.508635 -17.229198) (xy 72.553104 -17.28496)
			(xy 72.59105 -17.345351) (xy 72.621995 -17.40961) (xy 72.645552 -17.47693) (xy 72.661422 -17.546465)
			(xy 72.669408 -17.617339) (xy 72.669908 -17.653) (xy 72.669408 -17.688661) (xy 72.661422 -17.759535)
			(xy 72.645552 -17.82907) (xy 72.621995 -17.89639) (xy 72.59105 -17.960649) (xy 72.553104 -18.02104)
			(xy 72.508635 -18.076802) (xy 72.458202 -18.127235) (xy 72.40244 -18.171704) (xy 72.342049 -18.20965)
			(xy 72.27779 -18.240595) (xy 72.21047 -18.264152) (xy 72.140935 -18.280022) (xy 72.070061 -18.288008)
			(xy 71.998739 -18.288008) (xy 71.927865 -18.280022) (xy 71.85833 -18.264152) (xy 71.79101 -18.240595)
			(xy 71.726751 -18.20965) (xy 71.66636 -18.171704) (xy 71.610598 -18.127235) (xy 71.560165 -18.076802)
			(xy 71.515696 -18.02104) (xy 71.47775 -17.960649) (xy 71.446805 -17.89639) (xy 71.423248 -17.82907)
			(xy 71.407378 -17.759535) (xy 71.399392 -17.688661) (xy 31.18446 -17.688661) (xy 31.199613 -17.697909)
			(xy 31.242481 -17.733584) (xy 31.279698 -17.775121) (xy 31.310471 -17.821634) (xy 31.334143 -17.872131)
			(xy 31.350211 -17.925538) (xy 31.358331 -17.980714) (xy 31.35884 -18.0086) (xy 31.358331 -18.036486)
			(xy 31.350211 -18.091662) (xy 31.334143 -18.145069) (xy 31.310471 -18.195566) (xy 31.279698 -18.242079)
			(xy 31.242481 -18.283616) (xy 31.199613 -18.319291) (xy 31.152007 -18.348345) (xy 31.100678 -18.370157)
			(xy 31.046721 -18.384263) (xy 30.991284 -18.390363) (xy 30.93555 -18.388326) (xy 30.880707 -18.378196)
			(xy 30.827923 -18.360189) (xy 30.778323 -18.334688) (xy 30.732965 -18.302237) (xy 30.692816 -18.263528)
			(xy 30.65873 -18.219385) (xy 30.631434 -18.17075) (xy 30.611511 -18.118659) (xy 30.599385 -18.064222)
			(xy 30.595314 -18.0086) (xy 30.05328 -18.0086) (xy 30.05328 -18.552261) (xy 35.966392 -18.552261)
			(xy 35.966392 -18.480939) (xy 35.974378 -18.410065) (xy 35.990248 -18.34053) (xy 36.013805 -18.27321)
			(xy 36.04475 -18.208951) (xy 36.082696 -18.14856) (xy 36.127165 -18.092798) (xy 36.177598 -18.042365)
			(xy 36.23336 -17.997896) (xy 36.293751 -17.95995) (xy 36.35801 -17.929005) (xy 36.42533 -17.905448)
			(xy 36.494865 -17.889578) (xy 36.565739 -17.881592) (xy 36.637061 -17.881592) (xy 36.707935 -17.889578)
			(xy 36.77747 -17.905448) (xy 36.84479 -17.929005) (xy 36.909049 -17.95995) (xy 36.96944 -17.997896)
			(xy 37.025202 -18.042365) (xy 37.075635 -18.092798) (xy 37.120104 -18.14856) (xy 37.15805 -18.208951)
			(xy 37.188995 -18.27321) (xy 37.212552 -18.34053) (xy 37.228422 -18.410065) (xy 37.236408 -18.480939)
			(xy 37.236908 -18.5166) (xy 37.236408 -18.552261) (xy 37.228422 -18.623135) (xy 37.221409 -18.653861)
			(xy 43.637192 -18.653861) (xy 43.637192 -18.582539) (xy 43.645178 -18.511665) (xy 43.661048 -18.44213)
			(xy 43.684605 -18.37481) (xy 43.71555 -18.310551) (xy 43.753496 -18.25016) (xy 43.797965 -18.194398)
			(xy 43.848398 -18.143965) (xy 43.90416 -18.099496) (xy 43.964551 -18.06155) (xy 44.02881 -18.030605)
			(xy 44.09613 -18.007048) (xy 44.165665 -17.991178) (xy 44.236539 -17.983192) (xy 44.307861 -17.983192)
			(xy 44.378735 -17.991178) (xy 44.44827 -18.007048) (xy 44.51559 -18.030605) (xy 44.579849 -18.06155)
			(xy 44.64024 -18.099496) (xy 44.696002 -18.143965) (xy 44.746435 -18.194398) (xy 44.790904 -18.25016)
			(xy 44.82885 -18.310551) (xy 44.859795 -18.37481) (xy 44.883352 -18.44213) (xy 44.896893 -18.501461)
			(xy 51.866792 -18.501461) (xy 51.866792 -18.430139) (xy 51.874778 -18.359265) (xy 51.890648 -18.28973)
			(xy 51.914205 -18.22241) (xy 51.94515 -18.158151) (xy 51.983096 -18.09776) (xy 52.027565 -18.041998)
			(xy 52.077998 -17.991565) (xy 52.13376 -17.947096) (xy 52.194151 -17.90915) (xy 52.25841 -17.878205)
			(xy 52.32573 -17.854648) (xy 52.395265 -17.838778) (xy 52.466139 -17.830792) (xy 52.537461 -17.830792)
			(xy 52.608335 -17.838778) (xy 52.67787 -17.854648) (xy 52.74519 -17.878205) (xy 52.809449 -17.90915)
			(xy 52.86984 -17.947096) (xy 52.925602 -17.991565) (xy 52.976035 -18.041998) (xy 53.020504 -18.09776)
			(xy 53.05845 -18.158151) (xy 53.089395 -18.22241) (xy 53.112952 -18.28973) (xy 53.128822 -18.359265)
			(xy 53.136808 -18.430139) (xy 53.137308 -18.4658) (xy 53.136808 -18.501461) (xy 53.128822 -18.572335)
			(xy 53.112952 -18.64187) (xy 53.089395 -18.70919) (xy 53.05845 -18.773449) (xy 53.020504 -18.83384)
			(xy 52.976035 -18.889602) (xy 52.957776 -18.907861) (xy 63.982592 -18.907861) (xy 63.982592 -18.836539)
			(xy 63.990578 -18.765665) (xy 64.006448 -18.69613) (xy 64.030005 -18.62881) (xy 64.06095 -18.564551)
			(xy 64.098896 -18.50416) (xy 64.143365 -18.448398) (xy 64.193798 -18.397965) (xy 64.24956 -18.353496)
			(xy 64.309951 -18.31555) (xy 64.37421 -18.284605) (xy 64.44153 -18.261048) (xy 64.511065 -18.245178)
			(xy 64.581939 -18.237192) (xy 64.653261 -18.237192) (xy 64.724135 -18.245178) (xy 64.79367 -18.261048)
			(xy 64.86099 -18.284605) (xy 64.925249 -18.31555) (xy 64.98564 -18.353496) (xy 65.041402 -18.397965)
			(xy 65.091835 -18.448398) (xy 65.136304 -18.50416) (xy 65.17425 -18.564551) (xy 65.205195 -18.62881)
			(xy 65.228752 -18.69613) (xy 65.244622 -18.765665) (xy 65.252608 -18.836539) (xy 65.253108 -18.8722)
			(xy 65.252608 -18.907861) (xy 65.244622 -18.978735) (xy 65.228752 -19.04827) (xy 65.205195 -19.11559)
			(xy 65.17425 -19.179849) (xy 65.136304 -19.24024) (xy 65.091835 -19.296002) (xy 65.041402 -19.346435)
			(xy 64.98564 -19.390904) (xy 64.925249 -19.42885) (xy 64.86099 -19.459795) (xy 64.79367 -19.483352)
			(xy 64.724135 -19.499222) (xy 64.653261 -19.507208) (xy 64.581939 -19.507208) (xy 64.511065 -19.499222)
			(xy 64.44153 -19.483352) (xy 64.37421 -19.459795) (xy 64.309951 -19.42885) (xy 64.24956 -19.390904)
			(xy 64.193798 -19.346435) (xy 64.143365 -19.296002) (xy 64.098896 -19.24024) (xy 64.06095 -19.179849)
			(xy 64.030005 -19.11559) (xy 64.006448 -19.04827) (xy 63.990578 -18.978735) (xy 63.982592 -18.907861)
			(xy 52.957776 -18.907861) (xy 52.925602 -18.940035) (xy 52.86984 -18.984504) (xy 52.809449 -19.02245)
			(xy 52.74519 -19.053395) (xy 52.67787 -19.076952) (xy 52.608335 -19.092822) (xy 52.537461 -19.100808)
			(xy 52.466139 -19.100808) (xy 52.395265 -19.092822) (xy 52.32573 -19.076952) (xy 52.25841 -19.053395)
			(xy 52.194151 -19.02245) (xy 52.13376 -18.984504) (xy 52.077998 -18.940035) (xy 52.027565 -18.889602)
			(xy 51.983096 -18.83384) (xy 51.94515 -18.773449) (xy 51.914205 -18.70919) (xy 51.890648 -18.64187)
			(xy 51.874778 -18.572335) (xy 51.866792 -18.501461) (xy 44.896893 -18.501461) (xy 44.899222 -18.511665)
			(xy 44.907208 -18.582539) (xy 44.907708 -18.6182) (xy 44.907208 -18.653861) (xy 44.899222 -18.724735)
			(xy 44.883352 -18.79427) (xy 44.859795 -18.86159) (xy 44.82885 -18.925849) (xy 44.790904 -18.98624)
			(xy 44.746435 -19.042002) (xy 44.696002 -19.092435) (xy 44.64024 -19.136904) (xy 44.579849 -19.17485)
			(xy 44.51559 -19.205795) (xy 44.44827 -19.229352) (xy 44.378735 -19.245222) (xy 44.307861 -19.253208)
			(xy 44.236539 -19.253208) (xy 44.165665 -19.245222) (xy 44.09613 -19.229352) (xy 44.02881 -19.205795)
			(xy 43.964551 -19.17485) (xy 43.90416 -19.136904) (xy 43.848398 -19.092435) (xy 43.797965 -19.042002)
			(xy 43.753496 -18.98624) (xy 43.71555 -18.925849) (xy 43.684605 -18.86159) (xy 43.661048 -18.79427)
			(xy 43.645178 -18.724735) (xy 43.637192 -18.653861) (xy 37.221409 -18.653861) (xy 37.212552 -18.69267)
			(xy 37.188995 -18.75999) (xy 37.15805 -18.824249) (xy 37.120104 -18.88464) (xy 37.075635 -18.940402)
			(xy 37.025202 -18.990835) (xy 36.96944 -19.035304) (xy 36.909049 -19.07325) (xy 36.84479 -19.104195)
			(xy 36.77747 -19.127752) (xy 36.707935 -19.143622) (xy 36.637061 -19.151608) (xy 36.565739 -19.151608)
			(xy 36.494865 -19.143622) (xy 36.42533 -19.127752) (xy 36.35801 -19.104195) (xy 36.293751 -19.07325)
			(xy 36.23336 -19.035304) (xy 36.177598 -18.990835) (xy 36.127165 -18.940402) (xy 36.082696 -18.88464)
			(xy 36.04475 -18.824249) (xy 36.013805 -18.75999) (xy 35.990248 -18.69267) (xy 35.974378 -18.623135)
			(xy 35.966392 -18.552261) (xy 30.05328 -18.552261) (xy 30.05328 -20.473924) (xy 29.999686 -20.527518)
			(xy 29.984954 -20.603972) (xy 30.000194 -20.639786) (xy 30.019244 -20.686268) (xy 30.0355 -20.70354)
			(xy 30.054078 -20.723896) (xy 30.085783 -20.768971) (xy 30.110675 -20.818137) (xy 30.128235 -20.870374)
			(xy 30.138099 -20.924592) (xy 30.138411 -20.933357) (xy 30.79846 -20.933357) (xy 30.803541 -20.877812)
			(xy 30.816655 -20.823599) (xy 30.837521 -20.771872) (xy 30.865696 -20.723734) (xy 30.900578 -20.680211)
			(xy 30.941425 -20.642229) (xy 30.987367 -20.6106) (xy 31.037424 -20.585995) (xy 31.090529 -20.56894)
			(xy 31.145552 -20.559798) (xy 31.201319 -20.558765) (xy 31.229046 -20.561808) (xy 31.252129 -20.564202)
			(xy 31.298459 -20.561641) (xy 31.343555 -20.550712) (xy 31.385918 -20.53178) (xy 31.42414 -20.505472)
			(xy 31.456952 -20.472664) (xy 31.483265 -20.434445) (xy 31.502202 -20.392084) (xy 31.513136 -20.34699)
			(xy 31.515703 -20.30066) (xy 31.513272 -20.277582) (xy 31.510233 -20.249862) (xy 31.511274 -20.194108)
			(xy 31.520421 -20.1391) (xy 31.537478 -20.08601) (xy 31.562082 -20.035968) (xy 31.593709 -19.990041)
			(xy 31.631684 -19.949207) (xy 31.6752 -19.914337) (xy 31.723328 -19.886173) (xy 31.775044 -19.865315)
			(xy 31.829245 -19.852208) (xy 31.884776 -19.847131) (xy 31.940456 -19.850192) (xy 31.995096 -19.861327)
			(xy 32.047533 -19.880296) (xy 32.096651 -19.906698) (xy 32.141401 -19.939968) (xy 32.180832 -19.979399)
			(xy 32.214102 -20.024149) (xy 32.240504 -20.073267) (xy 32.259473 -20.125704) (xy 32.270608 -20.180344)
			(xy 32.273669 -20.236024) (xy 32.268592 -20.291555) (xy 32.255485 -20.345756) (xy 32.234627 -20.397472)
			(xy 32.206463 -20.4456) (xy 32.171593 -20.489116) (xy 32.130759 -20.527091) (xy 32.084832 -20.558718)
			(xy 32.03479 -20.583322) (xy 31.9817 -20.600379) (xy 31.926692 -20.609526) (xy 31.870938 -20.610567)
			(xy 31.843218 -20.607528) (xy 31.820141 -20.605056) (xy 31.773804 -20.607624) (xy 31.728703 -20.61856)
			(xy 31.686335 -20.6375) (xy 31.64811 -20.663817) (xy 31.615297 -20.696634) (xy 31.588985 -20.734863)
			(xy 31.57005 -20.777232) (xy 31.559119 -20.822335) (xy 31.556558 -20.868672) (xy 31.558992 -20.891754)
			(xy 31.562035 -20.919481) (xy 31.561002 -20.975248) (xy 31.55186 -21.030271) (xy 31.534805 -21.083376)
			(xy 31.5102 -21.133433) (xy 31.478571 -21.179375) (xy 31.440589 -21.220222) (xy 31.397066 -21.255104)
			(xy 31.348928 -21.283279) (xy 31.297201 -21.304145) (xy 31.242988 -21.317259) (xy 31.187443 -21.32234)
			(xy 31.13175 -21.31928) (xy 31.077096 -21.308146) (xy 31.024645 -21.289172) (xy 30.975515 -21.262765)
			(xy 30.930753 -21.229487) (xy 30.891313 -21.190047) (xy 30.858035 -21.145285) (xy 30.831628 -21.096155)
			(xy 30.812654 -21.043704) (xy 30.80152 -20.98905) (xy 30.79846 -20.933357) (xy 30.138411 -20.933357)
			(xy 30.140061 -20.979666) (xy 30.134081 -21.03445) (xy 30.120283 -21.087803) (xy 30.098953 -21.138617)
			(xy 30.070536 -21.185834) (xy 30.035623 -21.228473) (xy 29.99494 -21.265646) (xy 29.949332 -21.29658)
			(xy 29.899749 -21.320632) (xy 29.847222 -21.337302) (xy 29.792843 -21.346243) (xy 29.737744 -21.347269)
			(xy 29.68307 -21.340358) (xy 29.629959 -21.325655) (xy 29.579515 -21.303465) (xy 29.532788 -21.274249)
			(xy 29.511498 -21.256752) (xy 29.473652 -21.224748) (xy 29.374592 -21.228812) (xy 28.520543 -22.082861)
			(xy 40.462192 -22.082861) (xy 40.462192 -22.011539) (xy 40.470178 -21.940665) (xy 40.486048 -21.87113)
			(xy 40.509605 -21.80381) (xy 40.54055 -21.739551) (xy 40.578496 -21.67916) (xy 40.622965 -21.623398)
			(xy 40.673398 -21.572965) (xy 40.72916 -21.528496) (xy 40.789551 -21.49055) (xy 40.85381 -21.459605)
			(xy 40.92113 -21.436048) (xy 40.990665 -21.420178) (xy 41.061539 -21.412192) (xy 41.132861 -21.412192)
			(xy 41.203735 -21.420178) (xy 41.27327 -21.436048) (xy 41.34059 -21.459605) (xy 41.404849 -21.49055)
			(xy 41.46524 -21.528496) (xy 41.491529 -21.549461) (xy 45.440592 -21.549461) (xy 45.440592 -21.478139)
			(xy 45.448578 -21.407265) (xy 45.464448 -21.33773) (xy 45.488005 -21.27041) (xy 45.51895 -21.206151)
			(xy 45.556896 -21.14576) (xy 45.601365 -21.089998) (xy 45.651798 -21.039565) (xy 45.70756 -20.995096)
			(xy 45.767951 -20.95715) (xy 45.83221 -20.926205) (xy 45.89953 -20.902648) (xy 45.969065 -20.886778)
			(xy 46.039939 -20.878792) (xy 46.111261 -20.878792) (xy 46.182135 -20.886778) (xy 46.25167 -20.902648)
			(xy 46.31899 -20.926205) (xy 46.383249 -20.95715) (xy 46.44364 -20.995096) (xy 46.499402 -21.039565)
			(xy 46.549835 -21.089998) (xy 46.594304 -21.14576) (xy 46.63225 -21.206151) (xy 46.663195 -21.27041)
			(xy 46.686752 -21.33773) (xy 46.702622 -21.407265) (xy 46.710608 -21.478139) (xy 46.711108 -21.5138)
			(xy 46.710608 -21.549461) (xy 46.702622 -21.620335) (xy 46.686752 -21.68987) (xy 46.663195 -21.75719)
			(xy 46.63225 -21.821449) (xy 46.594304 -21.88184) (xy 46.549835 -21.937602) (xy 46.499402 -21.988035)
			(xy 46.44364 -22.032504) (xy 46.383249 -22.07045) (xy 46.31899 -22.101395) (xy 46.25167 -22.124952)
			(xy 46.182135 -22.140822) (xy 46.111261 -22.148808) (xy 46.039939 -22.148808) (xy 45.969065 -22.140822)
			(xy 45.89953 -22.124952) (xy 45.83221 -22.101395) (xy 45.767951 -22.07045) (xy 45.70756 -22.032504)
			(xy 45.651798 -21.988035) (xy 45.601365 -21.937602) (xy 45.556896 -21.88184) (xy 45.51895 -21.821449)
			(xy 45.488005 -21.75719) (xy 45.464448 -21.68987) (xy 45.448578 -21.620335) (xy 45.440592 -21.549461)
			(xy 41.491529 -21.549461) (xy 41.521002 -21.572965) (xy 41.571435 -21.623398) (xy 41.615904 -21.67916)
			(xy 41.65385 -21.739551) (xy 41.684795 -21.80381) (xy 41.708352 -21.87113) (xy 41.724222 -21.940665)
			(xy 41.732208 -22.011539) (xy 41.732708 -22.0472) (xy 41.732208 -22.082861) (xy 41.724222 -22.153735)
			(xy 41.708352 -22.22327) (xy 41.684795 -22.29059) (xy 41.65385 -22.354849) (xy 41.615904 -22.41524)
			(xy 41.571435 -22.471002) (xy 41.521002 -22.521435) (xy 41.46524 -22.565904) (xy 41.404849 -22.60385)
			(xy 41.34059 -22.634795) (xy 41.27327 -22.658352) (xy 41.203735 -22.674222) (xy 41.132861 -22.682208)
			(xy 41.061539 -22.682208) (xy 40.990665 -22.674222) (xy 40.92113 -22.658352) (xy 40.85381 -22.634795)
			(xy 40.789551 -22.60385) (xy 40.72916 -22.565904) (xy 40.673398 -22.521435) (xy 40.622965 -22.471002)
			(xy 40.578496 -22.41524) (xy 40.54055 -22.354849) (xy 40.509605 -22.29059) (xy 40.486048 -22.22327)
			(xy 40.470178 -22.153735) (xy 40.462192 -22.082861) (xy 28.520543 -22.082861) (xy 28.290012 -22.313392)
			(xy 28.274867 -22.329181) (xy 28.249686 -22.364955) (xy 28.231005 -22.404513) (xy 28.219375 -22.446686)
			(xy 28.21514 -22.490228) (xy 28.218426 -22.533852) (xy 28.229134 -22.576269) (xy 28.246949 -22.616224)
			(xy 28.271345 -22.652538) (xy 28.3016 -22.684137) (xy 28.318968 -22.69744) (xy 28.355126 -22.723782)
			(xy 28.422917 -22.782165) (xy 28.485017 -22.846568) (xy 28.540894 -22.916439) (xy 28.590069 -22.991179)
			(xy 28.63212 -23.070146) (xy 28.666687 -23.152665) (xy 28.693474 -23.238027) (xy 28.71225 -23.3255)
			(xy 28.722855 -23.414336) (xy 28.725198 -23.503771) (xy 28.719259 -23.59304) (xy 28.705088 -23.681376)
			(xy 28.682808 -23.768024) (xy 28.652609 -23.852239) (xy 28.61475 -23.9333) (xy 28.569555 -24.010512)
			(xy 28.517413 -24.083212) (xy 28.45877 -24.150778) (xy 28.394129 -24.212631) (xy 28.324044 -24.268239)
			(xy 28.249116 -24.317127) (xy 28.169988 -24.358874) (xy 28.087337 -24.393124) (xy 28.001873 -24.419583)
			(xy 27.914328 -24.438023) (xy 27.825453 -24.448287) (xy 27.780742 -24.449786) (xy 27.758213 -24.450837)
			(xy 27.714036 -24.459902) (xy 27.672151 -24.476618) (xy 27.633872 -24.500463) (xy 27.600401 -24.530686)
			(xy 27.572788 -24.566341) (xy 27.551898 -24.606308) (xy 27.538387 -24.649334) (xy 27.532679 -24.694069)
			(xy 27.534953 -24.739109) (xy 27.545138 -24.783041) (xy 27.562914 -24.824488) (xy 27.587724 -24.862147)
			(xy 27.602942 -24.878792) (xy 27.832304 -25.108154) (xy 28.1051 -25.380696) (xy 28.1051 -25.462484)
			(xy 28.176728 -25.534112) (xy 28.195016 -25.543256) (xy 28.237183 -25.56525) (xy 28.317396 -25.616353)
			(xy 28.392198 -25.675094) (xy 28.426918 -25.707594) (xy 28.455112 -25.735788) (xy 28.471721 -25.75182)
			(xy 28.509605 -25.778187) (xy 28.551627 -25.79728) (xy 28.596406 -25.808473) (xy 28.64247 -25.811397)
			(xy 28.688305 -25.805956) (xy 28.732404 -25.79233) (xy 28.773318 -25.770965) (xy 28.809702 -25.742564)
			(xy 28.840361 -25.70806) (xy 28.864286 -25.668589) (xy 28.880692 -25.625446) (xy 28.889038 -25.58005)
			(xy 28.889452 -25.556972) (xy 28.889452 -24.404828) (xy 29.38399 -23.91029) (xy 29.400246 -23.838916)
			(xy 29.388054 -23.804372) (xy 29.373902 -23.7626) (xy 29.35238 -23.677062) (xy 29.338749 -23.589918)
			(xy 29.333122 -23.501894) (xy 29.335546 -23.413724) (xy 29.346 -23.326142) (xy 29.364397 -23.239879)
			(xy 29.390585 -23.155653) (xy 29.424345 -23.074166) (xy 29.465395 -22.996097) (xy 29.513394 -22.922097)
			(xy 29.567941 -22.852783) (xy 29.628582 -22.788731) (xy 29.694811 -22.730477) (xy 29.766077 -22.678506)
			(xy 29.841786 -22.63325) (xy 29.921306 -22.595087) (xy 30.003975 -22.564335) (xy 30.089104 -22.54125)
			(xy 30.175984 -22.526025) (xy 30.26389 -22.518786) (xy 30.352089 -22.519594) (xy 30.439848 -22.528442)
			(xy 30.526434 -22.545256) (xy 30.611126 -22.569896) (xy 30.693218 -22.602157) (xy 30.772026 -22.64177)
			(xy 30.846893 -22.688405) (xy 30.917195 -22.741673) (xy 30.982346 -22.80113) (xy 31.041804 -22.866281)
			(xy 31.095072 -22.936583) (xy 31.141707 -23.01145) (xy 31.181321 -23.090257) (xy 31.213582 -23.172349)
			(xy 31.229151 -23.225861) (xy 32.740592 -23.225861) (xy 32.740592 -23.154539) (xy 32.748578 -23.083665)
			(xy 32.764448 -23.01413) (xy 32.788005 -22.94681) (xy 32.81895 -22.882551) (xy 32.856896 -22.82216)
			(xy 32.901365 -22.766398) (xy 32.951798 -22.715965) (xy 33.00756 -22.671496) (xy 33.067951 -22.63355)
			(xy 33.13221 -22.602605) (xy 33.19953 -22.579048) (xy 33.269065 -22.563178) (xy 33.339939 -22.555192)
			(xy 33.411261 -22.555192) (xy 33.482135 -22.563178) (xy 33.55167 -22.579048) (xy 33.61899 -22.602605)
			(xy 33.683249 -22.63355) (xy 33.74364 -22.671496) (xy 33.799402 -22.715965) (xy 33.849835 -22.766398)
			(xy 33.894304 -22.82216) (xy 33.93225 -22.882551) (xy 33.963027 -22.946461) (xy 34.874192 -22.946461)
			(xy 34.874192 -22.875139) (xy 34.882178 -22.804265) (xy 34.898048 -22.73473) (xy 34.921605 -22.66741)
			(xy 34.95255 -22.603151) (xy 34.990496 -22.54276) (xy 35.034965 -22.486998) (xy 35.085398 -22.436565)
			(xy 35.14116 -22.392096) (xy 35.201551 -22.35415) (xy 35.26581 -22.323205) (xy 35.33313 -22.299648)
			(xy 35.402665 -22.283778) (xy 35.473539 -22.275792) (xy 35.544861 -22.275792) (xy 35.615735 -22.283778)
			(xy 35.68527 -22.299648) (xy 35.75259 -22.323205) (xy 35.816849 -22.35415) (xy 35.87724 -22.392096)
			(xy 35.933002 -22.436565) (xy 35.983435 -22.486998) (xy 36.027904 -22.54276) (xy 36.06585 -22.603151)
			(xy 36.096795 -22.66741) (xy 36.120352 -22.73473) (xy 36.136222 -22.804265) (xy 36.144208 -22.875139)
			(xy 36.144708 -22.9108) (xy 36.144208 -22.946461) (xy 36.136222 -23.017335) (xy 36.120352 -23.08687)
			(xy 36.096795 -23.15419) (xy 36.06585 -23.218449) (xy 36.027904 -23.27884) (xy 35.983435 -23.334602)
			(xy 35.933002 -23.385035) (xy 35.87724 -23.429504) (xy 35.816849 -23.46745) (xy 35.75259 -23.498395)
			(xy 35.68527 -23.521952) (xy 35.615735 -23.537822) (xy 35.544861 -23.545808) (xy 35.473539 -23.545808)
			(xy 35.402665 -23.537822) (xy 35.33313 -23.521952) (xy 35.26581 -23.498395) (xy 35.201551 -23.46745)
			(xy 35.14116 -23.429504) (xy 35.085398 -23.385035) (xy 35.034965 -23.334602) (xy 34.990496 -23.27884)
			(xy 34.95255 -23.218449) (xy 34.921605 -23.15419) (xy 34.898048 -23.08687) (xy 34.882178 -23.017335)
			(xy 34.874192 -22.946461) (xy 33.963027 -22.946461) (xy 33.963195 -22.94681) (xy 33.986752 -23.01413)
			(xy 34.002622 -23.083665) (xy 34.010608 -23.154539) (xy 34.011108 -23.1902) (xy 34.010608 -23.225861)
			(xy 34.002622 -23.296735) (xy 33.986752 -23.36627) (xy 33.963195 -23.43359) (xy 33.93225 -23.497849)
			(xy 33.894304 -23.55824) (xy 33.849835 -23.614002) (xy 33.799402 -23.664435) (xy 33.74364 -23.708904)
			(xy 33.683249 -23.74685) (xy 33.61899 -23.777795) (xy 33.55167 -23.801352) (xy 33.482135 -23.817222)
			(xy 33.411261 -23.825208) (xy 33.339939 -23.825208) (xy 33.269065 -23.817222) (xy 33.19953 -23.801352)
			(xy 33.13221 -23.777795) (xy 33.067951 -23.74685) (xy 33.00756 -23.708904) (xy 32.951798 -23.664435)
			(xy 32.901365 -23.614002) (xy 32.856896 -23.55824) (xy 32.81895 -23.497849) (xy 32.788005 -23.43359)
			(xy 32.764448 -23.36627) (xy 32.748578 -23.296735) (xy 32.740592 -23.225861) (xy 31.229151 -23.225861)
			(xy 31.238223 -23.257041) (xy 31.255038 -23.343627) (xy 31.263886 -23.431385) (xy 31.264694 -23.519585)
			(xy 31.257456 -23.607491) (xy 31.242231 -23.694371) (xy 31.219146 -23.7795) (xy 31.188395 -23.862169)
			(xy 31.150232 -23.94169) (xy 31.104977 -24.017398) (xy 31.053006 -24.088665) (xy 31.007623 -24.140261)
			(xy 68.783192 -24.140261) (xy 68.783192 -24.068939) (xy 68.791178 -23.998065) (xy 68.807048 -23.92853)
			(xy 68.830605 -23.86121) (xy 68.86155 -23.796951) (xy 68.899496 -23.73656) (xy 68.943965 -23.680798)
			(xy 68.994398 -23.630365) (xy 69.05016 -23.585896) (xy 69.110551 -23.54795) (xy 69.17481 -23.517005)
			(xy 69.24213 -23.493448) (xy 69.311665 -23.477578) (xy 69.382539 -23.469592) (xy 69.453861 -23.469592)
			(xy 69.524735 -23.477578) (xy 69.59427 -23.493448) (xy 69.66159 -23.517005) (xy 69.725849 -23.54795)
			(xy 69.78624 -23.585896) (xy 69.842002 -23.630365) (xy 69.892435 -23.680798) (xy 69.936904 -23.73656)
			(xy 69.97485 -23.796951) (xy 70.005795 -23.86121) (xy 70.029352 -23.92853) (xy 70.045222 -23.998065)
			(xy 70.053208 -24.068939) (xy 70.053708 -24.1046) (xy 70.053208 -24.140261) (xy 70.045222 -24.211135)
			(xy 70.029352 -24.28067) (xy 70.005795 -24.34799) (xy 69.97485 -24.412249) (xy 69.936904 -24.47264)
			(xy 69.892435 -24.528402) (xy 69.842002 -24.578835) (xy 69.78624 -24.623304) (xy 69.725849 -24.66125)
			(xy 69.66159 -24.692195) (xy 69.59427 -24.715752) (xy 69.524735 -24.731622) (xy 69.453861 -24.739608)
			(xy 69.382539 -24.739608) (xy 69.311665 -24.731622) (xy 69.24213 -24.715752) (xy 69.17481 -24.692195)
			(xy 69.110551 -24.66125) (xy 69.05016 -24.623304) (xy 68.994398 -24.578835) (xy 68.943965 -24.528402)
			(xy 68.899496 -24.47264) (xy 68.86155 -24.412249) (xy 68.830605 -24.34799) (xy 68.807048 -24.28067)
			(xy 68.791178 -24.211135) (xy 68.783192 -24.140261) (xy 31.007623 -24.140261) (xy 30.994752 -24.154894)
			(xy 30.930701 -24.215536) (xy 30.861387 -24.270083) (xy 30.787388 -24.318082) (xy 30.709319 -24.359133)
			(xy 30.627832 -24.392893) (xy 30.543606 -24.419081) (xy 30.457343 -24.437479) (xy 30.369761 -24.447934)
			(xy 30.281591 -24.450358) (xy 30.193567 -24.444731) (xy 30.106423 -24.431101) (xy 30.020885 -24.40958)
			(xy 29.979112 -24.39543) (xy 29.944568 -24.383238) (xy 29.873194 -24.399494) (xy 29.581348 -24.69134)
			(xy 29.581348 -25.277318) (xy 29.581825 -25.299738) (xy 29.589693 -25.343882) (xy 29.605181 -25.385962)
			(xy 29.627809 -25.424674) (xy 29.656877 -25.458816) (xy 29.691482 -25.487332) (xy 29.730552 -25.509335)
			(xy 29.772875 -25.524145) (xy 29.81714 -25.531303) (xy 29.861975 -25.530586) (xy 29.905988 -25.522016)
			(xy 29.927042 -25.5143) (xy 29.964589 -25.499061) (xy 30.041717 -25.474191) (xy 30.120658 -25.45587)
			(xy 30.200856 -25.444227) (xy 30.281748 -25.439343) (xy 30.322266 -25.439878) (xy 30.365665 -25.441381)
			(xy 30.451949 -25.451223) (xy 30.537002 -25.468771) (xy 30.620136 -25.493883) (xy 30.70068 -25.526358)
			(xy 30.777983 -25.565932) (xy 30.851422 -25.612286) (xy 30.920403 -25.665046) (xy 30.984368 -25.723785)
			(xy 31.042802 -25.78803) (xy 31.095233 -25.857261) (xy 31.141237 -25.930919) (xy 31.161228 -25.969468)
			(xy 31.170372 -25.987756) (xy 31.242 -26.059384) (xy 31.930594 -26.059384) (xy 31.95398 -26.058861)
			(xy 31.999966 -26.050318) (xy 32.043611 -26.033502) (xy 32.08344 -26.00898) (xy 32.118107 -25.977582)
			(xy 32.146441 -25.940368) (xy 32.167484 -25.898597) (xy 32.180525 -25.853679) (xy 32.185123 -25.807134)
			(xy 32.183578 -25.783794) (xy 32.181075 -25.748418) (xy 32.182999 -25.677522) (xy 32.192805 -25.60728)
			(xy 32.210371 -25.538568) (xy 32.235479 -25.472238) (xy 32.267815 -25.409116) (xy 32.306979 -25.349988)
			(xy 32.352483 -25.295587) (xy 32.40376 -25.246592) (xy 32.460175 -25.20361) (xy 32.521024 -25.167177)
			(xy 32.585551 -25.137745) (xy 32.652954 -25.115681) (xy 32.722395 -25.101259) (xy 32.79301 -25.094659)
			(xy 32.86392 -25.095961) (xy 32.934245 -25.105152) (xy 33.003109 -25.122115) (xy 33.069656 -25.14664)
			(xy 33.133058 -25.178422) (xy 33.192528 -25.217065) (xy 33.247325 -25.26209) (xy 33.296769 -25.312937)
			(xy 33.340243 -25.368972) (xy 33.377209 -25.429499) (xy 33.407205 -25.493766) (xy 33.429859 -25.560973)
			(xy 33.444889 -25.630285) (xy 33.452108 -25.700839) (xy 33.451427 -25.771758) (xy 33.442854 -25.84216)
			(xy 33.426495 -25.91117) (xy 33.402555 -25.97793) (xy 33.37133 -26.041609) (xy 33.369002 -26.045261)
			(xy 39.547792 -26.045261) (xy 39.547792 -25.973939) (xy 39.555778 -25.903065) (xy 39.571648 -25.83353)
			(xy 39.595205 -25.76621) (xy 39.62615 -25.701951) (xy 39.664096 -25.64156) (xy 39.708565 -25.585798)
			(xy 39.758998 -25.535365) (xy 39.81476 -25.490896) (xy 39.875151 -25.45295) (xy 39.93941 -25.422005)
			(xy 40.00673 -25.398448) (xy 40.076265 -25.382578) (xy 40.147139 -25.374592) (xy 40.218461 -25.374592)
			(xy 40.289335 -25.382578) (xy 40.35887 -25.398448) (xy 40.42619 -25.422005) (xy 40.490449 -25.45295)
			(xy 40.55084 -25.490896) (xy 40.606602 -25.535365) (xy 40.633898 -25.562661) (xy 54.330592 -25.562661)
			(xy 54.330592 -25.491339) (xy 54.338578 -25.420465) (xy 54.354448 -25.35093) (xy 54.378005 -25.28361)
			(xy 54.40895 -25.219351) (xy 54.446896 -25.15896) (xy 54.491365 -25.103198) (xy 54.541798 -25.052765)
			(xy 54.59756 -25.008296) (xy 54.657951 -24.97035) (xy 54.72221 -24.939405) (xy 54.78953 -24.915848)
			(xy 54.859065 -24.899978) (xy 54.929939 -24.891992) (xy 55.001261 -24.891992) (xy 55.072135 -24.899978)
			(xy 55.14167 -24.915848) (xy 55.20899 -24.939405) (xy 55.273249 -24.97035) (xy 55.33364 -25.008296)
			(xy 55.389402 -25.052765) (xy 55.439835 -25.103198) (xy 55.484304 -25.15896) (xy 55.52225 -25.219351)
			(xy 55.553195 -25.28361) (xy 55.576752 -25.35093) (xy 55.592622 -25.420465) (xy 55.597196 -25.461061)
			(xy 63.271392 -25.461061) (xy 63.271392 -25.389739) (xy 63.279378 -25.318865) (xy 63.295248 -25.24933)
			(xy 63.318805 -25.18201) (xy 63.34975 -25.117751) (xy 63.387696 -25.05736) (xy 63.432165 -25.001598)
			(xy 63.482598 -24.951165) (xy 63.53836 -24.906696) (xy 63.598751 -24.86875) (xy 63.66301 -24.837805)
			(xy 63.73033 -24.814248) (xy 63.799865 -24.798378) (xy 63.870739 -24.790392) (xy 63.942061 -24.790392)
			(xy 64.012935 -24.798378) (xy 64.08247 -24.814248) (xy 64.14979 -24.837805) (xy 64.214049 -24.86875)
			(xy 64.27444 -24.906696) (xy 64.330202 -24.951165) (xy 64.380635 -25.001598) (xy 64.425104 -25.05736)
			(xy 64.46305 -25.117751) (xy 64.493995 -25.18201) (xy 64.517552 -25.24933) (xy 64.533422 -25.318865)
			(xy 64.541408 -25.389739) (xy 64.541908 -25.4254) (xy 64.541408 -25.461061) (xy 64.533422 -25.531935)
			(xy 64.517552 -25.60147) (xy 64.49558 -25.664261) (xy 70.942192 -25.664261) (xy 70.942192 -25.592939)
			(xy 70.950178 -25.522065) (xy 70.966048 -25.45253) (xy 70.989605 -25.38521) (xy 71.02055 -25.320951)
			(xy 71.058496 -25.26056) (xy 71.102965 -25.204798) (xy 71.153398 -25.154365) (xy 71.20916 -25.109896)
			(xy 71.269551 -25.07195) (xy 71.33381 -25.041005) (xy 71.40113 -25.017448) (xy 71.470665 -25.001578)
			(xy 71.541539 -24.993592) (xy 71.612861 -24.993592) (xy 71.683735 -25.001578) (xy 71.75327 -25.017448)
			(xy 71.82059 -25.041005) (xy 71.884849 -25.07195) (xy 71.94524 -25.109896) (xy 72.001002 -25.154365)
			(xy 72.051435 -25.204798) (xy 72.095904 -25.26056) (xy 72.13385 -25.320951) (xy 72.164795 -25.38521)
			(xy 72.188352 -25.45253) (xy 72.204222 -25.522065) (xy 72.212208 -25.592939) (xy 72.212708 -25.6286)
			(xy 72.212208 -25.664261) (xy 72.206484 -25.715061) (xy 77.546192 -25.715061) (xy 77.546192 -25.643739)
			(xy 77.554178 -25.572865) (xy 77.570048 -25.50333) (xy 77.593605 -25.43601) (xy 77.62455 -25.371751)
			(xy 77.662496 -25.31136) (xy 77.706965 -25.255598) (xy 77.757398 -25.205165) (xy 77.81316 -25.160696)
			(xy 77.873551 -25.12275) (xy 77.93781 -25.091805) (xy 78.00513 -25.068248) (xy 78.074665 -25.052378)
			(xy 78.145539 -25.044392) (xy 78.216861 -25.044392) (xy 78.287735 -25.052378) (xy 78.35727 -25.068248)
			(xy 78.42459 -25.091805) (xy 78.488849 -25.12275) (xy 78.54924 -25.160696) (xy 78.605002 -25.205165)
			(xy 78.655435 -25.255598) (xy 78.699904 -25.31136) (xy 78.73785 -25.371751) (xy 78.768795 -25.43601)
			(xy 78.792352 -25.50333) (xy 78.808222 -25.572865) (xy 78.816208 -25.643739) (xy 78.816708 -25.6794)
			(xy 78.816208 -25.715061) (xy 78.808222 -25.785935) (xy 78.792352 -25.85547) (xy 78.768795 -25.92279)
			(xy 78.73785 -25.987049) (xy 78.699904 -26.04744) (xy 78.655435 -26.103202) (xy 78.606543 -26.152094)
			(xy 90.260676 -26.152094) (xy 90.264747 -26.096472) (xy 90.276873 -26.042035) (xy 90.296796 -25.989944)
			(xy 90.324092 -25.941309) (xy 90.358178 -25.897166) (xy 90.398327 -25.858457) (xy 90.443685 -25.826006)
			(xy 90.493285 -25.800505) (xy 90.546069 -25.782498) (xy 90.600912 -25.772368) (xy 90.656646 -25.770331)
			(xy 90.712083 -25.776431) (xy 90.76604 -25.790537) (xy 90.817369 -25.812349) (xy 90.864975 -25.841403)
			(xy 90.907843 -25.877078) (xy 90.94506 -25.918615) (xy 90.975833 -25.965128) (xy 90.999505 -26.015625)
			(xy 91.015573 -26.069032) (xy 91.023693 -26.124208) (xy 91.024202 -26.152094) (xy 91.023693 -26.17998)
			(xy 91.015573 -26.235156) (xy 90.999505 -26.288563) (xy 90.975833 -26.33906) (xy 90.94506 -26.385573)
			(xy 90.907843 -26.42711) (xy 90.864975 -26.462785) (xy 90.817369 -26.491839) (xy 90.76604 -26.513651)
			(xy 90.712083 -26.527757) (xy 90.656646 -26.533857) (xy 90.600912 -26.53182) (xy 90.546069 -26.52169)
			(xy 90.493285 -26.503683) (xy 90.443685 -26.478182) (xy 90.398327 -26.445731) (xy 90.358178 -26.407022)
			(xy 90.324092 -26.362879) (xy 90.296796 -26.314244) (xy 90.276873 -26.262153) (xy 90.264747 -26.207716)
			(xy 90.260676 -26.152094) (xy 78.606543 -26.152094) (xy 78.605002 -26.153635) (xy 78.54924 -26.198104)
			(xy 78.488849 -26.23605) (xy 78.42459 -26.266995) (xy 78.35727 -26.290552) (xy 78.287735 -26.306422)
			(xy 78.216861 -26.314408) (xy 78.145539 -26.314408) (xy 78.074665 -26.306422) (xy 78.00513 -26.290552)
			(xy 77.93781 -26.266995) (xy 77.873551 -26.23605) (xy 77.81316 -26.198104) (xy 77.757398 -26.153635)
			(xy 77.706965 -26.103202) (xy 77.662496 -26.04744) (xy 77.62455 -25.987049) (xy 77.593605 -25.92279)
			(xy 77.570048 -25.85547) (xy 77.554178 -25.785935) (xy 77.546192 -25.715061) (xy 72.206484 -25.715061)
			(xy 72.204222 -25.735135) (xy 72.188352 -25.80467) (xy 72.164795 -25.87199) (xy 72.13385 -25.936249)
			(xy 72.095904 -25.99664) (xy 72.051435 -26.052402) (xy 72.001002 -26.102835) (xy 71.94524 -26.147304)
			(xy 71.884849 -26.18525) (xy 71.82059 -26.216195) (xy 71.75327 -26.239752) (xy 71.683735 -26.255622)
			(xy 71.612861 -26.263608) (xy 71.541539 -26.263608) (xy 71.470665 -26.255622) (xy 71.40113 -26.239752)
			(xy 71.33381 -26.216195) (xy 71.269551 -26.18525) (xy 71.20916 -26.147304) (xy 71.153398 -26.102835)
			(xy 71.102965 -26.052402) (xy 71.058496 -25.99664) (xy 71.02055 -25.936249) (xy 70.989605 -25.87199)
			(xy 70.966048 -25.80467) (xy 70.950178 -25.735135) (xy 70.942192 -25.664261) (xy 64.49558 -25.664261)
			(xy 64.493995 -25.66879) (xy 64.46305 -25.733049) (xy 64.425104 -25.79344) (xy 64.380635 -25.849202)
			(xy 64.330202 -25.899635) (xy 64.27444 -25.944104) (xy 64.214049 -25.98205) (xy 64.14979 -26.012995)
			(xy 64.08247 -26.036552) (xy 64.012935 -26.052422) (xy 63.942061 -26.060408) (xy 63.870739 -26.060408)
			(xy 63.799865 -26.052422) (xy 63.73033 -26.036552) (xy 63.66301 -26.012995) (xy 63.598751 -25.98205)
			(xy 63.53836 -25.944104) (xy 63.482598 -25.899635) (xy 63.432165 -25.849202) (xy 63.387696 -25.79344)
			(xy 63.34975 -25.733049) (xy 63.318805 -25.66879) (xy 63.295248 -25.60147) (xy 63.279378 -25.531935)
			(xy 63.271392 -25.461061) (xy 55.597196 -25.461061) (xy 55.600608 -25.491339) (xy 55.601108 -25.527)
			(xy 55.600608 -25.562661) (xy 55.592622 -25.633535) (xy 55.576752 -25.70307) (xy 55.553195 -25.77039)
			(xy 55.52225 -25.834649) (xy 55.484304 -25.89504) (xy 55.439835 -25.950802) (xy 55.389402 -26.001235)
			(xy 55.33364 -26.045704) (xy 55.273249 -26.08365) (xy 55.20899 -26.114595) (xy 55.14167 -26.138152)
			(xy 55.072135 -26.154022) (xy 55.001261 -26.162008) (xy 54.929939 -26.162008) (xy 54.859065 -26.154022)
			(xy 54.78953 -26.138152) (xy 54.72221 -26.114595) (xy 54.657951 -26.08365) (xy 54.59756 -26.045704)
			(xy 54.541798 -26.001235) (xy 54.491365 -25.950802) (xy 54.446896 -25.89504) (xy 54.40895 -25.834649)
			(xy 54.378005 -25.77039) (xy 54.354448 -25.70307) (xy 54.338578 -25.633535) (xy 54.330592 -25.562661)
			(xy 40.633898 -25.562661) (xy 40.657035 -25.585798) (xy 40.701504 -25.64156) (xy 40.73945 -25.701951)
			(xy 40.770395 -25.76621) (xy 40.793952 -25.83353) (xy 40.809822 -25.903065) (xy 40.817808 -25.973939)
			(xy 40.818308 -26.0096) (xy 40.817808 -26.045261) (xy 40.809822 -26.116135) (xy 40.793952 -26.18567)
			(xy 40.770395 -26.25299) (xy 40.73945 -26.317249) (xy 40.701504 -26.37764) (xy 40.657035 -26.433402)
			(xy 40.606602 -26.483835) (xy 40.55084 -26.528304) (xy 40.490449 -26.56625) (xy 40.42619 -26.597195)
			(xy 40.35887 -26.620752) (xy 40.289335 -26.636622) (xy 40.218461 -26.644608) (xy 40.147139 -26.644608)
			(xy 40.076265 -26.636622) (xy 40.00673 -26.620752) (xy 39.93941 -26.597195) (xy 39.875151 -26.56625)
			(xy 39.81476 -26.528304) (xy 39.758998 -26.483835) (xy 39.708565 -26.433402) (xy 39.664096 -26.37764)
			(xy 39.62615 -26.317249) (xy 39.595205 -26.25299) (xy 39.571648 -26.18567) (xy 39.555778 -26.116135)
			(xy 39.547792 -26.045261) (xy 33.369002 -26.045261) (xy 33.333209 -26.101415) (xy 33.288666 -26.156605)
			(xy 33.238255 -26.206492) (xy 33.182603 -26.250457) (xy 33.122402 -26.287951) (xy 33.058401 -26.318509)
			(xy 33.02508 -26.330656) (xy 33.003205 -26.338824) (xy 32.962651 -26.36196) (xy 32.927007 -26.392116)
			(xy 32.897472 -26.428276) (xy 32.87504 -26.469223) (xy 32.860466 -26.513579) (xy 32.854242 -26.559851)
			(xy 32.856576 -26.606482) (xy 32.867389 -26.651901) (xy 32.886319 -26.694581) (xy 32.912727 -26.733084)
			(xy 32.928814 -26.75001) (xy 33.085786 -26.907236) (xy 33.753044 -27.574494) (xy 90.448382 -27.574494)
			(xy 90.452453 -27.518872) (xy 90.464579 -27.464435) (xy 90.484502 -27.412344) (xy 90.511798 -27.363709)
			(xy 90.545884 -27.319566) (xy 90.586033 -27.280857) (xy 90.631391 -27.248406) (xy 90.680991 -27.222905)
			(xy 90.733775 -27.204898) (xy 90.788618 -27.194768) (xy 90.844352 -27.192731) (xy 90.899789 -27.198831)
			(xy 90.953746 -27.212937) (xy 91.005075 -27.234749) (xy 91.052681 -27.263803) (xy 91.095549 -27.299478)
			(xy 91.132766 -27.341015) (xy 91.163539 -27.387528) (xy 91.187211 -27.438025) (xy 91.203279 -27.491432)
			(xy 91.211399 -27.546608) (xy 91.211908 -27.574494) (xy 91.211399 -27.60238) (xy 91.203279 -27.657556)
			(xy 91.187211 -27.710963) (xy 91.163539 -27.76146) (xy 91.132766 -27.807973) (xy 91.095549 -27.84951)
			(xy 91.052681 -27.885185) (xy 91.005075 -27.914239) (xy 90.953746 -27.936051) (xy 90.899789 -27.950157)
			(xy 90.844352 -27.956257) (xy 90.788618 -27.95422) (xy 90.733775 -27.94409) (xy 90.680991 -27.926083)
			(xy 90.631391 -27.900582) (xy 90.586033 -27.868131) (xy 90.545884 -27.829422) (xy 90.511798 -27.785279)
			(xy 90.484502 -27.736644) (xy 90.464579 -27.684553) (xy 90.452453 -27.630116) (xy 90.448382 -27.574494)
			(xy 33.753044 -27.574494) (xy 33.784286 -27.605736) (xy 33.806638 -27.615388) (xy 33.831702 -27.626773)
			(xy 33.878545 -27.655691) (xy 33.920744 -27.691042) (xy 33.957422 -27.732092) (xy 33.987819 -27.777988)
			(xy 34.011303 -27.827778) (xy 34.027386 -27.880425) (xy 34.035733 -27.934838) (xy 34.036172 -27.989886)
			(xy 34.028694 -28.044425) (xy 34.013453 -28.097323) (xy 33.990766 -28.14748) (xy 33.961105 -28.193855)
			(xy 33.925085 -28.235485) (xy 33.883455 -28.271505) (xy 33.83708 -28.301166) (xy 33.786923 -28.323853)
			(xy 33.734025 -28.339094) (xy 33.679486 -28.346572) (xy 33.624438 -28.346133) (xy 33.570025 -28.337786)
			(xy 33.517378 -28.321703) (xy 33.467588 -28.298219) (xy 33.421692 -28.267822) (xy 33.380642 -28.231144)
			(xy 33.345291 -28.188945) (xy 33.316373 -28.142102) (xy 33.304988 -28.117038) (xy 33.295336 -28.094686)
			(xy 32.688276 -27.48788) (xy 31.951676 -26.75128) (xy 31.242 -26.75128) (xy 31.170372 -26.822908)
			(xy 31.161228 -26.841196) (xy 31.140209 -26.881572) (xy 31.091645 -26.958569) (xy 31.036051 -27.030655)
			(xy 30.973919 -27.097188) (xy 30.905801 -27.157578) (xy 30.832302 -27.21129) (xy 30.754075 -27.257846)
			(xy 30.713172 -27.277822) (xy 30.664973 -27.299864) (xy 30.564798 -27.334489) (xy 30.513274 -27.34691)
			(xy 30.491717 -27.352815) (xy 30.450949 -27.371127) (xy 30.414014 -27.39629) (xy 30.382051 -27.427526)
			(xy 30.356045 -27.463873) (xy 30.336799 -27.504208) (xy 30.324907 -27.547289) (xy 30.320735 -27.591786)
			(xy 30.324412 -27.636326) (xy 30.335825 -27.679536) (xy 30.354621 -27.720083) (xy 30.380221 -27.756717)
			(xy 30.395672 -27.772868) (xy 31.708344 -29.08554) (xy 32.282382 -29.08554) (xy 32.286453 -29.029918)
			(xy 32.298579 -28.975481) (xy 32.318502 -28.92339) (xy 32.345798 -28.874755) (xy 32.379884 -28.830612)
			(xy 32.420033 -28.791903) (xy 32.465391 -28.759452) (xy 32.514991 -28.733951) (xy 32.567775 -28.715944)
			(xy 32.622618 -28.705814) (xy 32.678352 -28.703777) (xy 32.733789 -28.709877) (xy 32.787746 -28.723983)
			(xy 32.839075 -28.745795) (xy 32.886681 -28.774849) (xy 32.929549 -28.810524) (xy 32.966766 -28.852061)
			(xy 32.997539 -28.898574) (xy 33.021211 -28.949071) (xy 33.037279 -29.002478) (xy 33.045399 -29.057654)
			(xy 33.045908 -29.08554) (xy 33.045399 -29.113426) (xy 33.037279 -29.168602) (xy 33.021211 -29.222009)
			(xy 32.997539 -29.272506) (xy 32.966766 -29.319019) (xy 32.929549 -29.360556) (xy 32.886681 -29.396231)
			(xy 32.839075 -29.425285) (xy 32.787746 -29.447097) (xy 32.733789 -29.461203) (xy 32.678352 -29.467303)
			(xy 32.622618 -29.465266) (xy 32.567775 -29.455136) (xy 32.514991 -29.437129) (xy 32.465391 -29.411628)
			(xy 32.420033 -29.379177) (xy 32.379884 -29.340468) (xy 32.345798 -29.296325) (xy 32.318502 -29.24769)
			(xy 32.298579 -29.195599) (xy 32.286453 -29.141162) (xy 32.282382 -29.08554) (xy 31.708344 -29.08554)
			(xy 31.740348 -29.117544) (xy 31.740348 -31.512256) (xy 31.739332 -31.513272) (xy 31.727946 -31.525387)
			(xy 31.711273 -31.554136) (xy 31.702594 -31.586217) (xy 31.702498 -31.619451) (xy 31.710991 -31.651581)
			(xy 31.727497 -31.680427) (xy 31.738824 -31.692596) (xy 31.770574 -31.7246) (xy 31.797934 -31.726547)
			(xy 31.851719 -31.737306) (xy 31.903409 -31.755658) (xy 31.951937 -31.781224) (xy 31.996303 -31.813477)
			(xy 32.035592 -31.851752) (xy 32.068993 -31.89526) (xy 32.095818 -31.943104) (xy 32.115514 -31.994296)
			(xy 32.127674 -32.047782) (xy 32.132048 -32.102458) (xy 32.128545 -32.157197) (xy 32.117238 -32.21087)
			(xy 32.09836 -32.262369) (xy 32.072301 -32.310634) (xy 32.056324 -32.33293) (xy 32.03964 -32.354613)
			(xy 32.001087 -32.39343) (xy 31.957385 -32.426343) (xy 31.90943 -32.452675) (xy 31.858205 -32.471888)
			(xy 31.804761 -32.483587) (xy 31.750194 -32.487532) (xy 31.695623 -32.483642) (xy 31.642167 -32.471998)
			(xy 31.590923 -32.452837) (xy 31.542941 -32.426553) (xy 31.499205 -32.393685) (xy 31.460613 -32.354906)
			(xy 31.427955 -32.311013) (xy 31.414466 -32.28721) (xy 31.40226 -32.26749) (xy 31.371871 -32.232463)
			(xy 31.335629 -32.203534) (xy 31.294738 -32.181664) (xy 31.250557 -32.16758) (xy 31.204553 -32.161749)
			(xy 31.158255 -32.164366) (xy 31.113201 -32.175343) (xy 31.070888 -32.194316) (xy 31.032721 -32.220654)
			(xy 31.01594 -32.236664) (xy 30.683708 -32.568642) (xy 30.405578 -32.846772) (xy 30.389823 -32.864082)
			(xy 30.364289 -32.903303) (xy 30.346367 -32.946535) (xy 30.336661 -32.992317) (xy 30.335499 -33.039103)
			(xy 30.342922 -33.085311) (xy 30.358678 -33.129379) (xy 30.382235 -33.169818) (xy 30.412797 -33.205262)
			(xy 30.44933 -33.234512) (xy 30.4906 -33.25658) (xy 30.512766 -33.264094) (xy 30.540704 -33.27299)
			(xy 30.593662 -33.29815) (xy 30.642151 -33.33111) (xy 30.685031 -33.371097) (xy 30.721292 -33.41717)
			(xy 30.750082 -33.468245) (xy 30.760924 -33.495488) (xy 30.770145 -33.521419) (xy 30.781885 -33.575186)
			(xy 30.785779 -33.630083) (xy 30.781746 -33.684969) (xy 30.76987 -33.738707) (xy 30.750397 -33.790181)
			(xy 30.72373 -33.838323) (xy 30.690424 -33.882135) (xy 30.65117 -33.920708) (xy 30.60678 -33.953241)
			(xy 30.558178 -33.979059) (xy 30.506371 -33.997627) (xy 30.452433 -34.008559) (xy 30.397484 -34.011629)
			(xy 30.342665 -34.006773) (xy 30.289111 -33.994092) (xy 30.263338 -33.984438) (xy 30.240986 -33.975548)
			(xy 29.666692 -33.975548) (xy 29.643731 -33.976034) (xy 29.598555 -33.984273) (xy 29.555596 -34.000499)
			(xy 29.516254 -34.024184) (xy 29.481811 -34.054556) (xy 29.453389 -34.090625) (xy 29.431915 -34.131216)
			(xy 29.418087 -34.175006) (xy 29.412357 -34.220569) (xy 29.4132 -34.243518) (xy 29.414251 -34.271721)
			(xy 29.409036 -34.327914) (xy 29.395601 -34.382727) (xy 29.374239 -34.434963) (xy 29.345416 -34.483482)
			(xy 29.309762 -34.527228) (xy 29.268053 -34.565245) (xy 29.2212 -34.596704) (xy 29.170224 -34.620919)
			(xy 29.116237 -34.637362) (xy 29.060418 -34.645675) (xy 29.003982 -34.645675) (xy 28.948163 -34.637362)
			(xy 28.894176 -34.620919) (xy 28.8432 -34.596704) (xy 28.796347 -34.565245) (xy 28.754638 -34.527228)
			(xy 28.718984 -34.483482) (xy 28.690161 -34.434963) (xy 28.668799 -34.382727) (xy 28.655364 -34.327914)
			(xy 28.650149 -34.271721) (xy 28.6512 -34.243518) (xy 28.651966 -34.220573) (xy 28.64621 -34.175029)
			(xy 28.632369 -34.13126) (xy 28.610895 -34.090687) (xy 28.582485 -34.054629) (xy 28.548062 -34.024258)
			(xy 28.508746 -34.000561) (xy 28.465813 -33.984309) (xy 28.42066 -33.97603) (xy 28.397708 -33.975548)
			(xy 28.076144 -33.975548) (xy 27.441652 -33.341056) (xy 27.441652 -32.407098) (xy 27.441174 -32.384568)
			(xy 27.43324 -32.340211) (xy 27.417604 -32.297951) (xy 27.394756 -32.259112) (xy 27.365413 -32.224915)
			(xy 27.330497 -32.196431) (xy 27.291103 -32.174556) (xy 27.248466 -32.159975) (xy 27.22626 -32.156146)
			(xy 27.196628 -32.151588) (xy 27.139206 -32.134365) (xy 27.11196 -32.121856) (xy 27.08591 -32.108729)
			(xy 27.037786 -32.075765) (xy 26.995235 -32.035866) (xy 26.959249 -31.989958) (xy 26.930664 -31.939111)
			(xy 26.910146 -31.884508) (xy 26.898172 -31.827419) (xy 26.895021 -31.769173) (xy 26.89733 -31.740094)
			(xy 26.899145 -31.716579) (xy 26.895068 -31.669597) (xy 26.882395 -31.624173) (xy 26.861559 -31.581866)
			(xy 26.833277 -31.544129) (xy 26.798519 -31.512257) (xy 26.758478 -31.487343) (xy 26.714529 -31.470243)
			(xy 26.668179 -31.461544) (xy 26.6446 -31.460948) (xy 21.395944 -31.460948) (xy 15.615158 -25.680162)
			(xy 15.599524 -25.665141) (xy 15.564116 -25.640125) (xy 15.524973 -25.621487) (xy 15.483234 -25.609767)
			(xy 15.440111 -25.605306) (xy 15.396857 -25.608235) (xy 15.354728 -25.618467) (xy 15.31495 -25.635705)
			(xy 15.278676 -25.659449) (xy 15.246963 -25.689008) (xy 15.22073 -25.723524) (xy 15.200741 -25.761994)
			(xy 15.193772 -25.782524) (xy 15.180195 -25.823381) (xy 15.146485 -25.902609) (xy 15.105579 -25.978372)
			(xy 15.057827 -26.050018) (xy 15.003642 -26.116932) (xy 14.943489 -26.178536) (xy 14.877887 -26.234301)
			(xy 14.807399 -26.283747) (xy 14.732633 -26.326449) (xy 14.654231 -26.362038) (xy 14.572869 -26.390209)
			(xy 14.489246 -26.410719) (xy 14.404082 -26.423392) (xy 14.318111 -26.428119) (xy 14.232071 -26.424858)
			(xy 14.146704 -26.413639) (xy 14.062744 -26.394557) (xy 13.980913 -26.367777) (xy 13.901916 -26.333529)
			(xy 13.826433 -26.292109) (xy 13.755112 -26.243871) (xy 13.688569 -26.189233) (xy 13.627375 -26.128663)
			(xy 13.572057 -26.062683) (xy 13.523091 -25.99186) (xy 13.480899 -25.916805) (xy 13.445844 -25.838164)
			(xy 13.418226 -25.756612) (xy 13.398285 -25.672851) (xy 13.386191 -25.587604) (xy 13.382049 -25.501602)
			(xy 13.385894 -25.415587) (xy 13.397694 -25.330298) (xy 13.417346 -25.246469) (xy 13.444681 -25.164822)
			(xy 13.479465 -25.08606) (xy 13.521398 -25.01086) (xy 13.545312 -24.975058) (xy 13.557889 -24.955813)
			(xy 13.576617 -24.913831) (xy 13.587487 -24.869165) (xy 13.590147 -24.823272) (xy 13.58451 -24.777649)
			(xy 13.570758 -24.733784) (xy 13.549341 -24.693108) (xy 13.520957 -24.656947) (xy 13.486533 -24.626481)
			(xy 13.44719 -24.602704) (xy 13.404212 -24.58639) (xy 13.359 -24.578073) (xy 13.336016 -24.577548)
			(xy 12.284456 -24.577548) (xy 12.261444 -24.578049) (xy 12.216174 -24.586339) (xy 12.173135 -24.602641)
			(xy 12.133731 -24.626422) (xy 12.099251 -24.656905) (xy 12.07082 -24.693096) (xy 12.049365 -24.733813)
			(xy 12.035588 -24.777726) (xy 12.029939 -24.823401) (xy 12.032601 -24.869347) (xy 12.043489 -24.914064)
			(xy 12.062246 -24.956092) (xy 12.074906 -24.975312) (xy 12.098767 -25.010937) (xy 12.140549 -25.085818)
			(xy 12.17524 -25.164237) (xy 12.202545 -25.245523) (xy 12.222231 -25.328982) (xy 12.23413 -25.413902)
			(xy 12.238139 -25.499558) (xy 12.234225 -25.585218) (xy 12.222422 -25.670151) (xy 12.202829 -25.753632)
			(xy 12.175615 -25.834948) (xy 12.141011 -25.913406) (xy 12.099313 -25.988334) (xy 12.050877 -26.059094)
			(xy 11.996117 -26.125081) (xy 11.9355 -26.185732) (xy 11.869544 -26.240529) (xy 11.798811 -26.289004)
			(xy 11.723906 -26.330744) (xy 11.645468 -26.365391) (xy 11.564167 -26.392651) (xy 11.480696 -26.412291)
			(xy 11.39577 -26.424142) (xy 11.310112 -26.428103) (xy 11.224454 -26.424142) (xy 11.139528 -26.412291)
			(xy 11.056057 -26.392651) (xy 10.974756 -26.365391) (xy 10.896318 -26.330744) (xy 10.821413 -26.289004)
			(xy 10.75068 -26.240529) (xy 10.684724 -26.185732) (xy 10.624107 -26.125081) (xy 10.569347 -26.059094)
			(xy 10.520911 -25.988334) (xy 10.479213 -25.913406) (xy 10.444609 -25.834948) (xy 10.417395 -25.753632)
			(xy 10.397802 -25.670151) (xy 10.385999 -25.585218) (xy 10.382085 -25.499558) (xy 10.386094 -25.413902)
			(xy 10.397993 -25.328982) (xy 10.417679 -25.245523) (xy 10.444984 -25.164237) (xy 10.479675 -25.085818)
			(xy 10.521457 -25.010937) (xy 10.545318 -24.975312) (xy 10.557932 -24.956055) (xy 10.576722 -24.914035)
			(xy 10.587637 -24.869318) (xy 10.590321 -24.823367) (xy 10.584686 -24.777683) (xy 10.570916 -24.733761)
			(xy 10.549462 -24.693037) (xy 10.521024 -24.656842) (xy 10.486534 -24.626361) (xy 10.447117 -24.602589)
			(xy 10.404065 -24.586303) (xy 10.358783 -24.578038) (xy 10.335768 -24.577548) (xy 6.061456 -24.577548)
			(xy 5.832856 -24.806148) (xy 4.149344 -24.806148) (xy 3.362452 -24.019256) (xy 3.362452 -23.935944)
			(xy 3.361958 -23.919289) (xy 3.353337 -23.887113) (xy 3.336683 -23.858265) (xy 3.31313 -23.834711)
			(xy 3.284282 -23.818055) (xy 3.252107 -23.809433) (xy 3.235452 -23.808944) (xy 3.219361 -23.809422)
			(xy 3.188207 -23.817492) (xy 3.160066 -23.833105) (xy 3.13673 -23.855267) (xy 3.127756 -23.868634)
			(xy 3.104655 -23.904776) (xy 3.052968 -23.97324) (xy 2.995413 -24.03685) (xy 2.932444 -24.095104)
			(xy 2.864556 -24.147545) (xy 2.792285 -24.193758) (xy 2.7162 -24.23338) (xy 2.636901 -24.266098)
			(xy 2.555013 -24.291654) (xy 2.471181 -24.309848) (xy 2.386066 -24.320534) (xy 2.300338 -24.32363)
			(xy 2.214674 -24.319111) (xy 2.129748 -24.307013) (xy 2.046229 -24.28743) (xy 1.964777 -24.260518)
			(xy 1.886032 -24.226488) (xy 1.848104 -24.206454) (xy 1.828641 -24.196439) (xy 1.787149 -24.182507)
			(xy 1.743883 -24.175892) (xy 1.700124 -24.176789) (xy 1.657166 -24.185172) (xy 1.61628 -24.200792)
			(xy 1.578676 -24.223188) (xy 1.545466 -24.251697) (xy 1.517633 -24.285476) (xy 1.496 -24.323525)
			(xy 1.481208 -24.364717) (xy 1.473694 -24.407836) (xy 1.4732 -24.42972) (xy 1.4732 -32.456374) (xy 1.47365 -32.478154)
			(xy 1.481081 -32.521076) (xy 1.495722 -32.562101) (xy 1.517146 -32.600029) (xy 1.544724 -32.633748)
			(xy 1.577648 -32.66227) (xy 1.614953 -32.684759) (xy 1.655548 -32.700557) (xy 1.698242 -32.709201)
			(xy 1.741784 -32.710437) (xy 1.7849 -32.70423) (xy 1.826325 -32.690761) (xy 1.864847 -32.670425)
			(xy 1.899336 -32.643817) (xy 1.914398 -32.628078) (xy 1.95634 -32.582749) (xy 2.042974 -32.494718)
			(xy 2.087626 -32.452056) (xy 2.106531 -32.433719) (xy 2.140718 -32.393652) (xy 2.170408 -32.350149)
			(xy 2.18313 -32.327088) (xy 2.196972 -32.300245) (xy 2.21873 -32.243905) (xy 2.233424 -32.185324)
			(xy 2.240832 -32.125384) (xy 2.241296 -32.095186) (xy 2.241296 -28.999942) (xy 2.241792 -28.932998)
			(xy 2.249724 -28.799346) (xy 2.265559 -28.666399) (xy 2.289242 -28.534623) (xy 2.32069 -28.404482)
			(xy 2.359793 -28.276432) (xy 2.406413 -28.150923) (xy 2.460386 -28.028397) (xy 2.521523 -27.909284)
			(xy 2.589609 -27.794001) (xy 2.664404 -27.682954) (xy 2.745647 -27.576533) (xy 2.833051 -27.475112)
			(xy 2.926311 -27.379047) (xy 3.025097 -27.288676) (xy 3.129064 -27.204315) (xy 3.237845 -27.126261)
			(xy 3.35106 -27.054789) (xy 3.468309 -26.99015) (xy 3.589182 -26.932569) (xy 3.713254 -26.882251)
			(xy 3.840089 -26.839371) (xy 3.969241 -26.80408) (xy 4.100258 -26.776502) (xy 4.232677 -26.756734)
			(xy 4.366036 -26.744846) (xy 4.499864 -26.740878) (xy 4.633692 -26.744846) (xy 4.767051 -26.756734)
			(xy 4.89947 -26.776502) (xy 5.030487 -26.80408) (xy 5.159639 -26.839371) (xy 5.286474 -26.882251)
			(xy 5.410546 -26.932569) (xy 5.531419 -26.99015) (xy 5.648668 -27.054789) (xy 5.761883 -27.126261)
			(xy 5.870664 -27.204315) (xy 5.974631 -27.288676) (xy 6.073417 -27.379047) (xy 6.166677 -27.475112)
			(xy 6.254081 -27.576533) (xy 6.335324 -27.682954) (xy 6.410119 -27.794001) (xy 6.478205 -27.909284)
			(xy 6.539342 -28.028397) (xy 6.593315 -28.150923) (xy 6.639935 -28.276432) (xy 6.679038 -28.404482)
			(xy 6.710486 -28.534623) (xy 6.711979 -28.542933) (xy 10.382999 -28.542933) (xy 10.382999 -28.457207)
			(xy 10.390909 -28.371847) (xy 10.406661 -28.28758) (xy 10.430121 -28.205127) (xy 10.461089 -28.12519)
			(xy 10.4993 -28.048451) (xy 10.544429 -27.975565) (xy 10.59609 -27.907154) (xy 10.653844 -27.843802)
			(xy 10.717196 -27.786048) (xy 10.785607 -27.734387) (xy 10.858493 -27.689258) (xy 10.935232 -27.651047)
			(xy 11.015169 -27.620079) (xy 11.097622 -27.596619) (xy 11.181889 -27.580867) (xy 11.267249 -27.572957)
			(xy 11.352975 -27.572957) (xy 11.438335 -27.580867) (xy 11.522602 -27.596619) (xy 11.605055 -27.620079)
			(xy 11.684992 -27.651047) (xy 11.761731 -27.689258) (xy 11.834617 -27.734387) (xy 11.903028 -27.786048)
			(xy 11.96638 -27.843802) (xy 12.024134 -27.907154) (xy 12.075795 -27.975565) (xy 12.120924 -28.048451)
			(xy 12.159135 -28.12519) (xy 12.190103 -28.205127) (xy 12.213563 -28.28758) (xy 12.229315 -28.371847)
			(xy 12.237225 -28.457207) (xy 12.23772 -28.50007) (xy 12.237225 -28.542933) (xy 12.229315 -28.628293)
			(xy 12.213563 -28.71256) (xy 12.190103 -28.795013) (xy 12.159135 -28.87495) (xy 12.120924 -28.951689)
			(xy 12.075795 -29.024575) (xy 12.024134 -29.092986) (xy 11.96638 -29.156338) (xy 11.903028 -29.214092)
			(xy 11.834617 -29.265753) (xy 11.761731 -29.310882) (xy 11.684992 -29.349093) (xy 11.605055 -29.380061)
			(xy 11.522602 -29.403521) (xy 11.438335 -29.419273) (xy 11.352975 -29.427183) (xy 11.267249 -29.427183)
			(xy 11.181889 -29.419273) (xy 11.097622 -29.403521) (xy 11.015169 -29.380061) (xy 10.935232 -29.349093)
			(xy 10.858493 -29.310882) (xy 10.785607 -29.265753) (xy 10.717196 -29.214092) (xy 10.653844 -29.156338)
			(xy 10.59609 -29.092986) (xy 10.544429 -29.024575) (xy 10.4993 -28.951689) (xy 10.461089 -28.87495)
			(xy 10.430121 -28.795013) (xy 10.406661 -28.71256) (xy 10.390909 -28.628293) (xy 10.382999 -28.542933)
			(xy 6.711979 -28.542933) (xy 6.734169 -28.666399) (xy 6.750004 -28.799346) (xy 6.757936 -28.932998)
			(xy 6.758432 -28.999942) (xy 6.758432 -31.542927) (xy 10.382999 -31.542927) (xy 10.382999 -31.457201)
			(xy 10.390909 -31.371841) (xy 10.406661 -31.287574) (xy 10.430121 -31.205121) (xy 10.461089 -31.125184)
			(xy 10.4993 -31.048445) (xy 10.544429 -30.975559) (xy 10.59609 -30.907148) (xy 10.653844 -30.843796)
			(xy 10.717196 -30.786042) (xy 10.785607 -30.734381) (xy 10.858493 -30.689252) (xy 10.935232 -30.651041)
			(xy 11.015169 -30.620073) (xy 11.097622 -30.596613) (xy 11.181889 -30.580861) (xy 11.267249 -30.572951)
			(xy 11.352975 -30.572951) (xy 11.438335 -30.580861) (xy 11.522602 -30.596613) (xy 11.605055 -30.620073)
			(xy 11.684992 -30.651041) (xy 11.761731 -30.689252) (xy 11.834617 -30.734381) (xy 11.903028 -30.786042)
			(xy 11.96638 -30.843796) (xy 12.024134 -30.907148) (xy 12.075795 -30.975559) (xy 12.120924 -31.048445)
			(xy 12.159135 -31.125184) (xy 12.190103 -31.205121) (xy 12.213563 -31.287574) (xy 12.229315 -31.371841)
			(xy 12.237225 -31.457201) (xy 12.23772 -31.500064) (xy 12.237225 -31.542927) (xy 12.229315 -31.628287)
			(xy 12.213563 -31.712554) (xy 12.190103 -31.795007) (xy 12.159135 -31.874944) (xy 12.120924 -31.951683)
			(xy 12.075795 -32.024569) (xy 12.024134 -32.09298) (xy 11.96638 -32.156332) (xy 11.903028 -32.214086)
			(xy 11.834617 -32.265747) (xy 11.761731 -32.310876) (xy 11.684992 -32.349087) (xy 11.61196 -32.37738)
			(xy 24.789382 -32.37738) (xy 24.793453 -32.321758) (xy 24.805579 -32.267321) (xy 24.825502 -32.21523)
			(xy 24.852798 -32.166595) (xy 24.886884 -32.122452) (xy 24.927033 -32.083743) (xy 24.972391 -32.051292)
			(xy 25.021991 -32.025791) (xy 25.074775 -32.007784) (xy 25.129618 -31.997654) (xy 25.185352 -31.995617)
			(xy 25.240789 -32.001717) (xy 25.294746 -32.015823) (xy 25.346075 -32.037635) (xy 25.393681 -32.066689)
			(xy 25.436549 -32.102364) (xy 25.473766 -32.143901) (xy 25.504539 -32.190414) (xy 25.528211 -32.240911)
			(xy 25.544279 -32.294318) (xy 25.552399 -32.349494) (xy 25.552908 -32.37738) (xy 25.552399 -32.405266)
			(xy 25.544279 -32.460442) (xy 25.528211 -32.513849) (xy 25.504539 -32.564346) (xy 25.473766 -32.610859)
			(xy 25.436549 -32.652396) (xy 25.393681 -32.688071) (xy 25.346075 -32.717125) (xy 25.294746 -32.738937)
			(xy 25.240789 -32.753043) (xy 25.185352 -32.759143) (xy 25.129618 -32.757106) (xy 25.074775 -32.746976)
			(xy 25.021991 -32.728969) (xy 24.972391 -32.703468) (xy 24.927033 -32.671017) (xy 24.886884 -32.632308)
			(xy 24.852798 -32.588165) (xy 24.825502 -32.53953) (xy 24.805579 -32.487439) (xy 24.793453 -32.433002)
			(xy 24.789382 -32.37738) (xy 11.61196 -32.37738) (xy 11.605055 -32.380055) (xy 11.522602 -32.403515)
			(xy 11.438335 -32.419267) (xy 11.352975 -32.427177) (xy 11.267249 -32.427177) (xy 11.181889 -32.419267)
			(xy 11.097622 -32.403515) (xy 11.015169 -32.380055) (xy 10.935232 -32.349087) (xy 10.858493 -32.310876)
			(xy 10.785607 -32.265747) (xy 10.717196 -32.214086) (xy 10.653844 -32.156332) (xy 10.59609 -32.09298)
			(xy 10.544429 -32.024569) (xy 10.4993 -31.951683) (xy 10.461089 -31.874944) (xy 10.430121 -31.795007)
			(xy 10.406661 -31.712554) (xy 10.390909 -31.628287) (xy 10.382999 -31.542927) (xy 6.758432 -31.542927)
			(xy 6.758432 -32.095186) (xy 6.758892 -32.125384) (xy 6.766295 -32.185325) (xy 6.78099 -32.243907)
			(xy 6.802755 -32.300245) (xy 6.816598 -32.327088) (xy 6.829347 -32.350132) (xy 6.859048 -32.393624)
			(xy 6.893216 -32.433703) (xy 6.912102 -32.452056) (xy 6.972831 -32.510233) (xy 7.0893 -32.631578)
			(xy 7.19982 -32.758364) (xy 7.304137 -32.890302) (xy 7.402011 -33.027087) (xy 7.448042 -33.09747)
			(xy 7.493233 -33.16843) (xy 7.57758 -33.314013) (xy 7.654853 -33.463473) (xy 7.724872 -33.616464)
			(xy 7.787478 -33.772636) (xy 7.842527 -33.931628) (xy 7.889891 -34.093077) (xy 7.929462 -34.256611)
			(xy 7.961149 -34.421853) (xy 7.978397 -34.542921) (xy 10.382999 -34.542921) (xy 10.382999 -34.457195)
			(xy 10.390909 -34.371835) (xy 10.406661 -34.287568) (xy 10.430121 -34.205115) (xy 10.461089 -34.125178)
			(xy 10.4993 -34.048439) (xy 10.544429 -33.975553) (xy 10.59609 -33.907142) (xy 10.653844 -33.84379)
			(xy 10.717196 -33.786036) (xy 10.785607 -33.734375) (xy 10.858493 -33.689246) (xy 10.935232 -33.651035)
			(xy 11.015169 -33.620067) (xy 11.097622 -33.596607) (xy 11.181889 -33.580855) (xy 11.267249 -33.572945)
			(xy 11.352975 -33.572945) (xy 11.438335 -33.580855) (xy 11.522602 -33.596607) (xy 11.605055 -33.620067)
			(xy 11.684992 -33.651035) (xy 11.761731 -33.689246) (xy 11.834617 -33.734375) (xy 11.903028 -33.786036)
			(xy 11.96638 -33.84379) (xy 12.024134 -33.907142) (xy 12.075795 -33.975553) (xy 12.120924 -34.048439)
			(xy 12.159135 -34.125178) (xy 12.190103 -34.205115) (xy 12.213563 -34.287568) (xy 12.229315 -34.371835)
			(xy 12.237225 -34.457195) (xy 12.23772 -34.500058) (xy 12.237225 -34.542921) (xy 12.229315 -34.628281)
			(xy 12.213563 -34.712548) (xy 12.190103 -34.795001) (xy 12.159421 -34.8742) (xy 27.278582 -34.8742)
			(xy 27.282653 -34.818578) (xy 27.294779 -34.764141) (xy 27.314702 -34.71205) (xy 27.341998 -34.663415)
			(xy 27.376084 -34.619272) (xy 27.416233 -34.580563) (xy 27.461591 -34.548112) (xy 27.511191 -34.522611)
			(xy 27.563975 -34.504604) (xy 27.618818 -34.494474) (xy 27.674552 -34.492437) (xy 27.729989 -34.498537)
			(xy 27.783946 -34.512643) (xy 27.835275 -34.534455) (xy 27.882881 -34.563509) (xy 27.925749 -34.599184)
			(xy 27.962966 -34.640721) (xy 27.993739 -34.687234) (xy 28.017411 -34.737731) (xy 28.033479 -34.791138)
			(xy 28.041599 -34.846314) (xy 28.042108 -34.8742) (xy 28.041599 -34.902086) (xy 28.033479 -34.957262)
			(xy 28.017411 -35.010669) (xy 27.993739 -35.061166) (xy 27.962966 -35.107679) (xy 27.925749 -35.149216)
			(xy 27.882881 -35.184891) (xy 27.835275 -35.213945) (xy 27.783946 -35.235757) (xy 27.729989 -35.249863)
			(xy 27.674552 -35.255963) (xy 27.618818 -35.253926) (xy 27.563975 -35.243796) (xy 27.511191 -35.225789)
			(xy 27.461591 -35.200288) (xy 27.416233 -35.167837) (xy 27.376084 -35.129128) (xy 27.341998 -35.084985)
			(xy 27.314702 -35.03635) (xy 27.294779 -34.984259) (xy 27.282653 -34.929822) (xy 27.278582 -34.8742)
			(xy 12.159421 -34.8742) (xy 12.159135 -34.874938) (xy 12.120924 -34.951677) (xy 12.075795 -35.024563)
			(xy 12.024134 -35.092974) (xy 11.96638 -35.156326) (xy 11.903028 -35.21408) (xy 11.834617 -35.265741)
			(xy 11.761731 -35.31087) (xy 11.684992 -35.349081) (xy 11.605055 -35.380049) (xy 11.522602 -35.403509)
			(xy 11.438335 -35.419261) (xy 11.352975 -35.427171) (xy 11.267249 -35.427171) (xy 11.181889 -35.419261)
			(xy 11.097622 -35.403509) (xy 11.015169 -35.380049) (xy 10.935232 -35.349081) (xy 10.858493 -35.31087)
			(xy 10.785607 -35.265741) (xy 10.717196 -35.21408) (xy 10.653844 -35.156326) (xy 10.59609 -35.092974)
			(xy 10.544429 -35.024563) (xy 10.4993 -34.951677) (xy 10.461089 -34.874938) (xy 10.430121 -34.795001)
			(xy 10.406661 -34.712548) (xy 10.390909 -34.628281) (xy 10.382999 -34.542921) (xy 7.978397 -34.542921)
			(xy 7.984879 -34.588424) (xy 8.000598 -34.755941) (xy 8.008269 -34.924019) (xy 8.007876 -35.092272)
			(xy 7.999417 -35.260312) (xy 7.982914 -35.427754) (xy 7.958404 -35.594212) (xy 7.925944 -35.759304)
			(xy 7.885607 -35.922651) (xy 7.837488 -36.083876) (xy 7.781696 -36.242609) (xy 7.718359 -36.398486)
			(xy 7.647624 -36.551148) (xy 7.569652 -36.700243) (xy 7.484624 -36.84543) (xy 7.392734 -36.986375)
			(xy 7.294194 -37.122753) (xy 7.189231 -37.254251) (xy 7.078085 -37.380567) (xy 6.962328 -37.500052)
			(xy 9.403341 -37.500052) (xy 9.407346 -37.412144) (xy 9.419329 -37.324964) (xy 9.439189 -37.239235)
			(xy 9.466764 -37.155667) (xy 9.501823 -37.074953) (xy 9.544076 -36.997761) (xy 9.593174 -36.924732)
			(xy 9.64871 -36.85647) (xy 9.710222 -36.79354) (xy 9.777203 -36.736466) (xy 9.849096 -36.685718)
			(xy 9.925305 -36.641718) (xy 10.0052 -36.604831) (xy 10.088119 -36.575362) (xy 10.173374 -36.553555)
			(xy 10.260258 -36.539591) (xy 10.348052 -36.533585) (xy 10.436029 -36.535589) (xy 10.523459 -36.545584)
			(xy 10.609618 -36.563488) (xy 10.693792 -36.589152) (xy 10.775283 -36.622365) (xy 10.853417 -36.662851)
			(xy 10.927545 -36.710273) (xy 10.964108 -36.738661) (xy 23.469592 -36.738661) (xy 23.469592 -36.667339)
			(xy 23.477578 -36.596465) (xy 23.493448 -36.52693) (xy 23.517005 -36.45961) (xy 23.54795 -36.395351)
			(xy 23.585896 -36.33496) (xy 23.630365 -36.279198) (xy 23.680798 -36.228765) (xy 23.73656 -36.184296)
			(xy 23.796951 -36.14635) (xy 23.86121 -36.115405) (xy 23.92853 -36.091848) (xy 23.998065 -36.075978)
			(xy 24.068939 -36.067992) (xy 24.140261 -36.067992) (xy 24.211135 -36.075978) (xy 24.221138 -36.078261)
			(xy 25.272992 -36.078261) (xy 25.272992 -36.006939) (xy 25.280978 -35.936065) (xy 25.296848 -35.86653)
			(xy 25.320405 -35.79921) (xy 25.35135 -35.734951) (xy 25.389296 -35.67456) (xy 25.433765 -35.618798)
			(xy 25.484198 -35.568365) (xy 25.53996 -35.523896) (xy 25.600351 -35.48595) (xy 25.66461 -35.455005)
			(xy 25.73193 -35.431448) (xy 25.801465 -35.415578) (xy 25.872339 -35.407592) (xy 25.943661 -35.407592)
			(xy 26.014535 -35.415578) (xy 26.08407 -35.431448) (xy 26.15139 -35.455005) (xy 26.215649 -35.48595)
			(xy 26.27604 -35.523896) (xy 26.331802 -35.568365) (xy 26.382235 -35.618798) (xy 26.426704 -35.67456)
			(xy 26.46465 -35.734951) (xy 26.495595 -35.79921) (xy 26.519152 -35.86653) (xy 26.535022 -35.936065)
			(xy 26.543008 -36.006939) (xy 26.543508 -36.0426) (xy 26.543008 -36.078261) (xy 26.535022 -36.149135)
			(xy 26.519152 -36.21867) (xy 26.495595 -36.28599) (xy 26.475961 -36.326761) (xy 26.948648 -36.326761)
			(xy 26.955006 -36.255132) (xy 26.969409 -36.184679) (xy 26.991672 -36.116302) (xy 27.02151 -36.050874)
			(xy 27.058543 -35.989233) (xy 27.102296 -35.932165) (xy 27.152212 -35.880401) (xy 27.207651 -35.834602)
			(xy 27.267905 -35.795352) (xy 27.332204 -35.763155) (xy 27.399727 -35.738421) (xy 27.46961 -35.721466)
			(xy 27.54096 -35.712508) (xy 27.612865 -35.71166) (xy 27.684407 -35.718933) (xy 27.75467 -35.734236)
			(xy 27.822757 -35.757371) (xy 27.887798 -35.788043) (xy 27.948961 -35.825861) (xy 28.005464 -35.870341)
			(xy 28.056586 -35.920914) (xy 28.101673 -35.976934) (xy 28.140149 -36.037685) (xy 28.171522 -36.102391)
			(xy 28.195391 -36.170224) (xy 28.203906 -36.20516) (xy 28.209345 -36.227009) (xy 28.227009 -36.268425)
			(xy 28.251691 -36.306082) (xy 28.282619 -36.338803) (xy 28.318827 -36.365566) (xy 28.359182 -36.385534)
			(xy 28.402423 -36.398083) (xy 28.447198 -36.402821) (xy 28.492108 -36.399599) (xy 28.535748 -36.388517)
			(xy 28.576754 -36.369924) (xy 28.595574 -36.35756) (xy 28.625502 -36.337625) (xy 28.688957 -36.303794)
			(xy 28.755825 -36.277341) (xy 28.825252 -36.258605) (xy 28.896349 -36.247826) (xy 28.968209 -36.24514)
			(xy 29.039913 -36.250582) (xy 29.110545 -36.264083) (xy 29.179201 -36.285469) (xy 29.245005 -36.314469)
			(xy 29.307115 -36.35071) (xy 29.364737 -36.393731) (xy 29.380409 -36.408461) (xy 29.819592 -36.408461)
			(xy 29.819592 -36.337139) (xy 29.827578 -36.266265) (xy 29.843448 -36.19673) (xy 29.867005 -36.12941)
			(xy 29.89795 -36.065151) (xy 29.935896 -36.00476) (xy 29.980365 -35.948998) (xy 30.030798 -35.898565)
			(xy 30.08656 -35.854096) (xy 30.146951 -35.81615) (xy 30.21121 -35.785205) (xy 30.27853 -35.761648)
			(xy 30.348065 -35.745778) (xy 30.418939 -35.737792) (xy 30.490261 -35.737792) (xy 30.561135 -35.745778)
			(xy 30.63067 -35.761648) (xy 30.69799 -35.785205) (xy 30.762249 -35.81615) (xy 30.82264 -35.854096)
			(xy 30.878402 -35.898565) (xy 30.928835 -35.948998) (xy 30.973304 -36.00476) (xy 31.01125 -36.065151)
			(xy 31.042195 -36.12941) (xy 31.065752 -36.19673) (xy 31.067699 -36.205261) (xy 32.181792 -36.205261)
			(xy 32.181792 -36.133939) (xy 32.189778 -36.063065) (xy 32.205648 -35.99353) (xy 32.229205 -35.92621)
			(xy 32.26015 -35.861951) (xy 32.298096 -35.80156) (xy 32.342565 -35.745798) (xy 32.392998 -35.695365)
			(xy 32.44876 -35.650896) (xy 32.509151 -35.61295) (xy 32.57341 -35.582005) (xy 32.64073 -35.558448)
			(xy 32.710265 -35.542578) (xy 32.781139 -35.534592) (xy 32.852461 -35.534592) (xy 32.923335 -35.542578)
			(xy 32.99287 -35.558448) (xy 33.06019 -35.582005) (xy 33.088547 -35.595661) (xy 75.641192 -35.595661)
			(xy 75.641192 -35.524339) (xy 75.649178 -35.453465) (xy 75.665048 -35.38393) (xy 75.688605 -35.31661)
			(xy 75.71955 -35.252351) (xy 75.757496 -35.19196) (xy 75.801965 -35.136198) (xy 75.852398 -35.085765)
			(xy 75.90816 -35.041296) (xy 75.968551 -35.00335) (xy 76.03281 -34.972405) (xy 76.10013 -34.948848)
			(xy 76.169665 -34.932978) (xy 76.240539 -34.924992) (xy 76.311861 -34.924992) (xy 76.382735 -34.932978)
			(xy 76.45227 -34.948848) (xy 76.51959 -34.972405) (xy 76.522948 -34.974022) (xy 87.732106 -34.974022)
			(xy 87.736177 -34.9184) (xy 87.748303 -34.863963) (xy 87.768226 -34.811872) (xy 87.795522 -34.763237)
			(xy 87.829608 -34.719094) (xy 87.869757 -34.680385) (xy 87.915115 -34.647934) (xy 87.964715 -34.622433)
			(xy 88.017499 -34.604426) (xy 88.072342 -34.594296) (xy 88.128076 -34.592259) (xy 88.183513 -34.598359)
			(xy 88.23747 -34.612465) (xy 88.288799 -34.634277) (xy 88.336405 -34.663331) (xy 88.379273 -34.699006)
			(xy 88.41649 -34.740543) (xy 88.447263 -34.787056) (xy 88.470935 -34.837553) (xy 88.487003 -34.89096)
			(xy 88.495123 -34.946136) (xy 88.495632 -34.974022) (xy 88.495123 -35.001908) (xy 88.487003 -35.057084)
			(xy 88.470935 -35.110491) (xy 88.447263 -35.160988) (xy 88.41649 -35.207501) (xy 88.379273 -35.249038)
			(xy 88.336405 -35.284713) (xy 88.288799 -35.313767) (xy 88.23747 -35.335579) (xy 88.183513 -35.349685)
			(xy 88.128076 -35.355785) (xy 88.072342 -35.353748) (xy 88.017499 -35.343618) (xy 87.964715 -35.325611)
			(xy 87.915115 -35.30011) (xy 87.869757 -35.267659) (xy 87.829608 -35.22895) (xy 87.795522 -35.184807)
			(xy 87.768226 -35.136172) (xy 87.748303 -35.084081) (xy 87.736177 -35.029644) (xy 87.732106 -34.974022)
			(xy 76.522948 -34.974022) (xy 76.583849 -35.00335) (xy 76.64424 -35.041296) (xy 76.700002 -35.085765)
			(xy 76.750435 -35.136198) (xy 76.794904 -35.19196) (xy 76.83285 -35.252351) (xy 76.863795 -35.31661)
			(xy 76.887352 -35.38393) (xy 76.903222 -35.453465) (xy 76.911208 -35.524339) (xy 76.911708 -35.56)
			(xy 76.911208 -35.595661) (xy 76.903222 -35.666535) (xy 76.887352 -35.73607) (xy 76.863795 -35.80339)
			(xy 76.83285 -35.867649) (xy 76.794904 -35.92804) (xy 76.750435 -35.983802) (xy 76.700002 -36.034235)
			(xy 76.64424 -36.078704) (xy 76.583849 -36.11665) (xy 76.51959 -36.147595) (xy 76.45227 -36.171152)
			(xy 76.382735 -36.187022) (xy 76.311861 -36.195008) (xy 76.240539 -36.195008) (xy 76.169665 -36.187022)
			(xy 76.10013 -36.171152) (xy 76.03281 -36.147595) (xy 75.968551 -36.11665) (xy 75.90816 -36.078704)
			(xy 75.852398 -36.034235) (xy 75.801965 -35.983802) (xy 75.757496 -35.92804) (xy 75.71955 -35.867649)
			(xy 75.688605 -35.80339) (xy 75.665048 -35.73607) (xy 75.649178 -35.666535) (xy 75.641192 -35.595661)
			(xy 33.088547 -35.595661) (xy 33.124449 -35.61295) (xy 33.18484 -35.650896) (xy 33.240602 -35.695365)
			(xy 33.291035 -35.745798) (xy 33.335504 -35.80156) (xy 33.37345 -35.861951) (xy 33.404395 -35.92621)
			(xy 33.427952 -35.99353) (xy 33.443822 -36.063065) (xy 33.451808 -36.133939) (xy 33.452308 -36.1696)
			(xy 33.451808 -36.205261) (xy 33.443822 -36.276135) (xy 33.427952 -36.34567) (xy 33.404395 -36.41299)
			(xy 33.37345 -36.477249) (xy 33.335504 -36.53764) (xy 33.291035 -36.593402) (xy 33.240602 -36.643835)
			(xy 33.18484 -36.688304) (xy 33.124449 -36.72625) (xy 33.06019 -36.757195) (xy 32.99287 -36.780752)
			(xy 32.923335 -36.796622) (xy 32.852461 -36.804608) (xy 32.781139 -36.804608) (xy 32.710265 -36.796622)
			(xy 32.64073 -36.780752) (xy 32.57341 -36.757195) (xy 32.509151 -36.72625) (xy 32.44876 -36.688304)
			(xy 32.392998 -36.643835) (xy 32.342565 -36.593402) (xy 32.298096 -36.53764) (xy 32.26015 -36.477249)
			(xy 32.229205 -36.41299) (xy 32.205648 -36.34567) (xy 32.189778 -36.276135) (xy 32.181792 -36.205261)
			(xy 31.067699 -36.205261) (xy 31.081622 -36.266265) (xy 31.089608 -36.337139) (xy 31.090108 -36.3728)
			(xy 31.089608 -36.408461) (xy 31.081622 -36.479335) (xy 31.065752 -36.54887) (xy 31.042195 -36.61619)
			(xy 31.01125 -36.680449) (xy 30.973304 -36.74084) (xy 30.928835 -36.796602) (xy 30.878402 -36.847035)
			(xy 30.82264 -36.891504) (xy 30.782921 -36.916461) (xy 67.360792 -36.916461) (xy 67.360792 -36.845139)
			(xy 67.368778 -36.774265) (xy 67.384648 -36.70473) (xy 67.408205 -36.63741) (xy 67.43915 -36.573151)
			(xy 67.477096 -36.51276) (xy 67.521565 -36.456998) (xy 67.571998 -36.406565) (xy 67.62776 -36.362096)
			(xy 67.688151 -36.32415) (xy 67.75241 -36.293205) (xy 67.81973 -36.269648) (xy 67.889265 -36.253778)
			(xy 67.960139 -36.245792) (xy 68.031461 -36.245792) (xy 68.102335 -36.253778) (xy 68.17187 -36.269648)
			(xy 68.23919 -36.293205) (xy 68.303449 -36.32415) (xy 68.36384 -36.362096) (xy 68.419602 -36.406565)
			(xy 68.470035 -36.456998) (xy 68.514297 -36.5125) (xy 87.844882 -36.5125) (xy 87.848953 -36.456878)
			(xy 87.861079 -36.402441) (xy 87.881002 -36.35035) (xy 87.908298 -36.301715) (xy 87.942384 -36.257572)
			(xy 87.982533 -36.218863) (xy 88.027891 -36.186412) (xy 88.077491 -36.160911) (xy 88.130275 -36.142904)
			(xy 88.185118 -36.132774) (xy 88.240852 -36.130737) (xy 88.296289 -36.136837) (xy 88.350246 -36.150943)
			(xy 88.401575 -36.172755) (xy 88.449181 -36.201809) (xy 88.492049 -36.237484) (xy 88.529266 -36.279021)
			(xy 88.560039 -36.325534) (xy 88.583711 -36.376031) (xy 88.599779 -36.429438) (xy 88.607899 -36.484614)
			(xy 88.608408 -36.5125) (xy 88.607899 -36.540386) (xy 88.599779 -36.595562) (xy 88.583711 -36.648969)
			(xy 88.560039 -36.699466) (xy 88.529266 -36.745979) (xy 88.492049 -36.787516) (xy 88.449181 -36.823191)
			(xy 88.401575 -36.852245) (xy 88.350246 -36.874057) (xy 88.296289 -36.888163) (xy 88.240852 -36.894263)
			(xy 88.185118 -36.892226) (xy 88.130275 -36.882096) (xy 88.077491 -36.864089) (xy 88.027891 -36.838588)
			(xy 87.982533 -36.806137) (xy 87.942384 -36.767428) (xy 87.908298 -36.723285) (xy 87.881002 -36.67465)
			(xy 87.861079 -36.622559) (xy 87.848953 -36.568122) (xy 87.844882 -36.5125) (xy 68.514297 -36.5125)
			(xy 68.514504 -36.51276) (xy 68.55245 -36.573151) (xy 68.583395 -36.63741) (xy 68.606952 -36.70473)
			(xy 68.622822 -36.774265) (xy 68.630808 -36.845139) (xy 68.631308 -36.8808) (xy 68.630808 -36.916461)
			(xy 68.622822 -36.987335) (xy 68.606952 -37.05687) (xy 68.583395 -37.12419) (xy 68.55245 -37.188449)
			(xy 68.514504 -37.24884) (xy 68.470035 -37.304602) (xy 68.419602 -37.355035) (xy 68.36384 -37.399504)
			(xy 68.303449 -37.43745) (xy 68.23919 -37.468395) (xy 68.17187 -37.491952) (xy 68.102335 -37.507822)
			(xy 68.031461 -37.515808) (xy 67.960139 -37.515808) (xy 67.889265 -37.507822) (xy 67.81973 -37.491952)
			(xy 67.75241 -37.468395) (xy 67.688151 -37.43745) (xy 67.62776 -37.399504) (xy 67.571998 -37.355035)
			(xy 67.521565 -37.304602) (xy 67.477096 -37.24884) (xy 67.43915 -37.188449) (xy 67.408205 -37.12419)
			(xy 67.384648 -37.05687) (xy 67.368778 -36.987335) (xy 67.360792 -36.916461) (xy 30.782921 -36.916461)
			(xy 30.762249 -36.92945) (xy 30.69799 -36.960395) (xy 30.63067 -36.983952) (xy 30.561135 -36.999822)
			(xy 30.490261 -37.007808) (xy 30.418939 -37.007808) (xy 30.348065 -36.999822) (xy 30.27853 -36.983952)
			(xy 30.21121 -36.960395) (xy 30.146951 -36.92945) (xy 30.08656 -36.891504) (xy 30.030798 -36.847035)
			(xy 29.980365 -36.796602) (xy 29.935896 -36.74084) (xy 29.89795 -36.680449) (xy 29.867005 -36.61619)
			(xy 29.843448 -36.54887) (xy 29.827578 -36.479335) (xy 29.819592 -36.408461) (xy 29.380409 -36.408461)
			(xy 29.417135 -36.44298) (xy 29.46364 -36.497829) (xy 29.503656 -36.557577) (xy 29.536673 -36.621459)
			(xy 29.562269 -36.68866) (xy 29.580115 -36.758321) (xy 29.589985 -36.82955) (xy 29.591752 -36.901439)
			(xy 29.585394 -36.973068) (xy 29.570991 -37.043521) (xy 29.548728 -37.111898) (xy 29.51889 -37.177326)
			(xy 29.481857 -37.238967) (xy 29.438104 -37.296035) (xy 29.388188 -37.347799) (xy 29.332749 -37.393598)
			(xy 29.272495 -37.432848) (xy 29.208196 -37.465045) (xy 29.140673 -37.489779) (xy 29.07079 -37.506734)
			(xy 28.99944 -37.515692) (xy 28.927535 -37.51654) (xy 28.855993 -37.509267) (xy 28.78573 -37.493964)
			(xy 28.717643 -37.470829) (xy 28.652602 -37.440157) (xy 28.591439 -37.402339) (xy 28.534936 -37.357859)
			(xy 28.483814 -37.307286) (xy 28.438727 -37.251266) (xy 28.400251 -37.190515) (xy 28.368878 -37.125809)
			(xy 28.345009 -37.057976) (xy 28.336494 -37.02304) (xy 28.331055 -37.001191) (xy 28.313391 -36.959775)
			(xy 28.288709 -36.922118) (xy 28.257781 -36.889397) (xy 28.221573 -36.862634) (xy 28.181218 -36.842666)
			(xy 28.137977 -36.830117) (xy 28.093202 -36.825379) (xy 28.048292 -36.828601) (xy 28.004652 -36.839683)
			(xy 27.963646 -36.858276) (xy 27.944826 -36.87064) (xy 27.914898 -36.890575) (xy 27.851443 -36.924406)
			(xy 27.784575 -36.950859) (xy 27.715148 -36.969595) (xy 27.644051 -36.980374) (xy 27.572191 -36.98306)
			(xy 27.500487 -36.977618) (xy 27.429855 -36.964117) (xy 27.361199 -36.942731) (xy 27.295395 -36.913731)
			(xy 27.233285 -36.87749) (xy 27.175663 -36.834469) (xy 27.123265 -36.78522) (xy 27.07676 -36.730371)
			(xy 27.036744 -36.670623) (xy 27.003727 -36.606741) (xy 26.978131 -36.53954) (xy 26.960285 -36.469879)
			(xy 26.950415 -36.39865) (xy 26.948648 -36.326761) (xy 26.475961 -36.326761) (xy 26.46465 -36.350249)
			(xy 26.426704 -36.41064) (xy 26.382235 -36.466402) (xy 26.331802 -36.516835) (xy 26.27604 -36.561304)
			(xy 26.215649 -36.59925) (xy 26.15139 -36.630195) (xy 26.08407 -36.653752) (xy 26.014535 -36.669622)
			(xy 25.943661 -36.677608) (xy 25.872339 -36.677608) (xy 25.801465 -36.669622) (xy 25.73193 -36.653752)
			(xy 25.66461 -36.630195) (xy 25.600351 -36.59925) (xy 25.53996 -36.561304) (xy 25.484198 -36.516835)
			(xy 25.433765 -36.466402) (xy 25.389296 -36.41064) (xy 25.35135 -36.350249) (xy 25.320405 -36.28599)
			(xy 25.296848 -36.21867) (xy 25.280978 -36.149135) (xy 25.272992 -36.078261) (xy 24.221138 -36.078261)
			(xy 24.28067 -36.091848) (xy 24.34799 -36.115405) (xy 24.412249 -36.14635) (xy 24.47264 -36.184296)
			(xy 24.528402 -36.228765) (xy 24.578835 -36.279198) (xy 24.623304 -36.33496) (xy 24.66125 -36.395351)
			(xy 24.692195 -36.45961) (xy 24.715752 -36.52693) (xy 24.731622 -36.596465) (xy 24.739608 -36.667339)
			(xy 24.740108 -36.703) (xy 24.739608 -36.738661) (xy 24.731622 -36.809535) (xy 24.715752 -36.87907)
			(xy 24.692195 -36.94639) (xy 24.66125 -37.010649) (xy 24.623304 -37.07104) (xy 24.578835 -37.126802)
			(xy 24.528402 -37.177235) (xy 24.47264 -37.221704) (xy 24.412249 -37.25965) (xy 24.34799 -37.290595)
			(xy 24.28067 -37.314152) (xy 24.211135 -37.330022) (xy 24.140261 -37.338008) (xy 24.068939 -37.338008)
			(xy 23.998065 -37.330022) (xy 23.92853 -37.314152) (xy 23.86121 -37.290595) (xy 23.796951 -37.25965)
			(xy 23.73656 -37.221704) (xy 23.680798 -37.177235) (xy 23.630365 -37.126802) (xy 23.585896 -37.07104)
			(xy 23.54795 -37.010649) (xy 23.517005 -36.94639) (xy 23.493448 -36.87907) (xy 23.477578 -36.809535)
			(xy 23.469592 -36.738661) (xy 10.964108 -36.738661) (xy 10.997053 -36.76424) (xy 11.061367 -36.824305)
			(xy 11.119951 -36.889969) (xy 11.172322 -36.960688) (xy 11.218045 -37.035876) (xy 11.256742 -37.114911)
			(xy 11.288091 -37.197137) (xy 11.311833 -37.281873) (xy 11.327771 -37.368417) (xy 11.335773 -37.456052)
			(xy 11.336274 -37.500052) (xy 11.335773 -37.544052) (xy 11.327771 -37.631687) (xy 11.311833 -37.718231)
			(xy 11.288091 -37.802967) (xy 11.256742 -37.885193) (xy 11.218045 -37.964228) (xy 11.172322 -38.039416)
			(xy 11.119951 -38.110135) (xy 11.061916 -38.175184) (xy 21.970541 -38.175184) (xy 21.971759 -38.10453)
			(xy 21.980808 -38.034448) (xy 21.997577 -37.965802) (xy 22.021858 -37.899441) (xy 22.053352 -37.836184)
			(xy 22.091671 -37.776811) (xy 22.136339 -37.722056) (xy 22.186807 -37.672595) (xy 22.242451 -37.629038)
			(xy 22.302584 -37.591925) (xy 22.366464 -37.561712) (xy 22.433301 -37.538772) (xy 22.50227 -37.52339)
			(xy 22.57252 -37.515755) (xy 22.643184 -37.515961) (xy 22.713389 -37.524006) (xy 22.782267 -37.53979)
			(xy 22.848969 -37.563119) (xy 22.912671 -37.593704) (xy 22.972587 -37.631168) (xy 23.027976 -37.675049)
			(xy 23.078154 -37.724803) (xy 23.122503 -37.779818) (xy 23.138229 -37.8045) (xy 24.510237 -37.8045)
			(xy 24.516013 -37.733674) (xy 24.529654 -37.663935) (xy 24.55099 -37.596154) (xy 24.579755 -37.531175)
			(xy 24.61559 -37.469812) (xy 24.658046 -37.412829) (xy 24.706595 -37.360938) (xy 24.76063 -37.314788)
			(xy 24.819475 -37.274953) (xy 24.882398 -37.241933) (xy 24.948611 -37.216138) (xy 25.017289 -37.197891)
			(xy 25.087574 -37.18742) (xy 25.158589 -37.184855) (xy 25.229446 -37.190228) (xy 25.299261 -37.203473)
			(xy 25.367163 -37.224424) (xy 25.432303 -37.25282) (xy 25.49387 -37.288305) (xy 25.551093 -37.330437)
			(xy 25.603258 -37.37869) (xy 25.649715 -37.432462) (xy 25.689883 -37.491081) (xy 25.723261 -37.553815)
			(xy 25.736804 -37.586666) (xy 25.745214 -37.606826) (xy 25.767981 -37.644104) (xy 25.796787 -37.676939)
			(xy 25.830783 -37.704366) (xy 25.868968 -37.725575) (xy 25.910217 -37.739943) (xy 25.953316 -37.747046)
			(xy 25.996995 -37.746675) (xy 26.039966 -37.73884) (xy 26.080966 -37.723774) (xy 26.118785 -37.701918)
			(xy 26.135838 -37.688266) (xy 26.163402 -37.665842) (xy 26.222697 -37.626679) (xy 26.28599 -37.594375)
			(xy 26.352493 -37.569334) (xy 26.421373 -37.551869) (xy 26.491773 -37.542197) (xy 26.562811 -37.540439)
			(xy 26.633603 -37.546617) (xy 26.703263 -37.560654) (xy 26.770923 -37.582375) (xy 26.835737 -37.611509)
			(xy 26.896896 -37.647692) (xy 26.953636 -37.690471) (xy 27.00525 -37.739314) (xy 27.051093 -37.79361)
			(xy 27.090593 -37.852681) (xy 27.123255 -37.91579) (xy 27.148674 -37.982149) (xy 27.16653 -38.050929)
			(xy 27.176602 -38.121273) (xy 27.178763 -38.1923) (xy 27.172987 -38.263126) (xy 27.159346 -38.332865)
			(xy 27.13801 -38.400646) (xy 27.109245 -38.465625) (xy 27.07341 -38.526988) (xy 27.030954 -38.583971)
			(xy 27.022637 -38.592861) (xy 27.762192 -38.592861) (xy 27.762192 -38.521539) (xy 27.770178 -38.450665)
			(xy 27.786048 -38.38113) (xy 27.809605 -38.31381) (xy 27.84055 -38.249551) (xy 27.878496 -38.18916)
			(xy 27.922965 -38.133398) (xy 27.973398 -38.082965) (xy 28.02916 -38.038496) (xy 28.089551 -38.00055)
			(xy 28.15381 -37.969605) (xy 28.22113 -37.946048) (xy 28.290665 -37.930178) (xy 28.361539 -37.922192)
			(xy 28.432861 -37.922192) (xy 28.503735 -37.930178) (xy 28.57327 -37.946048) (xy 28.64059 -37.969605)
			(xy 28.704849 -38.00055) (xy 28.76524 -38.038496) (xy 28.821002 -38.082965) (xy 28.871435 -38.133398)
			(xy 28.915904 -38.18916) (xy 28.95385 -38.249551) (xy 28.984795 -38.31381) (xy 29.008352 -38.38113)
			(xy 29.024222 -38.450665) (xy 29.032208 -38.521539) (xy 29.032708 -38.5572) (xy 29.032208 -38.592861)
			(xy 29.024222 -38.663735) (xy 29.008352 -38.73327) (xy 28.984795 -38.80059) (xy 28.95385 -38.864849)
			(xy 28.915904 -38.92524) (xy 28.871435 -38.981002) (xy 28.821002 -39.031435) (xy 28.76524 -39.075904)
			(xy 28.704849 -39.11385) (xy 28.64059 -39.144795) (xy 28.57327 -39.168352) (xy 28.503735 -39.184222)
			(xy 28.432861 -39.192208) (xy 28.361539 -39.192208) (xy 28.290665 -39.184222) (xy 28.22113 -39.168352)
			(xy 28.15381 -39.144795) (xy 28.089551 -39.11385) (xy 28.02916 -39.075904) (xy 27.973398 -39.031435)
			(xy 27.922965 -38.981002) (xy 27.878496 -38.92524) (xy 27.84055 -38.864849) (xy 27.809605 -38.80059)
			(xy 27.786048 -38.73327) (xy 27.770178 -38.663735) (xy 27.762192 -38.592861) (xy 27.022637 -38.592861)
			(xy 26.982405 -38.635862) (xy 26.92837 -38.682012) (xy 26.869525 -38.721847) (xy 26.806602 -38.754867)
			(xy 26.740389 -38.780662) (xy 26.671711 -38.798909) (xy 26.601426 -38.80938) (xy 26.530411 -38.811945)
			(xy 26.459554 -38.806572) (xy 26.389739 -38.793327) (xy 26.321837 -38.772376) (xy 26.256697 -38.74398)
			(xy 26.19513 -38.708495) (xy 26.137907 -38.666363) (xy 26.085742 -38.61811) (xy 26.039285 -38.564338)
			(xy 25.999117 -38.505719) (xy 25.965739 -38.442985) (xy 25.952196 -38.410134) (xy 25.943786 -38.389974)
			(xy 25.921019 -38.352696) (xy 25.892213 -38.319861) (xy 25.858217 -38.292434) (xy 25.820032 -38.271225)
			(xy 25.778783 -38.256857) (xy 25.735684 -38.249754) (xy 25.692005 -38.250125) (xy 25.649034 -38.25796)
			(xy 25.608034 -38.273026) (xy 25.570215 -38.294882) (xy 25.553162 -38.308534) (xy 25.525598 -38.330958)
			(xy 25.466303 -38.370121) (xy 25.40301 -38.402425) (xy 25.336507 -38.427466) (xy 25.267627 -38.444931)
			(xy 25.197227 -38.454603) (xy 25.126189 -38.456361) (xy 25.055397 -38.450183) (xy 24.985737 -38.436146)
			(xy 24.918077 -38.414425) (xy 24.853263 -38.385291) (xy 24.792104 -38.349108) (xy 24.735364 -38.306329)
			(xy 24.68375 -38.257486) (xy 24.637907 -38.20319) (xy 24.598407 -38.144119) (xy 24.565745 -38.08101)
			(xy 24.540326 -38.014651) (xy 24.52247 -37.945871) (xy 24.512398 -37.875527) (xy 24.510237 -37.8045)
			(xy 23.138229 -37.8045) (xy 23.160474 -37.839413) (xy 23.191598 -37.902854) (xy 23.215492 -37.969355)
			(xy 23.23186 -38.038098) (xy 23.2405 -38.108231) (xy 23.241306 -38.178891) (xy 23.234267 -38.249203)
			(xy 23.219471 -38.318301) (xy 23.208742 -38.351968) (xy 23.202016 -38.373751) (xy 23.19553 -38.41887)
			(xy 23.197192 -38.464424) (xy 23.206949 -38.50895) (xy 23.22449 -38.551024) (xy 23.249251 -38.589296)
			(xy 23.280439 -38.62254) (xy 23.317054 -38.64969) (xy 23.357924 -38.669877) (xy 23.401739 -38.682453)
			(xy 23.447093 -38.687016) (xy 23.469854 -38.685724) (xy 23.505868 -38.683357) (xy 23.578003 -38.685805)
			(xy 23.649395 -38.69641) (xy 23.719127 -38.715035) (xy 23.786299 -38.741441) (xy 23.850047 -38.775288)
			(xy 23.90955 -38.816139) (xy 23.964041 -38.863469) (xy 24.012819 -38.916669) (xy 24.055255 -38.975052)
			(xy 24.090803 -39.037867) (xy 24.119005 -39.104305) (xy 24.139498 -39.173511) (xy 24.146256 -39.208964)
			(xy 24.15074 -39.23148) (xy 24.166744 -39.274508) (xy 24.190214 -39.313962) (xy 24.220387 -39.34856)
			(xy 24.256283 -39.377177) (xy 24.296734 -39.398883) (xy 24.340426 -39.412972) (xy 24.385937 -39.418986)
			(xy 24.431789 -39.41673) (xy 24.47649 -39.406276) (xy 24.518587 -39.387965) (xy 24.537924 -39.375588)
			(xy 24.567615 -39.356235) (xy 24.630499 -39.323539) (xy 24.69663 -39.298042) (xy 24.765188 -39.280063)
			(xy 24.83532 -39.269823) (xy 24.906157 -39.26745) (xy 24.976818 -39.272973) (xy 25.046425 -39.286324)
			(xy 25.114115 -39.307338) (xy 25.179046 -39.335752) (xy 25.240412 -39.371214) (xy 25.297452 -39.413285)
			(xy 25.349456 -39.46144) (xy 25.39578 -39.515083) (xy 25.435847 -39.573548) (xy 25.46916 -39.636107)
			(xy 25.495306 -39.701984) (xy 25.513959 -39.770362) (xy 25.524889 -39.84039) (xy 25.527959 -39.9112)
			(xy 25.523131 -39.981911) (xy 25.517074 -40.015261) (xy 26.009592 -40.015261) (xy 26.009592 -39.943939)
			(xy 26.017578 -39.873065) (xy 26.033448 -39.80353) (xy 26.057005 -39.73621) (xy 26.08795 -39.671951)
			(xy 26.125896 -39.61156) (xy 26.170365 -39.555798) (xy 26.220798 -39.505365) (xy 26.27656 -39.460896)
			(xy 26.336951 -39.42295) (xy 26.40121 -39.392005) (xy 26.46853 -39.368448) (xy 26.538065 -39.352578)
			(xy 26.608939 -39.344592) (xy 26.680261 -39.344592) (xy 26.751135 -39.352578) (xy 26.82067 -39.368448)
			(xy 26.88799 -39.392005) (xy 26.952249 -39.42295) (xy 27.01264 -39.460896) (xy 27.068402 -39.505365)
			(xy 27.118835 -39.555798) (xy 27.163304 -39.61156) (xy 27.20125 -39.671951) (xy 27.232195 -39.73621)
			(xy 27.255752 -39.80353) (xy 27.271622 -39.873065) (xy 27.279608 -39.943939) (xy 27.280108 -39.9796)
			(xy 27.279608 -40.015261) (xy 27.271622 -40.086135) (xy 27.255752 -40.15567) (xy 27.232195 -40.22299)
			(xy 27.20125 -40.287249) (xy 27.163304 -40.34764) (xy 27.118835 -40.403402) (xy 27.117792 -40.404445)
			(xy 27.533417 -40.404445) (xy 27.541006 -40.333693) (xy 27.556452 -40.264231) (xy 27.579561 -40.19693)
			(xy 27.610043 -40.132631) (xy 27.647517 -40.07214) (xy 27.691513 -40.016214) (xy 27.741482 -39.965552)
			(xy 27.796797 -39.920789) (xy 27.856766 -39.882486) (xy 27.920639 -39.851121) (xy 27.987616 -39.827087)
			(xy 28.056858 -39.810686) (xy 28.127499 -39.802123) (xy 28.198654 -39.801504) (xy 28.269433 -39.808837)
			(xy 28.33895 -39.824031) (xy 28.406335 -39.846896) (xy 28.470744 -39.877145) (xy 28.53137 -39.914399)
			(xy 28.587456 -39.958193) (xy 28.638298 -40.007978) (xy 28.683261 -40.06313) (xy 28.721781 -40.122961)
			(xy 28.753377 -40.186719) (xy 28.777653 -40.253609) (xy 28.794305 -40.322791) (xy 28.803124 -40.3934)
			(xy 28.804001 -40.464553) (xy 28.796924 -40.535358) (xy 28.781982 -40.60493) (xy 28.759361 -40.672397)
			(xy 28.729346 -40.736915) (xy 28.692311 -40.797676) (xy 28.648721 -40.853919) (xy 28.624276 -40.879776)
			(xy 28.609401 -40.895856) (xy 28.584722 -40.932037) (xy 28.566613 -40.971915) (xy 28.55561 -41.014308)
			(xy 28.55204 -41.057959) (xy 28.556008 -41.101576) (xy 28.567396 -41.143866) (xy 28.585867 -41.183578)
			(xy 28.601571 -41.206156) (xy 29.362322 -41.206156) (xy 29.36264 -41.134978) (xy 29.37091 -41.064282)
			(xy 29.387028 -40.994953) (xy 29.410794 -40.92786) (xy 29.441908 -40.863842) (xy 29.479982 -40.803703)
			(xy 29.524538 -40.748196) (xy 29.575018 -40.698015) (xy 29.63079 -40.65379) (xy 29.691155 -40.616075)
			(xy 29.755356 -40.585342) (xy 29.82259 -40.561977) (xy 29.857192 -40.55364) (xy 29.879233 -40.548128)
			(xy 29.921062 -40.530408) (xy 29.959077 -40.505539) (xy 29.992069 -40.474311) (xy 30.018988 -40.437719)
			(xy 30.038978 -40.396926) (xy 30.051403 -40.353231) (xy 30.055867 -40.308024) (xy 30.052228 -40.262742)
			(xy 30.040603 -40.218828) (xy 30.031436 -40.19804) (xy 30.01719 -40.166419) (xy 29.994802 -40.100773)
			(xy 29.9797 -40.03308) (xy 29.972061 -39.964145) (xy 29.971977 -39.894787) (xy 29.979449 -39.825833)
			(xy 29.994389 -39.758104) (xy 30.016618 -39.692405) (xy 30.045871 -39.629519) (xy 30.06344 -39.599616)
			(xy 30.075212 -39.579141) (xy 30.091829 -39.534938) (xy 30.09999 -39.488426) (xy 30.099415 -39.441207)
			(xy 30.090124 -39.394907) (xy 30.072436 -39.351122) (xy 30.046961 -39.31136) (xy 30.014576 -39.276991)
			(xy 29.976398 -39.249199) (xy 29.93374 -39.228942) (xy 29.91104 -39.222426) (xy 29.877019 -39.212992)
			(xy 29.811182 -39.187486) (xy 29.748578 -39.15484) (xy 29.689978 -39.115456) (xy 29.636105 -39.069819)
			(xy 29.587622 -39.018492) (xy 29.545128 -38.962108) (xy 29.509144 -38.90136) (xy 29.480116 -38.836999)
			(xy 29.458401 -38.769816) (xy 29.444266 -38.700641) (xy 29.437886 -38.630325) (xy 29.439339 -38.559735)
			(xy 29.448608 -38.489741) (xy 29.465578 -38.421206) (xy 29.490039 -38.354974) (xy 29.521692 -38.291862)
			(xy 29.560144 -38.232647) (xy 29.604924 -38.178059) (xy 29.655478 -38.128771) (xy 29.711184 -38.08539)
			(xy 29.771354 -38.048451) (xy 29.835249 -38.018409) (xy 29.90208 -37.995635) (xy 29.971023 -37.980408)
			(xy 30.041229 -37.972917) (xy 30.111833 -37.973254) (xy 30.181965 -37.981415) (xy 30.25076 -37.997299)
			(xy 30.283086 -38.008661) (xy 31.521392 -38.008661) (xy 31.521392 -37.937339) (xy 31.529378 -37.866465)
			(xy 31.545248 -37.79693) (xy 31.568805 -37.72961) (xy 31.59975 -37.665351) (xy 31.637696 -37.60496)
			(xy 31.682165 -37.549198) (xy 31.732598 -37.498765) (xy 31.78836 -37.454296) (xy 31.848751 -37.41635)
			(xy 31.91301 -37.385405) (xy 31.98033 -37.361848) (xy 32.049865 -37.345978) (xy 32.120739 -37.337992)
			(xy 32.192061 -37.337992) (xy 32.262935 -37.345978) (xy 32.33247 -37.361848) (xy 32.39979 -37.385405)
			(xy 32.464049 -37.41635) (xy 32.52444 -37.454296) (xy 32.580202 -37.498765) (xy 32.630635 -37.549198)
			(xy 32.675104 -37.60496) (xy 32.71305 -37.665351) (xy 32.743995 -37.72961) (xy 32.767552 -37.79693)
			(xy 32.783422 -37.866465) (xy 32.791408 -37.937339) (xy 32.791908 -37.973) (xy 32.791408 -38.008661)
			(xy 32.783422 -38.079535) (xy 32.767552 -38.14907) (xy 32.743995 -38.21639) (xy 32.71305 -38.280649)
			(xy 32.675104 -38.34104) (xy 32.630635 -38.396802) (xy 32.580202 -38.447235) (xy 32.52444 -38.491704)
			(xy 32.464049 -38.52965) (xy 32.39979 -38.560595) (xy 32.33247 -38.584152) (xy 32.262935 -38.600022)
			(xy 32.192061 -38.608008) (xy 32.120739 -38.608008) (xy 32.049865 -38.600022) (xy 31.98033 -38.584152)
			(xy 31.91301 -38.560595) (xy 31.848751 -38.52965) (xy 31.78836 -38.491704) (xy 31.732598 -38.447235)
			(xy 31.682165 -38.396802) (xy 31.637696 -38.34104) (xy 31.59975 -38.280649) (xy 31.568805 -38.21639)
			(xy 31.545248 -38.14907) (xy 31.529378 -38.079535) (xy 31.521392 -38.008661) (xy 30.283086 -38.008661)
			(xy 30.31737 -38.020711) (xy 30.380975 -38.051361) (xy 30.44079 -38.088873) (xy 30.496079 -38.132784)
			(xy 30.546161 -38.182552) (xy 30.590417 -38.237565) (xy 30.628302 -38.297145) (xy 30.659351 -38.360556)
			(xy 30.683179 -38.427019) (xy 30.699494 -38.495713) (xy 30.708093 -38.565792) (xy 30.708873 -38.636392)
			(xy 30.701822 -38.706644) (xy 30.687027 -38.775681) (xy 30.664671 -38.842653) (xy 30.63503 -38.906735)
			(xy 30.61716 -38.937184) (xy 30.605388 -38.957659) (xy 30.588771 -39.001862) (xy 30.58061 -39.048374)
			(xy 30.581185 -39.095593) (xy 30.590476 -39.141893) (xy 30.608164 -39.185678) (xy 30.633639 -39.22544)
			(xy 30.666024 -39.259809) (xy 30.704202 -39.287601) (xy 30.74686 -39.307858) (xy 30.76956 -39.314374)
			(xy 30.803508 -39.323808) (xy 30.86921 -39.349267) (xy 30.931693 -39.381837) (xy 30.99019 -39.421119)
			(xy 31.043983 -39.466631) (xy 31.092411 -39.517813) (xy 31.134881 -39.574039) (xy 31.170872 -39.634616)
			(xy 31.19994 -39.698804) (xy 31.221731 -39.765812) (xy 31.235975 -39.83482) (xy 31.242499 -39.90498)
			(xy 31.241223 -39.975431) (xy 31.232161 -40.045308) (xy 31.215426 -40.113755) (xy 31.191223 -40.17993)
			(xy 31.159848 -40.243022) (xy 31.121686 -40.302256) (xy 31.077207 -40.356906) (xy 31.026956 -40.4063)
			(xy 30.97155 -40.449833) (xy 30.911668 -40.48697) (xy 30.848046 -40.517255) (xy 30.781465 -40.540318)
			(xy 30.747208 -40.54856) (xy 30.725167 -40.554072) (xy 30.683338 -40.571792) (xy 30.645323 -40.596661)
			(xy 30.612331 -40.627889) (xy 30.585412 -40.664481) (xy 30.565422 -40.705274) (xy 30.552997 -40.748969)
			(xy 30.548533 -40.794176) (xy 30.552172 -40.839458) (xy 30.563797 -40.883372) (xy 30.572964 -40.90416)
			(xy 30.587592 -40.936608) (xy 30.610357 -41.004047) (xy 30.625443 -41.073608) (xy 30.632661 -41.144419)
			(xy 30.631921 -41.215593) (xy 30.623231 -41.286239) (xy 30.606701 -41.355471) (xy 30.582537 -41.422422)
			(xy 30.551042 -41.486253) (xy 30.512612 -41.546165) (xy 30.467727 -41.601407) (xy 30.416949 -41.651287)
			(xy 30.360916 -41.695179) (xy 30.300328 -41.732535) (xy 30.235945 -41.762886) (xy 30.168574 -41.785851)
			(xy 30.099058 -41.801144) (xy 30.028268 -41.808573) (xy 29.957092 -41.808043) (xy 29.886421 -41.799563)
			(xy 29.81714 -41.783239) (xy 29.750118 -41.759274) (xy 29.686193 -41.72797) (xy 29.626167 -41.689717)
			(xy 29.570793 -41.644996) (xy 29.520762 -41.594367) (xy 29.476703 -41.538464) (xy 29.439168 -41.477988)
			(xy 29.408626 -41.413696) (xy 29.38546 -41.346393) (xy 29.369961 -41.276923) (xy 29.362322 -41.206156)
			(xy 28.601571 -41.206156) (xy 28.610875 -41.219533) (xy 28.641677 -41.250668) (xy 28.677363 -41.27606)
			(xy 28.69692 -41.285922) (xy 28.72879 -41.301748) (xy 28.789145 -41.339441) (xy 28.844912 -41.38364)
			(xy 28.895392 -41.433791) (xy 28.939954 -41.489268) (xy 28.97804 -41.549376) (xy 29.009173 -41.613362)
			(xy 29.032964 -41.680425) (xy 29.049114 -41.749726) (xy 29.057422 -41.820398) (xy 29.057783 -41.891555)
			(xy 29.050194 -41.962307) (xy 29.034748 -42.031769) (xy 29.011639 -42.09907) (xy 28.981157 -42.163369)
			(xy 28.943683 -42.22386) (xy 28.899687 -42.279786) (xy 28.849718 -42.330448) (xy 28.794403 -42.375211)
			(xy 28.734434 -42.413514) (xy 28.670561 -42.444879) (xy 28.603584 -42.468913) (xy 28.534342 -42.485314)
			(xy 28.463701 -42.493877) (xy 28.392546 -42.494496) (xy 28.321767 -42.487163) (xy 28.25225 -42.471969)
			(xy 28.184865 -42.449104) (xy 28.120456 -42.418855) (xy 28.05983 -42.381601) (xy 28.003744 -42.337807)
			(xy 27.952902 -42.288022) (xy 27.907939 -42.23287) (xy 27.869419 -42.173039) (xy 27.837823 -42.109281)
			(xy 27.813547 -42.042391) (xy 27.796895 -41.973209) (xy 27.788076 -41.9026) (xy 27.787199 -41.831447)
			(xy 27.794276 -41.760642) (xy 27.809218 -41.69107) (xy 27.831839 -41.623603) (xy 27.861854 -41.559085)
			(xy 27.898889 -41.498324) (xy 27.942479 -41.442081) (xy 27.966924 -41.416224) (xy 27.981799 -41.400144)
			(xy 28.006478 -41.363963) (xy 28.024587 -41.324085) (xy 28.03559 -41.281692) (xy 28.03916 -41.238041)
			(xy 28.035192 -41.194424) (xy 28.023804 -41.152134) (xy 28.005333 -41.112422) (xy 27.980325 -41.076467)
			(xy 27.949523 -41.045332) (xy 27.913837 -41.01994) (xy 27.89428 -41.010078) (xy 27.86241 -40.994252)
			(xy 27.802055 -40.956559) (xy 27.746288 -40.91236) (xy 27.695808 -40.862209) (xy 27.651246 -40.806732)
			(xy 27.61316 -40.746624) (xy 27.582027 -40.682638) (xy 27.558236 -40.615575) (xy 27.542086 -40.546274)
			(xy 27.533778 -40.475602) (xy 27.533417 -40.404445) (xy 27.117792 -40.404445) (xy 27.068402 -40.453835)
			(xy 27.01264 -40.498304) (xy 26.952249 -40.53625) (xy 26.88799 -40.567195) (xy 26.82067 -40.590752)
			(xy 26.751135 -40.606622) (xy 26.680261 -40.614608) (xy 26.608939 -40.614608) (xy 26.538065 -40.606622)
			(xy 26.46853 -40.590752) (xy 26.40121 -40.567195) (xy 26.336951 -40.53625) (xy 26.27656 -40.498304)
			(xy 26.220798 -40.453835) (xy 26.170365 -40.403402) (xy 26.125896 -40.34764) (xy 26.08795 -40.287249)
			(xy 26.057005 -40.22299) (xy 26.033448 -40.15567) (xy 26.017578 -40.086135) (xy 26.009592 -40.015261)
			(xy 25.517074 -40.015261) (xy 25.510465 -40.051647) (xy 25.490119 -40.11954) (xy 25.462345 -40.184748)
			(xy 25.427488 -40.24646) (xy 25.385981 -40.303911) (xy 25.338339 -40.356387) (xy 25.285155 -40.403236)
			(xy 25.227088 -40.443876) (xy 25.164859 -40.477803) (xy 25.099242 -40.504596) (xy 25.031051 -40.523921)
			(xy 24.961134 -40.535539) (xy 24.890358 -40.539306) (xy 24.819602 -40.535174) (xy 24.749746 -40.523195)
			(xy 24.681656 -40.503518) (xy 24.616178 -40.476387) (xy 24.554126 -40.442139) (xy 24.496269 -40.401199)
			(xy 24.443327 -40.354076) (xy 24.395957 -40.301355) (xy 24.354747 -40.24369) (xy 24.320209 -40.181799)
			(xy 24.292772 -40.116448) (xy 24.272777 -40.048451) (xy 24.266144 -40.013636) (xy 24.26166 -39.99112)
			(xy 24.245656 -39.948092) (xy 24.222186 -39.908638) (xy 24.192013 -39.87404) (xy 24.156117 -39.845423)
			(xy 24.115666 -39.823717) (xy 24.071974 -39.809628) (xy 24.026463 -39.803614) (xy 23.980611 -39.80587)
			(xy 23.93591 -39.816324) (xy 23.893813 -39.834635) (xy 23.874476 -39.847012) (xy 23.8444 -39.866586)
			(xy 23.780673 -39.899585) (xy 23.713635 -39.925194) (xy 23.644138 -39.94309) (xy 23.573069 -39.953042)
			(xy 23.50133 -39.954926) (xy 23.429836 -39.948717) (xy 23.359496 -39.934493) (xy 23.291206 -39.912437)
			(xy 23.225835 -39.882829) (xy 23.164216 -39.846045) (xy 23.107133 -39.802554) (xy 23.055311 -39.75291)
			(xy 23.009412 -39.697744) (xy 22.97002 -39.637759) (xy 22.937635 -39.573719) (xy 22.91267 -39.506438)
			(xy 22.895443 -39.436773) (xy 22.886173 -39.36561) (xy 22.884978 -39.293857) (xy 22.891873 -39.222426)
			(xy 22.906771 -39.152226) (xy 22.917658 -39.118032) (xy 22.924384 -39.096249) (xy 22.93087 -39.05113)
			(xy 22.929208 -39.005576) (xy 22.919451 -38.96105) (xy 22.90191 -38.918976) (xy 22.877149 -38.880704)
			(xy 22.845961 -38.84746) (xy 22.809346 -38.82031) (xy 22.768476 -38.800123) (xy 22.724661 -38.787547)
			(xy 22.679307 -38.782984) (xy 22.656546 -38.784276) (xy 22.621283 -38.786543) (xy 22.550654 -38.784314)
			(xy 22.480708 -38.774262) (xy 22.41231 -38.756512) (xy 22.346303 -38.731283) (xy 22.283503 -38.698886)
			(xy 22.224685 -38.659722) (xy 22.170575 -38.614274) (xy 22.121842 -38.563103) (xy 22.079087 -38.506841)
			(xy 22.042838 -38.446183) (xy 22.013542 -38.381877) (xy 21.991562 -38.314719) (xy 21.977169 -38.245536)
			(xy 21.970541 -38.175184) (xy 11.061916 -38.175184) (xy 11.061367 -38.175799) (xy 10.997053 -38.235864)
			(xy 10.927545 -38.289831) (xy 10.853417 -38.337253) (xy 10.775283 -38.377739) (xy 10.693792 -38.410952)
			(xy 10.609618 -38.436616) (xy 10.523459 -38.45452) (xy 10.436029 -38.464515) (xy 10.348052 -38.466519)
			(xy 10.260258 -38.460513) (xy 10.173374 -38.446549) (xy 10.088119 -38.424742) (xy 10.0052 -38.395273)
			(xy 9.925305 -38.358386) (xy 9.849096 -38.314386) (xy 9.777203 -38.263638) (xy 9.710222 -38.206564)
			(xy 9.64871 -38.143634) (xy 9.593174 -38.075372) (xy 9.544076 -38.002343) (xy 9.501823 -37.925151)
			(xy 9.466764 -37.844437) (xy 9.439189 -37.760869) (xy 9.419329 -37.67514) (xy 9.407346 -37.58796)
			(xy 9.403341 -37.500052) (xy 6.962328 -37.500052) (xy 6.961012 -37.50141) (xy 6.838282 -37.616502)
			(xy 6.710176 -37.72558) (xy 6.576989 -37.828392) (xy 6.439027 -37.924701) (xy 6.296607 -38.014288)
			(xy 6.150056 -38.096944) (xy 5.999713 -38.172481) (xy 5.845921 -38.240725) (xy 5.689035 -38.301519)
			(xy 5.529416 -38.354723) (xy 5.36743 -38.400215) (xy 5.203449 -38.437891) (xy 5.037851 -38.467663)
			(xy 4.871016 -38.489463) (xy 4.703328 -38.503242) (xy 4.535173 -38.508967) (xy 4.366936 -38.506626)
			(xy 4.199005 -38.496223) (xy 4.031766 -38.477782) (xy 3.865602 -38.451347) (xy 3.700897 -38.416978)
			(xy 3.538028 -38.374753) (xy 3.377371 -38.324771) (xy 3.219294 -38.267145) (xy 3.064161 -38.202008)
			(xy 2.912328 -38.12951) (xy 2.764145 -38.049818) (xy 2.619952 -37.963115) (xy 2.480081 -37.8696)
			(xy 2.344853 -37.769488) (xy 2.214578 -37.663009) (xy 2.089558 -37.550408) (xy 1.970078 -37.431945)
			(xy 1.912874 -37.370258) (xy 1.896542 -37.353536) (xy 1.858943 -37.325774) (xy 1.816903 -37.305355)
			(xy 1.771837 -37.292967) (xy 1.725266 -37.289028) (xy 1.67876 -37.29367) (xy 1.633887 -37.306738)
			(xy 1.59216 -37.32779) (xy 1.554985 -37.356118) (xy 1.523617 -37.390764) (xy 1.499113 -37.430563)
			(xy 1.482299 -37.47417) (xy 1.473741 -37.520118) (xy 1.4732 -37.543486) (xy 1.4732 -39.278661) (xy 20.650192 -39.278661)
			(xy 20.650192 -39.207339) (xy 20.658178 -39.136465) (xy 20.674048 -39.06693) (xy 20.697605 -38.99961)
			(xy 20.72855 -38.935351) (xy 20.766496 -38.87496) (xy 20.810965 -38.819198) (xy 20.861398 -38.768765)
			(xy 20.91716 -38.724296) (xy 20.977551 -38.68635) (xy 21.04181 -38.655405) (xy 21.10913 -38.631848)
			(xy 21.178665 -38.615978) (xy 21.249539 -38.607992) (xy 21.320861 -38.607992) (xy 21.391735 -38.615978)
			(xy 21.46127 -38.631848) (xy 21.52859 -38.655405) (xy 21.592849 -38.68635) (xy 21.65324 -38.724296)
			(xy 21.709002 -38.768765) (xy 21.759435 -38.819198) (xy 21.803904 -38.87496) (xy 21.84185 -38.935351)
			(xy 21.872795 -38.99961) (xy 21.896352 -39.06693) (xy 21.912222 -39.136465) (xy 21.920208 -39.207339)
			(xy 21.920708 -39.243) (xy 21.920208 -39.278661) (xy 21.912222 -39.349535) (xy 21.896352 -39.41907)
			(xy 21.872795 -39.48639) (xy 21.84185 -39.550649) (xy 21.803904 -39.61104) (xy 21.759435 -39.666802)
			(xy 21.709002 -39.717235) (xy 21.65324 -39.761704) (xy 21.592849 -39.79965) (xy 21.52859 -39.830595)
			(xy 21.46127 -39.854152) (xy 21.391735 -39.870022) (xy 21.320861 -39.878008) (xy 21.249539 -39.878008)
			(xy 21.178665 -39.870022) (xy 21.10913 -39.854152) (xy 21.04181 -39.830595) (xy 20.977551 -39.79965)
			(xy 20.91716 -39.761704) (xy 20.861398 -39.717235) (xy 20.810965 -39.666802) (xy 20.766496 -39.61104)
			(xy 20.72855 -39.550649) (xy 20.697605 -39.48639) (xy 20.674048 -39.41907) (xy 20.658178 -39.349535)
			(xy 20.650192 -39.278661) (xy 1.4732 -39.278661) (xy 1.4732 -39.3446) (xy 3.388461 -41.259861) (xy 12.547592 -41.259861)
			(xy 12.547592 -41.188539) (xy 12.555578 -41.117665) (xy 12.571448 -41.04813) (xy 12.595005 -40.98081)
			(xy 12.62595 -40.916551) (xy 12.663896 -40.85616) (xy 12.708365 -40.800398) (xy 12.758798 -40.749965)
			(xy 12.81456 -40.705496) (xy 12.874951 -40.66755) (xy 12.93921 -40.636605) (xy 13.00653 -40.613048)
			(xy 13.076065 -40.597178) (xy 13.146939 -40.589192) (xy 13.218261 -40.589192) (xy 13.289135 -40.597178)
			(xy 13.35867 -40.613048) (xy 13.42599 -40.636605) (xy 13.490249 -40.66755) (xy 13.55064 -40.705496)
			(xy 13.606402 -40.749965) (xy 13.656835 -40.800398) (xy 13.701304 -40.85616) (xy 13.73925 -40.916551)
			(xy 13.770195 -40.98081) (xy 13.793752 -41.04813) (xy 13.809622 -41.117665) (xy 13.817608 -41.188539)
			(xy 13.818108 -41.2242) (xy 13.817608 -41.259861) (xy 13.809622 -41.330735) (xy 13.793752 -41.40027)
			(xy 13.770195 -41.46759) (xy 13.73925 -41.531849) (xy 13.701304 -41.59224) (xy 13.656835 -41.648002)
			(xy 13.606402 -41.698435) (xy 13.55064 -41.742904) (xy 13.490249 -41.78085) (xy 13.42599 -41.811795)
			(xy 13.35867 -41.835352) (xy 13.289135 -41.851222) (xy 13.218261 -41.859208) (xy 13.146939 -41.859208)
			(xy 13.076065 -41.851222) (xy 13.00653 -41.835352) (xy 12.93921 -41.811795) (xy 12.874951 -41.78085)
			(xy 12.81456 -41.742904) (xy 12.758798 -41.698435) (xy 12.708365 -41.648002) (xy 12.663896 -41.59224)
			(xy 12.62595 -41.531849) (xy 12.595005 -41.46759) (xy 12.571448 -41.40027) (xy 12.555578 -41.330735)
			(xy 12.547592 -41.259861) (xy 3.388461 -41.259861) (xy 3.8354 -41.7068) (xy 11.1506 -41.7068) (xy 12.468352 -43.024552)
			(xy 12.484563 -43.040085) (xy 12.521393 -43.065756) (xy 12.562161 -43.084554) (xy 12.605598 -43.095894)
			(xy 12.650352 -43.099423) (xy 12.69503 -43.095032) (xy 12.738241 -43.082857) (xy 12.778639 -43.063276)
			(xy 12.814967 -43.036901) (xy 12.846094 -43.004551) (xy 12.87105 -42.967234) (xy 12.88906 -42.926112)
			(xy 12.894818 -42.90441) (xy 12.903903 -42.868853) (xy 12.929165 -42.799948) (xy 12.962195 -42.73441)
			(xy 13.002553 -42.673113) (xy 13.049704 -42.616872) (xy 13.103018 -42.566437) (xy 13.161786 -42.522477)
			(xy 13.225226 -42.485579) (xy 13.292494 -42.456233) (xy 13.362694 -42.43483) (xy 13.434893 -42.421655)
			(xy 13.508128 -42.416884) (xy 13.581425 -42.420579) (xy 13.617702 -42.426128) (xy 13.640013 -42.429366)
			(xy 13.68509 -42.428841) (xy 13.729367 -42.420372) (xy 13.771455 -42.404225) (xy 13.810034 -42.380906)
			(xy 13.843895 -42.351146) (xy 13.871974 -42.315879) (xy 13.893391 -42.276212) (xy 13.907474 -42.233389)
			(xy 13.913781 -42.188753) (xy 13.912114 -42.143704) (xy 13.90777 -42.121582) (xy 13.900595 -42.086324)
			(xy 13.893306 -42.014738) (xy 13.894149 -41.942788) (xy 13.903112 -41.871393) (xy 13.92008 -41.801466)
			(xy 13.944837 -41.733904) (xy 13.977065 -41.669569) (xy 14.016352 -41.609286) (xy 14.062197 -41.553825)
			(xy 14.114011 -41.503897) (xy 14.171132 -41.460139) (xy 14.23283 -41.423112) (xy 14.298314 -41.393289)
			(xy 14.366748 -41.371053) (xy 14.437255 -41.356687) (xy 14.508933 -41.350376) (xy 14.580865 -41.3522)
			(xy 14.652131 -41.362136) (xy 14.721819 -41.380056) (xy 14.789038 -41.405732) (xy 14.852927 -41.438835)
			(xy 14.912669 -41.478941) (xy 14.967499 -41.525538) (xy 15.016716 -41.578028) (xy 15.059691 -41.635741)
			(xy 15.095873 -41.697938) (xy 15.124799 -41.763823) (xy 15.1461 -41.832553) (xy 15.159503 -41.90325)
			(xy 15.164742 -41.973741) (xy 16.00096 -41.973741) (xy 16.003132 -41.918141) (xy 16.013356 -41.863446)
			(xy 16.031415 -41.810816) (xy 16.056926 -41.761367) (xy 16.089348 -41.716146) (xy 16.127993 -41.676114)
			(xy 16.172043 -41.642118) (xy 16.196056 -41.62806) (xy 16.21499 -41.616876) (xy 16.249058 -41.58908)
			(xy 16.277832 -41.555832) (xy 16.300451 -41.518127) (xy 16.316239 -41.47709) (xy 16.324726 -41.433947)
			(xy 16.325657 -41.389987) (xy 16.319005 -41.346524) (xy 16.304968 -41.304855) (xy 16.283966 -41.266226)
			(xy 16.256626 -41.23179) (xy 16.240506 -41.216834) (xy 16.214089 -41.192783) (xy 16.166322 -41.139654)
			(xy 16.124815 -41.081503) (xy 16.09009 -41.019064) (xy 16.062586 -40.953125) (xy 16.04265 -40.884517)
			(xy 16.030533 -40.814107) (xy 16.026389 -40.742782) (xy 16.030268 -40.671443) (xy 16.042123 -40.600988)
			(xy 16.061804 -40.532307) (xy 16.089063 -40.466266) (xy 16.123555 -40.403699) (xy 16.164846 -40.345394)
			(xy 16.212414 -40.292087) (xy 16.265661 -40.24445) (xy 16.323913 -40.203085) (xy 16.386437 -40.168513)
			(xy 16.452443 -40.141171) (xy 16.521099 -40.121403) (xy 16.591538 -40.109458) (xy 16.662873 -40.105488)
			(xy 16.734203 -40.109542) (xy 16.804629 -40.121569) (xy 16.873261 -40.141418) (xy 16.901347 -40.153091)
			(xy 19.379521 -40.153091) (xy 19.38111 -40.082378) (xy 19.39054 -40.012278) (xy 19.407696 -39.943659)
			(xy 19.432366 -39.877369) (xy 19.464243 -39.814228) (xy 19.502934 -39.755017) (xy 19.54796 -39.700468)
			(xy 19.598764 -39.651256) (xy 19.654719 -39.60799) (xy 19.715132 -39.571204) (xy 19.779256 -39.541353)
			(xy 19.846298 -39.518807) (xy 19.915429 -39.503845) (xy 19.985793 -39.496651) (xy 20.056521 -39.497315)
			(xy 20.126739 -39.505827) (xy 20.195576 -39.522084) (xy 20.262184 -39.545884) (xy 20.325736 -39.576932)
			(xy 20.385448 -39.614845) (xy 20.440581 -39.659154) (xy 20.490454 -39.70931) (xy 20.534449 -39.764694)
			(xy 20.572022 -39.82462) (xy 20.602709 -39.888348) (xy 20.62613 -39.955089) (xy 20.641996 -40.024018)
			(xy 20.65011 -40.094283) (xy 20.650372 -40.165014) (xy 20.642778 -40.235336) (xy 20.627424 -40.304381)
			(xy 20.616418 -40.337994) (xy 20.60962 -40.35923) (xy 20.603837 -40.396261) (xy 21.716992 -40.396261)
			(xy 21.716992 -40.324939) (xy 21.724978 -40.254065) (xy 21.740848 -40.18453) (xy 21.764405 -40.11721)
			(xy 21.79535 -40.052951) (xy 21.833296 -39.99256) (xy 21.877765 -39.936798) (xy 21.928198 -39.886365)
			(xy 21.98396 -39.841896) (xy 22.044351 -39.80395) (xy 22.10861 -39.773005) (xy 22.17593 -39.749448)
			(xy 22.245465 -39.733578) (xy 22.316339 -39.725592) (xy 22.387661 -39.725592) (xy 22.458535 -39.733578)
			(xy 22.52807 -39.749448) (xy 22.59539 -39.773005) (xy 22.659649 -39.80395) (xy 22.72004 -39.841896)
			(xy 22.775802 -39.886365) (xy 22.826235 -39.936798) (xy 22.870704 -39.99256) (xy 22.90865 -40.052951)
			(xy 22.939595 -40.11721) (xy 22.963152 -40.18453) (xy 22.979022 -40.254065) (xy 22.987008 -40.324939)
			(xy 22.987508 -40.3606) (xy 22.987008 -40.396261) (xy 22.979022 -40.467135) (xy 22.963152 -40.53667)
			(xy 22.939595 -40.60399) (xy 22.90865 -40.668249) (xy 22.870704 -40.72864) (xy 22.826235 -40.784402)
			(xy 22.775802 -40.834835) (xy 22.72004 -40.879304) (xy 22.659649 -40.91725) (xy 22.59539 -40.948195)
			(xy 22.52807 -40.971752) (xy 22.458535 -40.987622) (xy 22.387661 -40.995608) (xy 22.316339 -40.995608)
			(xy 22.245465 -40.987622) (xy 22.17593 -40.971752) (xy 22.10861 -40.948195) (xy 22.044351 -40.91725)
			(xy 21.98396 -40.879304) (xy 21.928198 -40.834835) (xy 21.877765 -40.784402) (xy 21.833296 -40.72864)
			(xy 21.79535 -40.668249) (xy 21.764405 -40.60399) (xy 21.740848 -40.53667) (xy 21.724978 -40.467135)
			(xy 21.716992 -40.396261) (xy 20.603837 -40.396261) (xy 20.60274 -40.403282) (xy 20.603649 -40.447858)
			(xy 20.612319 -40.491593) (xy 20.628484 -40.533145) (xy 20.651649 -40.57124) (xy 20.681104 -40.604711)
			(xy 20.715945 -40.632531) (xy 20.755105 -40.653847) (xy 20.797383 -40.668007) (xy 20.819364 -40.67175)
			(xy 20.854285 -40.67736) (xy 20.922674 -40.695413) (xy 20.988635 -40.720947) (xy 21.051353 -40.753648)
			(xy 21.110053 -40.79311) (xy 21.164008 -40.838846) (xy 21.212551 -40.89029) (xy 21.255082 -40.946806)
			(xy 21.291074 -41.007695) (xy 21.320083 -41.072204) (xy 21.34175 -41.139535) (xy 21.355807 -41.208856)
			(xy 21.362079 -41.279309) (xy 21.36049 -41.350022) (xy 21.352117 -41.412261) (xy 23.215592 -41.412261)
			(xy 23.215592 -41.340939) (xy 23.223578 -41.270065) (xy 23.239448 -41.20053) (xy 23.263005 -41.13321)
			(xy 23.29395 -41.068951) (xy 23.331896 -41.00856) (xy 23.376365 -40.952798) (xy 23.426798 -40.902365)
			(xy 23.48256 -40.857896) (xy 23.542951 -40.81995) (xy 23.60721 -40.789005) (xy 23.67453 -40.765448)
			(xy 23.744065 -40.749578) (xy 23.814939 -40.741592) (xy 23.886261 -40.741592) (xy 23.957135 -40.749578)
			(xy 24.02667 -40.765448) (xy 24.09399 -40.789005) (xy 24.158249 -40.81995) (xy 24.21864 -40.857896)
			(xy 24.274402 -40.902365) (xy 24.324835 -40.952798) (xy 24.369304 -41.00856) (xy 24.40725 -41.068951)
			(xy 24.438195 -41.13321) (xy 24.461752 -41.20053) (xy 24.477622 -41.270065) (xy 24.485608 -41.340939)
			(xy 24.486108 -41.3766) (xy 24.485608 -41.412261) (xy 24.477622 -41.483135) (xy 24.464812 -41.539261)
			(xy 24.942792 -41.539261) (xy 24.942792 -41.467939) (xy 24.950778 -41.397065) (xy 24.966648 -41.32753)
			(xy 24.990205 -41.26021) (xy 25.02115 -41.195951) (xy 25.059096 -41.13556) (xy 25.103565 -41.079798)
			(xy 25.153998 -41.029365) (xy 25.20976 -40.984896) (xy 25.270151 -40.94695) (xy 25.33441 -40.916005)
			(xy 25.40173 -40.892448) (xy 25.471265 -40.876578) (xy 25.542139 -40.868592) (xy 25.613461 -40.868592)
			(xy 25.684335 -40.876578) (xy 25.75387 -40.892448) (xy 25.82119 -40.916005) (xy 25.885449 -40.94695)
			(xy 25.94584 -40.984896) (xy 26.001602 -41.029365) (xy 26.052035 -41.079798) (xy 26.096504 -41.13556)
			(xy 26.13445 -41.195951) (xy 26.165395 -41.26021) (xy 26.188952 -41.32753) (xy 26.204822 -41.397065)
			(xy 26.212808 -41.467939) (xy 26.213308 -41.5036) (xy 26.212808 -41.539261) (xy 26.204822 -41.610135)
			(xy 26.188952 -41.67967) (xy 26.165395 -41.74699) (xy 26.13445 -41.811249) (xy 26.096504 -41.87164)
			(xy 26.052035 -41.927402) (xy 26.001602 -41.977835) (xy 25.94584 -42.022304) (xy 25.885449 -42.06025)
			(xy 25.82119 -42.091195) (xy 25.75387 -42.114752) (xy 25.684335 -42.130622) (xy 25.613461 -42.138608)
			(xy 25.542139 -42.138608) (xy 25.471265 -42.130622) (xy 25.40173 -42.114752) (xy 25.33441 -42.091195)
			(xy 25.270151 -42.06025) (xy 25.20976 -42.022304) (xy 25.153998 -41.977835) (xy 25.103565 -41.927402)
			(xy 25.059096 -41.87164) (xy 25.02115 -41.811249) (xy 24.990205 -41.74699) (xy 24.966648 -41.67967)
			(xy 24.950778 -41.610135) (xy 24.942792 -41.539261) (xy 24.464812 -41.539261) (xy 24.461752 -41.55267)
			(xy 24.438195 -41.61999) (xy 24.40725 -41.684249) (xy 24.369304 -41.74464) (xy 24.324835 -41.800402)
			(xy 24.274402 -41.850835) (xy 24.21864 -41.895304) (xy 24.158249 -41.93325) (xy 24.09399 -41.964195)
			(xy 24.02667 -41.987752) (xy 23.957135 -42.003622) (xy 23.886261 -42.011608) (xy 23.814939 -42.011608)
			(xy 23.744065 -42.003622) (xy 23.67453 -41.987752) (xy 23.60721 -41.964195) (xy 23.542951 -41.93325)
			(xy 23.48256 -41.895304) (xy 23.426798 -41.850835) (xy 23.376365 -41.800402) (xy 23.331896 -41.74464)
			(xy 23.29395 -41.684249) (xy 23.263005 -41.61999) (xy 23.239448 -41.55267) (xy 23.223578 -41.483135)
			(xy 23.215592 -41.412261) (xy 21.352117 -41.412261) (xy 21.35106 -41.420122) (xy 21.333904 -41.488741)
			(xy 21.309234 -41.555031) (xy 21.277357 -41.618172) (xy 21.238666 -41.677383) (xy 21.19364 -41.731932)
			(xy 21.142836 -41.781144) (xy 21.086881 -41.82441) (xy 21.026468 -41.861196) (xy 20.962344 -41.891047)
			(xy 20.895302 -41.913593) (xy 20.826171 -41.928555) (xy 20.755807 -41.935749) (xy 20.685079 -41.935085)
			(xy 20.614861 -41.926573) (xy 20.546024 -41.910316) (xy 20.479416 -41.886516) (xy 20.415864 -41.855468)
			(xy 20.356152 -41.817555) (xy 20.301019 -41.773246) (xy 20.251146 -41.72309) (xy 20.207151 -41.667706)
			(xy 20.169578 -41.60778) (xy 20.138891 -41.544052) (xy 20.11547 -41.477311) (xy 20.099604 -41.408382)
			(xy 20.09149 -41.338117) (xy 20.091228 -41.267386) (xy 20.098822 -41.197064) (xy 20.114176 -41.128019)
			(xy 20.125182 -41.094406) (xy 20.13198 -41.07317) (xy 20.13886 -41.029118) (xy 20.137951 -40.984542)
			(xy 20.129281 -40.940807) (xy 20.113116 -40.899255) (xy 20.089951 -40.86116) (xy 20.060496 -40.827689)
			(xy 20.025655 -40.799869) (xy 19.986495 -40.778553) (xy 19.944217 -40.764393) (xy 19.922236 -40.76065)
			(xy 19.887315 -40.75504) (xy 19.818926 -40.736987) (xy 19.752965 -40.711453) (xy 19.690247 -40.678752)
			(xy 19.631547 -40.63929) (xy 19.577592 -40.593554) (xy 19.529049 -40.54211) (xy 19.486518 -40.485594)
			(xy 19.450526 -40.424705) (xy 19.421517 -40.360196) (xy 19.39985 -40.292865) (xy 19.385793 -40.223544)
			(xy 19.379521 -40.153091) (xy 16.901347 -40.153091) (xy 16.939235 -40.168838) (xy 17.001718 -40.203483)
			(xy 17.059922 -40.244916) (xy 17.113113 -40.292615) (xy 17.160619 -40.345978) (xy 17.201841 -40.404331)
			(xy 17.23626 -40.466939) (xy 17.263441 -40.533012) (xy 17.283041 -40.601716) (xy 17.294814 -40.672184)
			(xy 17.29861 -40.743529) (xy 17.294381 -40.814849) (xy 17.282182 -40.885245) (xy 17.262165 -40.953828)
			(xy 17.234584 -41.019735) (xy 17.199786 -41.082133) (xy 17.15821 -41.140235) (xy 17.110382 -41.193309)
			(xy 17.092601 -41.209061) (xy 17.957792 -41.209061) (xy 17.957792 -41.137739) (xy 17.965778 -41.066865)
			(xy 17.981648 -40.99733) (xy 18.005205 -40.93001) (xy 18.03615 -40.865751) (xy 18.074096 -40.80536)
			(xy 18.118565 -40.749598) (xy 18.168998 -40.699165) (xy 18.22476 -40.654696) (xy 18.285151 -40.61675)
			(xy 18.34941 -40.585805) (xy 18.41673 -40.562248) (xy 18.486265 -40.546378) (xy 18.557139 -40.538392)
			(xy 18.628461 -40.538392) (xy 18.699335 -40.546378) (xy 18.76887 -40.562248) (xy 18.83619 -40.585805)
			(xy 18.900449 -40.61675) (xy 18.96084 -40.654696) (xy 19.016602 -40.699165) (xy 19.067035 -40.749598)
			(xy 19.111504 -40.80536) (xy 19.14945 -40.865751) (xy 19.180395 -40.93001) (xy 19.203952 -40.99733)
			(xy 19.219822 -41.066865) (xy 19.227808 -41.137739) (xy 19.228308 -41.1734) (xy 19.227808 -41.209061)
			(xy 19.219822 -41.279935) (xy 19.203952 -41.34947) (xy 19.180395 -41.41679) (xy 19.14945 -41.481049)
			(xy 19.111504 -41.54144) (xy 19.067035 -41.597202) (xy 19.016602 -41.647635) (xy 18.96084 -41.692104)
			(xy 18.900449 -41.73005) (xy 18.83619 -41.760995) (xy 18.76887 -41.784552) (xy 18.699335 -41.800422)
			(xy 18.628461 -41.808408) (xy 18.557139 -41.808408) (xy 18.486265 -41.800422) (xy 18.41673 -41.784552)
			(xy 18.34941 -41.760995) (xy 18.285151 -41.73005) (xy 18.22476 -41.692104) (xy 18.168998 -41.647635)
			(xy 18.118565 -41.597202) (xy 18.074096 -41.54144) (xy 18.03615 -41.481049) (xy 18.005205 -41.41679)
			(xy 17.981648 -41.34947) (xy 17.965778 -41.279935) (xy 17.957792 -41.209061) (xy 17.092601 -41.209061)
			(xy 17.056903 -41.240685) (xy 16.998449 -41.281764) (xy 16.935757 -41.31603) (xy 16.869618 -41.343049)
			(xy 16.835374 -41.353232) (xy 16.814339 -41.359639) (xy 16.774716 -41.378697) (xy 16.738966 -41.404293)
			(xy 16.708156 -41.435661) (xy 16.683206 -41.471864) (xy 16.664862 -41.511823) (xy 16.653671 -41.554344)
			(xy 16.649968 -41.598156) (xy 16.653862 -41.641951) (xy 16.665239 -41.684422) (xy 16.683757 -41.7243)
			(xy 16.695928 -41.742614) (xy 16.711423 -41.765727) (xy 16.736272 -41.815512) (xy 16.753628 -41.868378)
			(xy 16.763123 -41.923204) (xy 16.764554 -41.978828) (xy 16.757892 -42.03407) (xy 16.743278 -42.087759)
			(xy 16.721022 -42.138756) (xy 16.691595 -42.185981) (xy 16.655622 -42.228431) (xy 16.613866 -42.265206)
			(xy 16.567211 -42.295528) (xy 16.516647 -42.318753) (xy 16.463247 -42.334388) (xy 16.408142 -42.342102)
			(xy 16.352501 -42.341731) (xy 16.297503 -42.333284) (xy 16.244316 -42.316938) (xy 16.194066 -42.293042)
			(xy 16.147819 -42.262102) (xy 16.106557 -42.224773) (xy 16.071152 -42.181848) (xy 16.042357 -42.134235)
			(xy 16.020783 -42.082946) (xy 16.006885 -42.029067) (xy 16.00096 -41.973741) (xy 15.164742 -41.973741)
			(xy 15.164836 -41.975007) (xy 15.162031 -42.046908) (xy 15.151124 -42.118032) (xy 15.132254 -42.187469)
			(xy 15.105664 -42.254331) (xy 15.071693 -42.317763) (xy 15.030776 -42.376952) (xy 14.983436 -42.431142)
			(xy 14.930279 -42.479638) (xy 14.871985 -42.521822) (xy 14.8093 -42.557152) (xy 14.743027 -42.585177)
			(xy 14.674012 -42.605538) (xy 14.60314 -42.617975) (xy 14.531316 -42.622329) (xy 14.45946 -42.618544)
			(xy 14.423898 -42.613072) (xy 14.401587 -42.609834) (xy 14.35651 -42.610359) (xy 14.312233 -42.618828)
			(xy 14.270145 -42.634975) (xy 14.231566 -42.658294) (xy 14.197705 -42.688054) (xy 14.169626 -42.723321)
			(xy 14.148209 -42.762988) (xy 14.134126 -42.805811) (xy 14.127819 -42.850447) (xy 14.129486 -42.895496)
			(xy 14.13383 -42.917618) (xy 14.140862 -42.952095) (xy 14.148164 -43.022082) (xy 14.147692 -43.092448)
			(xy 14.13945 -43.16233) (xy 14.132967 -43.190261) (xy 15.163792 -43.190261) (xy 15.163792 -43.118939)
			(xy 15.171778 -43.048065) (xy 15.187648 -42.97853) (xy 15.211205 -42.91121) (xy 15.24215 -42.846951)
			(xy 15.280096 -42.78656) (xy 15.324565 -42.730798) (xy 15.374998 -42.680365) (xy 15.43076 -42.635896)
			(xy 15.491151 -42.59795) (xy 15.55541 -42.567005) (xy 15.62273 -42.543448) (xy 15.692265 -42.527578)
			(xy 15.763139 -42.519592) (xy 15.834461 -42.519592) (xy 15.905335 -42.527578) (xy 15.97487 -42.543448)
			(xy 16.04219 -42.567005) (xy 16.106449 -42.59795) (xy 16.16684 -42.635896) (xy 16.222602 -42.680365)
			(xy 16.273035 -42.730798) (xy 16.317504 -42.78656) (xy 16.35545 -42.846951) (xy 16.386395 -42.91121)
			(xy 16.409952 -42.97853) (xy 16.425822 -43.048065) (xy 16.433808 -43.118939) (xy 16.434308 -43.1546)
			(xy 16.433808 -43.190261) (xy 16.430946 -43.215661) (xy 17.246592 -43.215661) (xy 17.246592 -43.144339)
			(xy 17.254578 -43.073465) (xy 17.270448 -43.00393) (xy 17.294005 -42.93661) (xy 17.32495 -42.872351)
			(xy 17.362896 -42.81196) (xy 17.407365 -42.756198) (xy 17.457798 -42.705765) (xy 17.51356 -42.661296)
			(xy 17.573951 -42.62335) (xy 17.63821 -42.592405) (xy 17.70553 -42.568848) (xy 17.775065 -42.552978)
			(xy 17.845939 -42.544992) (xy 17.917261 -42.544992) (xy 17.988135 -42.552978) (xy 18.05767 -42.568848)
			(xy 18.12499 -42.592405) (xy 18.189249 -42.62335) (xy 18.24964 -42.661296) (xy 18.305402 -42.705765)
			(xy 18.355835 -42.756198) (xy 18.400304 -42.81196) (xy 18.43825 -42.872351) (xy 18.469195 -42.93661)
			(xy 18.492752 -43.00393) (xy 18.508622 -43.073465) (xy 18.516608 -43.144339) (xy 18.517089 -43.178619)
			(xy 19.227229 -43.178619) (xy 19.228585 -43.106784) (xy 19.238033 -43.035561) (xy 19.255453 -42.965857)
			(xy 19.280623 -42.898563) (xy 19.313221 -42.834537) (xy 19.352833 -42.774596) (xy 19.398952 -42.719504)
			(xy 19.45099 -42.669965) (xy 19.508282 -42.626611) (xy 19.570099 -42.589995) (xy 19.635651 -42.560583)
			(xy 19.704101 -42.538753) (xy 19.774577 -42.524781) (xy 19.846179 -42.518847) (xy 19.917993 -42.521025)
			(xy 19.989104 -42.531289) (xy 20.058603 -42.549507) (xy 20.125604 -42.575447) (xy 20.189252 -42.608777)
			(xy 20.248736 -42.649074) (xy 20.303295 -42.695821) (xy 20.328128 -42.721784) (xy 20.343306 -42.737485)
			(xy 20.378093 -42.763883) (xy 20.416881 -42.783942) (xy 20.458529 -42.797071) (xy 20.501809 -42.802883)
			(xy 20.545446 -42.801207) (xy 20.588152 -42.792092) (xy 20.628671 -42.775807) (xy 20.665807 -42.752831)
			(xy 20.698465 -42.723843) (xy 20.71243 -42.707052) (xy 20.735237 -42.679293) (xy 20.786126 -42.628574)
			(xy 20.84241 -42.583918) (xy 20.90337 -42.545894) (xy 20.968231 -42.514988) (xy 21.036163 -42.491594)
			(xy 21.1063 -42.47601) (xy 21.177747 -42.468436) (xy 21.249592 -42.468967) (xy 21.320919 -42.477598)
			(xy 21.390818 -42.494218) (xy 21.458396 -42.518615) (xy 21.522792 -42.550478) (xy 21.583183 -42.589399)
			(xy 21.6388 -42.634884) (xy 21.688932 -42.68635) (xy 21.73294 -42.743142) (xy 21.770263 -42.804535)
			(xy 21.800423 -42.869745) (xy 21.823037 -42.937941) (xy 21.837816 -43.008252) (xy 21.840213 -43.033632)
			(xy 22.275082 -43.033632) (xy 22.281216 -42.962803) (xy 22.295216 -42.8931) (xy 22.316907 -42.825396)
			(xy 22.34602 -42.760535) (xy 22.38219 -42.699329) (xy 22.424964 -42.642542) (xy 22.449028 -42.616374)
			(xy 22.463818 -42.600097) (xy 22.488114 -42.563442) (xy 22.505732 -42.52315) (xy 22.516144 -42.480425)
			(xy 22.519041 -42.436545) (xy 22.514334 -42.392822) (xy 22.502164 -42.350564) (xy 22.482897 -42.311034)
			(xy 22.457107 -42.275415) (xy 22.441662 -42.259758) (xy 22.422092 -42.240062) (xy 22.388311 -42.195999)
			(xy 22.361274 -42.147505) (xy 22.341551 -42.095604) (xy 22.329559 -42.041392) (xy 22.325552 -41.986015)
			(xy 22.329613 -41.930642) (xy 22.341657 -41.876442) (xy 22.36143 -41.82456) (xy 22.388514 -41.776092)
			(xy 22.422338 -41.732062) (xy 22.462186 -41.693399) (xy 22.507217 -41.660919) (xy 22.55648 -41.63531)
			(xy 22.608935 -41.617112) (xy 22.663474 -41.606709) (xy 22.718944 -41.60432) (xy 22.774175 -41.609997)
			(xy 22.828 -41.623619) (xy 22.879282 -41.6449) (xy 22.926939 -41.673388) (xy 22.969962 -41.708483)
			(xy 23.007445 -41.749443) (xy 23.038595 -41.795404) (xy 23.062754 -41.845394) (xy 23.079413 -41.898358)
			(xy 23.088218 -41.953177) (xy 23.088985 -42.008694) (xy 23.081698 -42.063736) (xy 23.066509 -42.11714)
			(xy 23.05558 -42.142664) (xy 23.046978 -42.162907) (xy 23.036112 -42.205524) (xy 23.03274 -42.249375)
			(xy 23.036964 -42.293153) (xy 23.048656 -42.335551) (xy 23.067468 -42.375305) (xy 23.09284 -42.411229)
			(xy 23.124014 -42.442253) (xy 23.160061 -42.46745) (xy 23.179786 -42.477182) (xy 23.211769 -42.492706)
			(xy 23.272421 -42.529796) (xy 23.328555 -42.573424) (xy 23.379469 -42.623045) (xy 23.424527 -42.678038)
			(xy 23.463166 -42.737716) (xy 23.494903 -42.801333) (xy 23.519341 -42.868095) (xy 23.536176 -42.937168)
			(xy 23.545196 -43.007688) (xy 23.54629 -43.078774) (xy 23.545333 -43.088661) (xy 23.977592 -43.088661)
			(xy 23.977592 -43.017339) (xy 23.985578 -42.946465) (xy 24.001448 -42.87693) (xy 24.025005 -42.80961)
			(xy 24.05595 -42.745351) (xy 24.093896 -42.68496) (xy 24.138365 -42.629198) (xy 24.188798 -42.578765)
			(xy 24.24456 -42.534296) (xy 24.304951 -42.49635) (xy 24.36921 -42.465405) (xy 24.43653 -42.441848)
			(xy 24.506065 -42.425978) (xy 24.576939 -42.417992) (xy 24.648261 -42.417992) (xy 24.719135 -42.425978)
			(xy 24.78867 -42.441848) (xy 24.85599 -42.465405) (xy 24.920249 -42.49635) (xy 24.98064 -42.534296)
			(xy 25.036402 -42.578765) (xy 25.086835 -42.629198) (xy 25.131304 -42.68496) (xy 25.16925 -42.745351)
			(xy 25.200195 -42.80961) (xy 25.223752 -42.87693) (xy 25.239622 -42.946465) (xy 25.247608 -43.017339)
			(xy 25.248108 -43.053) (xy 25.247608 -43.088661) (xy 25.239622 -43.159535) (xy 25.223752 -43.22907)
			(xy 25.209048 -43.271089) (xy 26.415236 -43.271089) (xy 26.417589 -43.199553) (xy 26.427967 -43.128734)
			(xy 26.446237 -43.059529) (xy 26.472167 -42.992816) (xy 26.505431 -42.92944) (xy 26.545605 -42.870203)
			(xy 26.592182 -42.815855) (xy 26.64457 -42.767086) (xy 26.673048 -42.745406) (xy 26.690618 -42.731888)
			(xy 26.721116 -42.699718) (xy 26.745573 -42.662745) (xy 26.763246 -42.622091) (xy 26.773599 -42.578987)
			(xy 26.77632 -42.534741) (xy 26.771324 -42.490694) (xy 26.758764 -42.448181) (xy 26.739021 -42.408491)
			(xy 26.712693 -42.372827) (xy 26.680578 -42.34227) (xy 26.66238 -42.329608) (xy 26.63935 -42.313803)
			(xy 26.597793 -42.276484) (xy 26.56212 -42.233504) (xy 26.533093 -42.185784) (xy 26.511334 -42.134342)
			(xy 26.497306 -42.080277) (xy 26.49131 -42.024744) (xy 26.493474 -41.968931) (xy 26.503751 -41.91403)
			(xy 26.521922 -41.861213) (xy 26.547598 -41.81161) (xy 26.580232 -41.766279) (xy 26.619125 -41.726191)
			(xy 26.663447 -41.6922) (xy 26.712251 -41.665034) (xy 26.764493 -41.645273) (xy 26.819059 -41.633339)
			(xy 26.874781 -41.629487) (xy 26.930469 -41.6338) (xy 26.984934 -41.646185) (xy 27.037011 -41.666378)
			(xy 27.085588 -41.693947) (xy 27.129627 -41.728303) (xy 27.168188 -41.768712) (xy 27.200445 -41.81431)
			(xy 27.22571 -41.864125) (xy 27.243444 -41.91709) (xy 27.253266 -41.972074) (xy 27.254968 -42.027903)
			(xy 27.248513 -42.083384) (xy 27.234038 -42.137331) (xy 27.211854 -42.188592) (xy 27.182434 -42.236071)
			(xy 27.164792 -42.257726) (xy 27.150795 -42.27493) (xy 27.128507 -42.313274) (xy 27.113209 -42.354904)
			(xy 27.105365 -42.398556) (xy 27.105214 -42.442907) (xy 27.112758 -42.486611) (xy 27.12777 -42.528344)
			(xy 27.149795 -42.56684) (xy 27.178164 -42.600932) (xy 27.212017 -42.629584) (xy 27.250328 -42.65193)
			(xy 27.270964 -42.660062) (xy 27.304368 -42.672914) (xy 27.368308 -42.70508) (xy 27.428229 -42.744227)
			(xy 27.483372 -42.78986) (xy 27.533037 -42.8414) (xy 27.576595 -42.898195) (xy 27.613496 -42.959525)
			(xy 27.643272 -43.024613) (xy 27.665544 -43.092635) (xy 27.680032 -43.162729) (xy 27.686551 -43.234006)
			(xy 27.685857 -43.266461) (xy 28.651192 -43.266461) (xy 28.651192 -43.195139) (xy 28.659178 -43.124265)
			(xy 28.675048 -43.05473) (xy 28.698605 -42.98741) (xy 28.72955 -42.923151) (xy 28.767496 -42.86276)
			(xy 28.811965 -42.806998) (xy 28.862398 -42.756565) (xy 28.91816 -42.712096) (xy 28.978551 -42.67415)
			(xy 29.04281 -42.643205) (xy 29.11013 -42.619648) (xy 29.179665 -42.603778) (xy 29.250539 -42.595792)
			(xy 29.321861 -42.595792) (xy 29.392735 -42.603778) (xy 29.46227 -42.619648) (xy 29.52959 -42.643205)
			(xy 29.593849 -42.67415) (xy 29.65424 -42.712096) (xy 29.710002 -42.756565) (xy 29.760435 -42.806998)
			(xy 29.804904 -42.86276) (xy 29.84285 -42.923151) (xy 29.873795 -42.98741) (xy 29.897352 -43.05473)
			(xy 29.913222 -43.124265) (xy 29.921208 -43.195139) (xy 29.921708 -43.2308) (xy 29.921208 -43.266461)
			(xy 29.913222 -43.337335) (xy 29.897352 -43.40687) (xy 29.873795 -43.47419) (xy 29.84285 -43.538449)
			(xy 29.804904 -43.59884) (xy 29.760435 -43.654602) (xy 29.710002 -43.705035) (xy 29.65424 -43.749504)
			(xy 29.593849 -43.78745) (xy 29.52959 -43.818395) (xy 29.46227 -43.841952) (xy 29.392735 -43.857822)
			(xy 29.321861 -43.865808) (xy 29.250539 -43.865808) (xy 29.179665 -43.857822) (xy 29.11013 -43.841952)
			(xy 29.04281 -43.818395) (xy 28.978551 -43.78745) (xy 28.91816 -43.749504) (xy 28.862398 -43.705035)
			(xy 28.811965 -43.654602) (xy 28.767496 -43.59884) (xy 28.72955 -43.538449) (xy 28.698605 -43.47419)
			(xy 28.675048 -43.40687) (xy 28.659178 -43.337335) (xy 28.651192 -43.266461) (xy 27.685857 -43.266461)
			(xy 27.68502 -43.305565) (xy 27.675457 -43.376499) (xy 27.657983 -43.445909) (xy 27.632821 -43.512915)
			(xy 27.600288 -43.57667) (xy 27.560797 -43.636365) (xy 27.514848 -43.691244) (xy 27.463023 -43.740612)
			(xy 27.405979 -43.783844) (xy 27.344438 -43.820392) (xy 27.27918 -43.849792) (xy 27.211032 -43.871674)
			(xy 27.140856 -43.885759) (xy 27.069542 -43.891868) (xy 26.997993 -43.889926) (xy 26.927115 -43.879955)
			(xy 26.857807 -43.862083) (xy 26.790946 -43.836536) (xy 26.72738 -43.803638) (xy 26.667913 -43.763804)
			(xy 26.613298 -43.717541) (xy 26.564229 -43.665433) (xy 26.521325 -43.608142) (xy 26.485132 -43.546392)
			(xy 26.456106 -43.480966) (xy 26.434617 -43.412693) (xy 26.420936 -43.342437) (xy 26.415236 -43.271089)
			(xy 25.209048 -43.271089) (xy 25.200195 -43.29639) (xy 25.16925 -43.360649) (xy 25.131304 -43.42104)
			(xy 25.086835 -43.476802) (xy 25.036402 -43.527235) (xy 24.98064 -43.571704) (xy 24.920249 -43.60965)
			(xy 24.85599 -43.640595) (xy 24.78867 -43.664152) (xy 24.719135 -43.680022) (xy 24.648261 -43.688008)
			(xy 24.576939 -43.688008) (xy 24.506065 -43.680022) (xy 24.43653 -43.664152) (xy 24.36921 -43.640595)
			(xy 24.304951 -43.60965) (xy 24.24456 -43.571704) (xy 24.188798 -43.527235) (xy 24.138365 -43.476802)
			(xy 24.093896 -43.42104) (xy 24.05595 -43.360649) (xy 24.025005 -43.29639) (xy 24.001448 -43.22907)
			(xy 23.985578 -43.159535) (xy 23.977592 -43.088661) (xy 23.545333 -43.088661) (xy 23.539443 -43.149538)
			(xy 23.524742 -43.219096) (xy 23.502369 -43.286578) (xy 23.472604 -43.351142) (xy 23.435819 -43.41198)
			(xy 23.392475 -43.468333) (xy 23.343111 -43.519496) (xy 23.288346 -43.564831) (xy 23.228864 -43.60377)
			(xy 23.165407 -43.635827) (xy 23.098769 -43.660602) (xy 23.029782 -43.677784) (xy 22.959308 -43.68716)
			(xy 22.888229 -43.688612) (xy 22.817431 -43.682122) (xy 22.7478 -43.667771) (xy 22.680206 -43.645738)
			(xy 22.615493 -43.616299) (xy 22.55447 -43.579822) (xy 22.497899 -43.536761) (xy 22.446488 -43.487657)
			(xy 22.400878 -43.433121) (xy 22.36164 -43.373835) (xy 22.329263 -43.310541) (xy 22.304153 -43.244028)
			(xy 22.286623 -43.175129) (xy 22.276892 -43.104703) (xy 22.275082 -43.033632) (xy 21.840213 -43.033632)
			(xy 21.844571 -43.079781) (xy 21.843215 -43.151616) (xy 21.833767 -43.222839) (xy 21.816347 -43.292543)
			(xy 21.791177 -43.359837) (xy 21.758579 -43.423863) (xy 21.718967 -43.483804) (xy 21.672848 -43.538896)
			(xy 21.62081 -43.588435) (xy 21.563518 -43.631789) (xy 21.501701 -43.668405) (xy 21.436149 -43.697817)
			(xy 21.367699 -43.719647) (xy 21.297223 -43.733619) (xy 21.225621 -43.739553) (xy 21.153807 -43.737375)
			(xy 21.082696 -43.727111) (xy 21.013197 -43.708893) (xy 20.946196 -43.682953) (xy 20.882548 -43.649623)
			(xy 20.823064 -43.609326) (xy 20.768505 -43.562579) (xy 20.743672 -43.536616) (xy 20.728494 -43.520915)
			(xy 20.693707 -43.494517) (xy 20.654919 -43.474458) (xy 20.613271 -43.461329) (xy 20.569991 -43.455517)
			(xy 20.526354 -43.457193) (xy 20.483648 -43.466308) (xy 20.443129 -43.482593) (xy 20.405993 -43.505569)
			(xy 20.373335 -43.534557) (xy 20.35937 -43.551348) (xy 20.336563 -43.579107) (xy 20.285674 -43.629826)
			(xy 20.22939 -43.674482) (xy 20.16843 -43.712506) (xy 20.103569 -43.743412) (xy 20.035637 -43.766806)
			(xy 19.9655 -43.78239) (xy 19.894053 -43.789964) (xy 19.822208 -43.789433) (xy 19.750881 -43.780802)
			(xy 19.680982 -43.764182) (xy 19.613404 -43.739785) (xy 19.549008 -43.707922) (xy 19.488617 -43.669001)
			(xy 19.433 -43.623516) (xy 19.382868 -43.57205) (xy 19.33886 -43.515258) (xy 19.301537 -43.453865)
			(xy 19.271377 -43.388655) (xy 19.248763 -43.320459) (xy 19.233984 -43.250148) (xy 19.227229 -43.178619)
			(xy 18.517089 -43.178619) (xy 18.517108 -43.18) (xy 18.516608 -43.215661) (xy 18.508622 -43.286535)
			(xy 18.492752 -43.35607) (xy 18.469195 -43.42339) (xy 18.43825 -43.487649) (xy 18.400304 -43.54804)
			(xy 18.355835 -43.603802) (xy 18.305402 -43.654235) (xy 18.24964 -43.698704) (xy 18.189249 -43.73665)
			(xy 18.12499 -43.767595) (xy 18.05767 -43.791152) (xy 17.988135 -43.807022) (xy 17.917261 -43.815008)
			(xy 17.845939 -43.815008) (xy 17.775065 -43.807022) (xy 17.70553 -43.791152) (xy 17.63821 -43.767595)
			(xy 17.573951 -43.73665) (xy 17.51356 -43.698704) (xy 17.457798 -43.654235) (xy 17.407365 -43.603802)
			(xy 17.362896 -43.54804) (xy 17.32495 -43.487649) (xy 17.294005 -43.42339) (xy 17.270448 -43.35607)
			(xy 17.254578 -43.286535) (xy 17.246592 -43.215661) (xy 16.430946 -43.215661) (xy 16.425822 -43.261135)
			(xy 16.409952 -43.33067) (xy 16.386395 -43.39799) (xy 16.35545 -43.462249) (xy 16.317504 -43.52264)
			(xy 16.273035 -43.578402) (xy 16.222602 -43.628835) (xy 16.16684 -43.673304) (xy 16.106449 -43.71125)
			(xy 16.04219 -43.742195) (xy 15.97487 -43.765752) (xy 15.905335 -43.781622) (xy 15.834461 -43.789608)
			(xy 15.763139 -43.789608) (xy 15.692265 -43.781622) (xy 15.62273 -43.765752) (xy 15.55541 -43.742195)
			(xy 15.491151 -43.71125) (xy 15.43076 -43.673304) (xy 15.374998 -43.628835) (xy 15.324565 -43.578402)
			(xy 15.280096 -43.52264) (xy 15.24215 -43.462249) (xy 15.211205 -43.39799) (xy 15.187648 -43.33067)
			(xy 15.171778 -43.261135) (xy 15.163792 -43.190261) (xy 14.132967 -43.190261) (xy 14.123541 -43.230875)
			(xy 14.100157 -43.297244) (xy 14.069587 -43.360623) (xy 14.032203 -43.420239) (xy 13.988463 -43.47536)
			(xy 13.938903 -43.525313) (xy 13.884129 -43.569487) (xy 13.824811 -43.60734) (xy 13.761674 -43.63841)
			(xy 13.695493 -43.662317) (xy 13.66139 -43.670982) (xy 13.639675 -43.676699) (xy 13.598545 -43.694712)
			(xy 13.561222 -43.719673) (xy 13.528867 -43.750805) (xy 13.502487 -43.787139) (xy 13.482903 -43.827544)
			(xy 13.470726 -43.870762) (xy 13.466334 -43.915448) (xy 13.469864 -43.960209) (xy 13.481206 -44.003654)
			(xy 13.500007 -44.044429) (xy 13.525682 -44.081265) (xy 13.541248 -44.097448) (xy 13.7922 -44.3484)
			(xy 47.9044 -44.3484) (xy 48.146716 -44.106084) (xy 48.161889 -44.090265) (xy 48.187108 -44.054419)
			(xy 48.205801 -44.014776) (xy 48.217411 -43.972513) (xy 48.221596 -43.928884) (xy 48.21823 -43.885184)
			(xy 48.207413 -43.842711) (xy 48.189467 -43.802725) (xy 48.164924 -43.766412) (xy 48.134512 -43.734851)
			(xy 48.099135 -43.708977) (xy 48.07966 -43.698922) (xy 48.048087 -43.682752) (xy 47.988405 -43.644405)
			(xy 47.933364 -43.599652) (xy 47.883648 -43.549048) (xy 47.839875 -43.493224) (xy 47.80259 -43.432874)
			(xy 47.772255 -43.368748) (xy 47.749249 -43.301642) (xy 47.733857 -43.232393) (xy 47.72627 -43.161861)
			(xy 47.726584 -43.090922) (xy 47.734794 -43.020459) (xy 47.750798 -42.951349) (xy 47.774397 -42.88445)
			(xy 47.805297 -42.820594) (xy 47.843115 -42.760576) (xy 47.88738 -42.705141) (xy 47.937541 -42.65498)
			(xy 47.992976 -42.610715) (xy 48.052994 -42.572897) (xy 48.11685 -42.541997) (xy 48.183749 -42.518398)
			(xy 48.252859 -42.502394) (xy 48.323322 -42.494184) (xy 48.394261 -42.49387) (xy 48.464793 -42.501457)
			(xy 48.534042 -42.516849) (xy 48.601148 -42.539855) (xy 48.665274 -42.57019) (xy 48.725624 -42.607475)
			(xy 48.781448 -42.651248) (xy 48.832052 -42.700964) (xy 48.876805 -42.756005) (xy 48.915152 -42.815687)
			(xy 48.931322 -42.84726) (xy 48.941445 -42.866698) (xy 48.967318 -42.902067) (xy 48.998876 -42.932473)
			(xy 49.035183 -42.957013) (xy 49.075162 -42.97496) (xy 49.117627 -42.985781) (xy 49.161319 -42.989157)
			(xy 49.204943 -42.984986) (xy 49.247204 -42.973392) (xy 49.286849 -42.954719) (xy 49.322702 -42.929521)
			(xy 49.338484 -42.914316) (xy 52.0446 -40.2082) (xy 53.481732 -40.2082) (xy 53.504449 -40.207695)
			(xy 53.549157 -40.199615) (xy 53.591718 -40.183717) (xy 53.630776 -40.160508) (xy 53.665088 -40.130727)
			(xy 53.69356 -40.095322) (xy 53.715286 -40.05542) (xy 53.729574 -40.012292) (xy 53.735971 -39.967311)
			(xy 53.73427 -39.92191) (xy 53.724528 -39.877533) (xy 53.707054 -39.835595) (xy 53.695092 -39.816278)
			(xy 53.676053 -39.785878) (xy 53.644181 -39.721614) (xy 53.619747 -39.65417) (xy 53.603064 -39.584403)
			(xy 53.594343 -39.513202) (xy 53.593695 -39.441471) (xy 53.601128 -39.370124) (xy 53.616548 -39.300067)
			(xy 53.639759 -39.232193) (xy 53.670466 -39.167364) (xy 53.708277 -39.106404) (xy 53.752712 -39.050091)
			(xy 53.803205 -38.999139) (xy 53.859115 -38.954197) (xy 53.91973 -38.915837) (xy 53.98428 -38.884546)
			(xy 54.051942 -38.860723) (xy 54.121856 -38.84467) (xy 54.193133 -38.836593) (xy 54.264867 -38.836593)
			(xy 54.336144 -38.84467) (xy 54.406058 -38.860723) (xy 54.47372 -38.884546) (xy 54.53827 -38.915837)
			(xy 54.598885 -38.954197) (xy 54.654795 -38.999139) (xy 54.705288 -39.050091) (xy 54.749723 -39.106404)
			(xy 54.787534 -39.167364) (xy 54.818241 -39.232193) (xy 54.841452 -39.300067) (xy 54.856872 -39.370124)
			(xy 54.864305 -39.441471) (xy 54.863657 -39.513202) (xy 54.854936 -39.584403) (xy 54.838253 -39.65417)
			(xy 54.813819 -39.721614) (xy 54.781947 -39.785878) (xy 54.762908 -39.816278) (xy 54.750994 -39.835628)
			(xy 54.7335 -39.87756) (xy 54.72374 -39.921934) (xy 54.722026 -39.967337) (xy 54.728412 -40.012321)
			(xy 54.742694 -40.055453) (xy 54.764419 -40.095358) (xy 54.792892 -40.130765) (xy 54.827207 -40.160545)
			(xy 54.86627 -40.183749) (xy 54.908837 -40.199637) (xy 54.95355 -40.207704) (xy 54.976268 -40.2082)
			(xy 56.8452 -40.2082) (xy 57.160261 -40.523261) (xy 63.423792 -40.523261) (xy 63.423792 -40.451939)
			(xy 63.431778 -40.381065) (xy 63.447648 -40.31153) (xy 63.471205 -40.24421) (xy 63.50215 -40.179951)
			(xy 63.540096 -40.11956) (xy 63.584565 -40.063798) (xy 63.634998 -40.013365) (xy 63.69076 -39.968896)
			(xy 63.751151 -39.93095) (xy 63.81541 -39.900005) (xy 63.88273 -39.876448) (xy 63.952265 -39.860578)
			(xy 64.023139 -39.852592) (xy 64.094461 -39.852592) (xy 64.165335 -39.860578) (xy 64.23487 -39.876448)
			(xy 64.30219 -39.900005) (xy 64.366449 -39.93095) (xy 64.42684 -39.968896) (xy 64.482602 -40.013365)
			(xy 64.533035 -40.063798) (xy 64.577504 -40.11956) (xy 64.61545 -40.179951) (xy 64.646395 -40.24421)
			(xy 64.669952 -40.31153) (xy 64.685822 -40.381065) (xy 64.693808 -40.451939) (xy 64.694308 -40.4876)
			(xy 64.693808 -40.523261) (xy 64.685822 -40.594135) (xy 64.678809 -40.624861) (xy 70.484992 -40.624861)
			(xy 70.484992 -40.553539) (xy 70.492978 -40.482665) (xy 70.508848 -40.41313) (xy 70.532405 -40.34581)
			(xy 70.56335 -40.281551) (xy 70.601296 -40.22116) (xy 70.645765 -40.165398) (xy 70.696198 -40.114965)
			(xy 70.75196 -40.070496) (xy 70.812351 -40.03255) (xy 70.87661 -40.001605) (xy 70.94393 -39.978048)
			(xy 71.013465 -39.962178) (xy 71.084339 -39.954192) (xy 71.155661 -39.954192) (xy 71.226535 -39.962178)
			(xy 71.29607 -39.978048) (xy 71.36339 -40.001605) (xy 71.427649 -40.03255) (xy 71.48804 -40.070496)
			(xy 71.543802 -40.114965) (xy 71.594235 -40.165398) (xy 71.638704 -40.22116) (xy 71.67665 -40.281551)
			(xy 71.707595 -40.34581) (xy 71.731152 -40.41313) (xy 71.747022 -40.482665) (xy 71.755008 -40.553539)
			(xy 71.755508 -40.5892) (xy 71.755008 -40.624861) (xy 71.747022 -40.695735) (xy 71.731152 -40.76527)
			(xy 71.707595 -40.83259) (xy 71.67665 -40.896849) (xy 71.638704 -40.95724) (xy 71.594235 -41.013002)
			(xy 71.543802 -41.063435) (xy 71.48804 -41.107904) (xy 71.427649 -41.14585) (xy 71.36339 -41.176795)
			(xy 71.29607 -41.200352) (xy 71.226535 -41.216222) (xy 71.155661 -41.224208) (xy 71.084339 -41.224208)
			(xy 71.013465 -41.216222) (xy 70.94393 -41.200352) (xy 70.87661 -41.176795) (xy 70.812351 -41.14585)
			(xy 70.75196 -41.107904) (xy 70.696198 -41.063435) (xy 70.645765 -41.013002) (xy 70.601296 -40.95724)
			(xy 70.56335 -40.896849) (xy 70.532405 -40.83259) (xy 70.508848 -40.76527) (xy 70.492978 -40.695735)
			(xy 70.484992 -40.624861) (xy 64.678809 -40.624861) (xy 64.669952 -40.66367) (xy 64.646395 -40.73099)
			(xy 64.61545 -40.795249) (xy 64.577504 -40.85564) (xy 64.533035 -40.911402) (xy 64.482602 -40.961835)
			(xy 64.42684 -41.006304) (xy 64.366449 -41.04425) (xy 64.30219 -41.075195) (xy 64.23487 -41.098752)
			(xy 64.165335 -41.114622) (xy 64.094461 -41.122608) (xy 64.023139 -41.122608) (xy 63.952265 -41.114622)
			(xy 63.88273 -41.098752) (xy 63.81541 -41.075195) (xy 63.751151 -41.04425) (xy 63.69076 -41.006304)
			(xy 63.634998 -40.961835) (xy 63.584565 -40.911402) (xy 63.540096 -40.85564) (xy 63.50215 -40.795249)
			(xy 63.471205 -40.73099) (xy 63.447648 -40.66367) (xy 63.431778 -40.594135) (xy 63.423792 -40.523261)
			(xy 57.160261 -40.523261) (xy 58.1279 -41.4909) (xy 58.1279 -45.730261) (xy 63.576192 -45.730261)
			(xy 63.576192 -45.658939) (xy 63.584178 -45.588065) (xy 63.600048 -45.51853) (xy 63.623605 -45.45121)
			(xy 63.65455 -45.386951) (xy 63.692496 -45.32656) (xy 63.736965 -45.270798) (xy 63.787398 -45.220365)
			(xy 63.84316 -45.175896) (xy 63.903551 -45.13795) (xy 63.96781 -45.107005) (xy 64.03513 -45.083448)
			(xy 64.104665 -45.067578) (xy 64.175539 -45.059592) (xy 64.246861 -45.059592) (xy 64.317735 -45.067578)
			(xy 64.38727 -45.083448) (xy 64.45459 -45.107005) (xy 64.518849 -45.13795) (xy 64.57924 -45.175896)
			(xy 64.635002 -45.220365) (xy 64.685435 -45.270798) (xy 64.729904 -45.32656) (xy 64.76785 -45.386951)
			(xy 64.798795 -45.45121) (xy 64.822352 -45.51853) (xy 64.838222 -45.588065) (xy 64.846208 -45.658939)
			(xy 64.846708 -45.6946) (xy 64.846208 -45.730261) (xy 64.838222 -45.801135) (xy 64.822352 -45.87067)
			(xy 64.80038 -45.933461) (xy 70.738992 -45.933461) (xy 70.738992 -45.862139) (xy 70.746978 -45.791265)
			(xy 70.762848 -45.72173) (xy 70.786405 -45.65441) (xy 70.81735 -45.590151) (xy 70.855296 -45.52976)
			(xy 70.899765 -45.473998) (xy 70.950198 -45.423565) (xy 71.00596 -45.379096) (xy 71.066351 -45.34115)
			(xy 71.13061 -45.310205) (xy 71.19793 -45.286648) (xy 71.267465 -45.270778) (xy 71.338339 -45.262792)
			(xy 71.409661 -45.262792) (xy 71.480535 -45.270778) (xy 71.55007 -45.286648) (xy 71.61739 -45.310205)
			(xy 71.681649 -45.34115) (xy 71.74204 -45.379096) (xy 71.797802 -45.423565) (xy 71.848235 -45.473998)
			(xy 71.892704 -45.52976) (xy 71.93065 -45.590151) (xy 71.961595 -45.65441) (xy 71.985152 -45.72173)
			(xy 72.001022 -45.791265) (xy 72.009008 -45.862139) (xy 72.009508 -45.8978) (xy 72.009008 -45.933461)
			(xy 72.001022 -46.004335) (xy 71.985152 -46.07387) (xy 71.961595 -46.14119) (xy 71.93065 -46.205449)
			(xy 71.892704 -46.26584) (xy 71.848235 -46.321602) (xy 71.797802 -46.372035) (xy 71.74204 -46.416504)
			(xy 71.681649 -46.45445) (xy 71.61739 -46.485395) (xy 71.55007 -46.508952) (xy 71.480535 -46.524822)
			(xy 71.409661 -46.532808) (xy 71.338339 -46.532808) (xy 71.267465 -46.524822) (xy 71.19793 -46.508952)
			(xy 71.13061 -46.485395) (xy 71.066351 -46.45445) (xy 71.00596 -46.416504) (xy 70.950198 -46.372035)
			(xy 70.899765 -46.321602) (xy 70.855296 -46.26584) (xy 70.81735 -46.205449) (xy 70.786405 -46.14119)
			(xy 70.762848 -46.07387) (xy 70.746978 -46.004335) (xy 70.738992 -45.933461) (xy 64.80038 -45.933461)
			(xy 64.798795 -45.93799) (xy 64.76785 -46.002249) (xy 64.729904 -46.06264) (xy 64.685435 -46.118402)
			(xy 64.635002 -46.168835) (xy 64.57924 -46.213304) (xy 64.518849 -46.25125) (xy 64.45459 -46.282195)
			(xy 64.38727 -46.305752) (xy 64.317735 -46.321622) (xy 64.246861 -46.329608) (xy 64.175539 -46.329608)
			(xy 64.104665 -46.321622) (xy 64.03513 -46.305752) (xy 63.96781 -46.282195) (xy 63.903551 -46.25125)
			(xy 63.84316 -46.213304) (xy 63.787398 -46.168835) (xy 63.736965 -46.118402) (xy 63.692496 -46.06264)
			(xy 63.65455 -46.002249) (xy 63.623605 -45.93799) (xy 63.600048 -45.87067) (xy 63.584178 -45.801135)
			(xy 63.576192 -45.730261) (xy 58.1279 -45.730261) (xy 58.1279 -49.0347) (xy 59.5884 -50.4952) (xy 77.232764 -50.4952)
			(xy 77.255761 -50.494706) (xy 77.301005 -50.486436) (xy 77.344023 -50.470159) (xy 77.383409 -50.446407)
			(xy 77.417877 -50.415954) (xy 77.446303 -50.379796) (xy 77.467759 -50.339113) (xy 77.481543 -50.295234)
			(xy 77.487206 -50.24959) (xy 77.484562 -50.203672) (xy 77.473699 -50.158979) (xy 77.454971 -50.116971)
			(xy 77.428989 -50.079019) (xy 77.413104 -50.062384) (xy 77.352242 -50.004773) (xy 77.235447 -49.884562)
			(xy 77.124525 -49.758911) (xy 77.01973 -49.628107) (xy 76.9213 -49.492447) (xy 76.829461 -49.352242)
			(xy 76.744422 -49.207812) (xy 76.666377 -49.059485) (xy 76.595504 -48.907601) (xy 76.531964 -48.752506)
			(xy 76.475903 -48.594553) (xy 76.427448 -48.434104) (xy 76.386711 -48.271524) (xy 76.353784 -48.107184)
			(xy 76.328741 -47.941459) (xy 76.311641 -47.774728) (xy 76.302523 -47.60737) (xy 76.301406 -47.439767)
			(xy 76.308294 -47.272303) (xy 76.323171 -47.105358) (xy 76.346004 -46.939314) (xy 76.376738 -46.77455)
			(xy 76.415306 -46.611442) (xy 76.437998 -46.530768) (xy 76.461963 -46.449231) (xy 76.516771 -46.28834)
			(xy 76.579305 -46.130293) (xy 76.649419 -45.975458) (xy 76.726947 -45.8242) (xy 76.811709 -45.676874)
			(xy 76.903505 -45.533825) (xy 77.002121 -45.395389) (xy 77.107324 -45.26189) (xy 77.218868 -45.133642)
			(xy 77.336491 -45.010945) (xy 77.397864 -44.952158) (xy 77.421653 -44.92886) (xy 77.463365 -44.876958)
			(xy 77.497684 -44.819897) (xy 77.523982 -44.758725) (xy 77.541776 -44.694561) (xy 77.550741 -44.628581)
			(xy 77.55128 -44.595288) (xy 77.55128 -41.500044) (xy 77.551776 -41.433093) (xy 77.559709 -41.299426)
			(xy 77.575546 -41.166463) (xy 77.599232 -41.034673) (xy 77.630683 -40.904517) (xy 77.669791 -40.776453)
			(xy 77.716415 -40.65093) (xy 77.770395 -40.52839) (xy 77.831538 -40.409263) (xy 77.899632 -40.293967)
			(xy 77.974436 -40.182908) (xy 78.055688 -40.076475) (xy 78.143102 -39.975043) (xy 78.236372 -39.878967)
			(xy 78.335169 -39.788585) (xy 78.439148 -39.704215) (xy 78.547941 -39.626153) (xy 78.661168 -39.554673)
			(xy 78.778431 -39.490026) (xy 78.899318 -39.432439) (xy 79.023404 -39.382115) (xy 79.150253 -39.33923)
			(xy 79.27942 -39.303935) (xy 79.410451 -39.276354) (xy 79.542885 -39.256584) (xy 79.676259 -39.244694)
			(xy 79.810102 -39.240726) (xy 79.943945 -39.244694) (xy 80.077319 -39.256584) (xy 80.209753 -39.276354)
			(xy 80.340784 -39.303935) (xy 80.469951 -39.33923) (xy 80.5968 -39.382115) (xy 80.720886 -39.432439)
			(xy 80.841773 -39.490026) (xy 80.959036 -39.554673) (xy 81.072263 -39.626153) (xy 81.181056 -39.704215)
			(xy 81.285035 -39.788585) (xy 81.383832 -39.878967) (xy 81.477102 -39.975043) (xy 81.564516 -40.076475)
			(xy 81.645768 -40.182908) (xy 81.720572 -40.293967) (xy 81.788666 -40.409263) (xy 81.849809 -40.52839)
			(xy 81.903789 -40.65093) (xy 81.950413 -40.776453) (xy 81.989521 -40.904517) (xy 82.020972 -41.034673)
			(xy 82.038619 -41.132861) (xy 88.264992 -41.132861) (xy 88.264992 -41.061539) (xy 88.272978 -40.990665)
			(xy 88.288848 -40.92113) (xy 88.312405 -40.85381) (xy 88.34335 -40.789551) (xy 88.381296 -40.72916)
			(xy 88.425765 -40.673398) (xy 88.476198 -40.622965) (xy 88.53196 -40.578496) (xy 88.592351 -40.54055)
			(xy 88.65661 -40.509605) (xy 88.72393 -40.486048) (xy 88.793465 -40.470178) (xy 88.864339 -40.462192)
			(xy 88.935661 -40.462192) (xy 89.006535 -40.470178) (xy 89.07607 -40.486048) (xy 89.14339 -40.509605)
			(xy 89.207649 -40.54055) (xy 89.26804 -40.578496) (xy 89.323802 -40.622965) (xy 89.374235 -40.673398)
			(xy 89.418704 -40.72916) (xy 89.45665 -40.789551) (xy 89.487595 -40.85381) (xy 89.511152 -40.92113)
			(xy 89.527022 -40.990665) (xy 89.535008 -41.061539) (xy 89.535508 -41.0972) (xy 89.535008 -41.132861)
			(xy 89.527022 -41.203735) (xy 89.511152 -41.27327) (xy 89.487595 -41.34059) (xy 89.45665 -41.404849)
			(xy 89.418704 -41.46524) (xy 89.374235 -41.521002) (xy 89.323802 -41.571435) (xy 89.26804 -41.615904)
			(xy 89.207649 -41.65385) (xy 89.14339 -41.684795) (xy 89.07607 -41.708352) (xy 89.006535 -41.724222)
			(xy 88.935661 -41.732208) (xy 88.864339 -41.732208) (xy 88.793465 -41.724222) (xy 88.72393 -41.708352)
			(xy 88.65661 -41.684795) (xy 88.592351 -41.65385) (xy 88.53196 -41.615904) (xy 88.476198 -41.571435)
			(xy 88.425765 -41.521002) (xy 88.381296 -41.46524) (xy 88.34335 -41.404849) (xy 88.312405 -41.34059)
			(xy 88.288848 -41.27327) (xy 88.272978 -41.203735) (xy 88.264992 -41.132861) (xy 82.038619 -41.132861)
			(xy 82.044658 -41.166463) (xy 82.060495 -41.299426) (xy 82.068428 -41.433093) (xy 82.068924 -41.500044)
			(xy 82.068924 -44.595288) (xy 82.069457 -44.628583) (xy 82.078412 -44.694568) (xy 82.096199 -44.758738)
			(xy 82.122492 -44.819916) (xy 82.15681 -44.876981) (xy 82.198523 -44.928887) (xy 82.202771 -44.933038)
			(xy 115.78564 -44.933038) (xy 115.78564 -44.805162) (xy 115.793669 -44.677538) (xy 115.809697 -44.55067)
			(xy 115.833658 -44.425058) (xy 115.86546 -44.3012) (xy 115.904976 -44.179582) (xy 115.95205 -44.060685)
			(xy 116.006497 -43.944979) (xy 116.068102 -43.83292) (xy 116.136622 -43.724951) (xy 116.211786 -43.621497)
			(xy 116.293297 -43.522966) (xy 116.380834 -43.429748) (xy 116.474052 -43.342211) (xy 116.572583 -43.2607)
			(xy 116.676037 -43.185536) (xy 116.784006 -43.117016) (xy 116.896065 -43.055411) (xy 117.011771 -43.000964)
			(xy 117.130668 -42.95389) (xy 117.252286 -42.914374) (xy 117.376144 -42.882572) (xy 117.501756 -42.858611)
			(xy 117.628624 -42.842583) (xy 117.756248 -42.834554) (xy 117.884124 -42.834554) (xy 118.011748 -42.842583)
			(xy 118.138616 -42.858611) (xy 118.264228 -42.882572) (xy 118.388086 -42.914374) (xy 118.509704 -42.95389)
			(xy 118.628601 -43.000964) (xy 118.744307 -43.055411) (xy 118.856366 -43.117016) (xy 118.964335 -43.185536)
			(xy 119.067789 -43.2607) (xy 119.16632 -43.342211) (xy 119.259538 -43.429748) (xy 119.347075 -43.522966)
			(xy 119.428586 -43.621497) (xy 119.50375 -43.724951) (xy 119.57227 -43.83292) (xy 119.633875 -43.944979)
			(xy 119.688322 -44.060685) (xy 119.735396 -44.179582) (xy 119.774912 -44.3012) (xy 119.806714 -44.425058)
			(xy 119.830675 -44.55067) (xy 119.846703 -44.677538) (xy 119.854732 -44.805162) (xy 119.855234 -44.8691)
			(xy 119.854732 -44.932982) (xy 127.217418 -44.932982) (xy 127.217418 -44.805218) (xy 127.22544 -44.677705)
			(xy 127.241453 -44.550948) (xy 127.265394 -44.425446) (xy 127.297168 -44.301696) (xy 127.336649 -44.180184)
			(xy 127.383682 -44.061392) (xy 127.438082 -43.945787) (xy 127.499633 -43.833826) (xy 127.568093 -43.725951)
			(xy 127.643191 -43.622587) (xy 127.724631 -43.524142) (xy 127.812092 -43.431006) (xy 127.905228 -43.343545)
			(xy 128.003673 -43.262105) (xy 128.107037 -43.187007) (xy 128.214912 -43.118547) (xy 128.326873 -43.056996)
			(xy 128.442478 -43.002596) (xy 128.56127 -42.955563) (xy 128.682782 -42.916082) (xy 128.806532 -42.884308)
			(xy 128.932034 -42.860367) (xy 129.058791 -42.844354) (xy 129.186304 -42.836332) (xy 129.314068 -42.836332)
			(xy 129.441581 -42.844354) (xy 129.568338 -42.860367) (xy 129.69384 -42.884308) (xy 129.81759 -42.916082)
			(xy 129.939102 -42.955563) (xy 130.057894 -43.002596) (xy 130.173499 -43.056996) (xy 130.28546 -43.118547)
			(xy 130.393335 -43.187007) (xy 130.496699 -43.262105) (xy 130.595144 -43.343545) (xy 130.68828 -43.431006)
			(xy 130.775741 -43.524142) (xy 130.857181 -43.622587) (xy 130.932279 -43.725951) (xy 131.000739 -43.833826)
			(xy 131.06229 -43.945787) (xy 131.11669 -44.061392) (xy 131.163723 -44.180184) (xy 131.203204 -44.301696)
			(xy 131.234978 -44.425446) (xy 131.258919 -44.550948) (xy 131.274932 -44.677705) (xy 131.282954 -44.805218)
			(xy 131.283456 -44.8691) (xy 131.282954 -44.932982) (xy 131.274932 -45.060495) (xy 131.258919 -45.187252)
			(xy 131.234978 -45.312754) (xy 131.203204 -45.436504) (xy 131.163723 -45.558016) (xy 131.11669 -45.676808)
			(xy 131.06229 -45.792413) (xy 131.000739 -45.904374) (xy 130.932279 -46.012249) (xy 130.857181 -46.115613)
			(xy 130.775741 -46.214058) (xy 130.68828 -46.307194) (xy 130.595144 -46.394655) (xy 130.496699 -46.476095)
			(xy 130.393335 -46.551193) (xy 130.28546 -46.619653) (xy 130.173499 -46.681204) (xy 130.057894 -46.735604)
			(xy 129.939102 -46.782637) (xy 129.81759 -46.822118) (xy 129.69384 -46.853892) (xy 129.568338 -46.877833)
			(xy 129.441581 -46.893846) (xy 129.314068 -46.901868) (xy 129.186304 -46.901868) (xy 129.058791 -46.893846)
			(xy 128.932034 -46.877833) (xy 128.806532 -46.853892) (xy 128.682782 -46.822118) (xy 128.56127 -46.782637)
			(xy 128.442478 -46.735604) (xy 128.326873 -46.681204) (xy 128.214912 -46.619653) (xy 128.107037 -46.551193)
			(xy 128.003673 -46.476095) (xy 127.905228 -46.394655) (xy 127.812092 -46.307194) (xy 127.724631 -46.214058)
			(xy 127.643191 -46.115613) (xy 127.568093 -46.012249) (xy 127.499633 -45.904374) (xy 127.438082 -45.792413)
			(xy 127.383682 -45.676808) (xy 127.336649 -45.558016) (xy 127.297168 -45.436504) (xy 127.265394 -45.312754)
			(xy 127.241453 -45.187252) (xy 127.22544 -45.060495) (xy 127.217418 -44.932982) (xy 119.854732 -44.932982)
			(xy 119.854732 -44.933038) (xy 119.846703 -45.060662) (xy 119.830675 -45.18753) (xy 119.806714 -45.313142)
			(xy 119.774912 -45.437) (xy 119.735396 -45.558618) (xy 119.688322 -45.677515) (xy 119.633875 -45.793221)
			(xy 119.57227 -45.90528) (xy 119.50375 -46.013249) (xy 119.428586 -46.116703) (xy 119.347075 -46.215234)
			(xy 119.259538 -46.308452) (xy 119.16632 -46.395989) (xy 119.067789 -46.4775) (xy 118.964335 -46.552664)
			(xy 118.856366 -46.621184) (xy 118.744307 -46.682789) (xy 118.628601 -46.737236) (xy 118.509704 -46.78431)
			(xy 118.388086 -46.823826) (xy 118.264228 -46.855628) (xy 118.138616 -46.879589) (xy 118.011748 -46.895617)
			(xy 117.884124 -46.903646) (xy 117.756248 -46.903646) (xy 117.628624 -46.895617) (xy 117.501756 -46.879589)
			(xy 117.376144 -46.855628) (xy 117.252286 -46.823826) (xy 117.130668 -46.78431) (xy 117.011771 -46.737236)
			(xy 116.896065 -46.682789) (xy 116.784006 -46.621184) (xy 116.676037 -46.552664) (xy 116.572583 -46.4775)
			(xy 116.474052 -46.395989) (xy 116.380834 -46.308452) (xy 116.293297 -46.215234) (xy 116.211786 -46.116703)
			(xy 116.136622 -46.013249) (xy 116.068102 -45.90528) (xy 116.006497 -45.793221) (xy 115.95205 -45.677515)
			(xy 115.904976 -45.558618) (xy 115.86546 -45.437) (xy 115.833658 -45.313142) (xy 115.809697 -45.18753)
			(xy 115.793669 -45.060662) (xy 115.78564 -44.933038) (xy 82.202771 -44.933038) (xy 82.22234 -44.952158)
			(xy 82.283703 -45.010956) (xy 82.401325 -45.133652) (xy 82.512869 -45.261899) (xy 82.618071 -45.395398)
			(xy 82.716686 -45.533833) (xy 82.808482 -45.676882) (xy 82.893243 -45.824208) (xy 82.970772 -45.975465)
			(xy 82.997759 -46.035061) (xy 88.315792 -46.035061) (xy 88.315792 -45.963739) (xy 88.323778 -45.892865)
			(xy 88.339648 -45.82333) (xy 88.363205 -45.75601) (xy 88.39415 -45.691751) (xy 88.432096 -45.63136)
			(xy 88.476565 -45.575598) (xy 88.526998 -45.525165) (xy 88.58276 -45.480696) (xy 88.643151 -45.44275)
			(xy 88.70741 -45.411805) (xy 88.77473 -45.388248) (xy 88.844265 -45.372378) (xy 88.915139 -45.364392)
			(xy 88.986461 -45.364392) (xy 89.057335 -45.372378) (xy 89.12687 -45.388248) (xy 89.19419 -45.411805)
			(xy 89.258449 -45.44275) (xy 89.31884 -45.480696) (xy 89.374602 -45.525165) (xy 89.425035 -45.575598)
			(xy 89.469504 -45.63136) (xy 89.50745 -45.691751) (xy 89.538395 -45.75601) (xy 89.561952 -45.82333)
			(xy 89.577822 -45.892865) (xy 89.585808 -45.963739) (xy 89.586308 -45.9994) (xy 89.585808 -46.035061)
			(xy 89.577822 -46.105935) (xy 89.561952 -46.17547) (xy 89.538395 -46.24279) (xy 89.50745 -46.307049)
			(xy 89.469504 -46.36744) (xy 89.425035 -46.423202) (xy 89.374602 -46.473635) (xy 89.31884 -46.518104)
			(xy 89.258449 -46.55605) (xy 89.19419 -46.586995) (xy 89.12687 -46.610552) (xy 89.057335 -46.626422)
			(xy 88.986461 -46.634408) (xy 88.915139 -46.634408) (xy 88.844265 -46.626422) (xy 88.77473 -46.610552)
			(xy 88.70741 -46.586995) (xy 88.643151 -46.55605) (xy 88.58276 -46.518104) (xy 88.526998 -46.473635)
			(xy 88.476565 -46.423202) (xy 88.432096 -46.36744) (xy 88.39415 -46.307049) (xy 88.363205 -46.24279)
			(xy 88.339648 -46.17547) (xy 88.323778 -46.105935) (xy 88.315792 -46.035061) (xy 82.997759 -46.035061)
			(xy 83.040885 -46.130298) (xy 83.103419 -46.288346) (xy 83.158226 -46.449235) (xy 83.182206 -46.530768)
			(xy 83.204877 -46.611446) (xy 83.243429 -46.774554) (xy 83.27415 -46.939317) (xy 83.29697 -47.105359)
			(xy 83.311836 -47.272301) (xy 83.318715 -47.439763) (xy 83.317591 -47.607362) (xy 83.308466 -47.774716)
			(xy 83.291362 -47.941443) (xy 83.266317 -48.107164) (xy 83.233389 -48.2715) (xy 83.192652 -48.434077)
			(xy 83.1442 -48.594523) (xy 83.088142 -48.752473) (xy 83.024608 -48.907567) (xy 82.953741 -49.05945)
			(xy 82.875703 -49.207777) (xy 82.790673 -49.352209) (xy 82.698845 -49.492416) (xy 82.600426 -49.628079)
			(xy 82.495644 -49.758889) (xy 82.384735 -49.884547) (xy 82.267953 -50.004767) (xy 82.2071 -50.062384)
			(xy 82.191267 -50.079062) (xy 82.1653 -50.117011) (xy 82.146583 -50.159011) (xy 82.135728 -50.203694)
			(xy 82.133088 -50.249601) (xy 82.13875 -50.295233) (xy 82.15253 -50.339103) (xy 82.173977 -50.379777)
			(xy 82.202391 -50.41593) (xy 82.236846 -50.446381) (xy 82.276216 -50.470137) (xy 82.319219 -50.486422)
			(xy 82.364449 -50.494705) (xy 82.38744 -50.4952) (xy 94.0816 -50.4952) (xy 97.0026 -47.5742) (xy 113.8682 -47.5742)
			(xy 114.229896 -47.935896) (xy 114.345974 -47.935896) (xy 114.370358 -47.925228) (xy 114.42233 -47.903095)
			(xy 114.528738 -47.865143) (xy 114.637492 -47.834553) (xy 114.748081 -47.811467) (xy 114.85999 -47.795992)
			(xy 114.972694 -47.788202) (xy 115.085668 -47.788132) (xy 115.198382 -47.795783) (xy 115.31031 -47.81112)
			(xy 115.420928 -47.83407) (xy 115.529718 -47.864526) (xy 115.636173 -47.902346) (xy 115.739795 -47.947352)
			(xy 115.840098 -47.999336) (xy 115.936615 -48.058052) (xy 116.028892 -48.123228) (xy 116.1165 -48.194557)
			(xy 116.199028 -48.271707) (xy 116.276091 -48.354317) (xy 116.347328 -48.442) (xy 116.412406 -48.534347)
			(xy 116.47102 -48.630925) (xy 116.522897 -48.731283) (xy 116.567794 -48.834952) (xy 116.605502 -48.941447)
			(xy 116.635843 -49.05027) (xy 116.658676 -49.160912) (xy 116.666772 -49.216818) (xy 116.66926 -49.231827)
			(xy 116.680375 -49.260139) (xy 116.697878 -49.285014) (xy 116.720772 -49.305038) (xy 116.747756 -49.319072)
			(xy 116.777295 -49.326319) (xy 116.792502 -49.3268) (xy 130.27787 -49.3268) (xy 130.293092 -49.326368)
			(xy 130.322672 -49.319168) (xy 130.349695 -49.305149) (xy 130.372616 -49.285113) (xy 130.390123 -49.260207)
			(xy 130.401214 -49.231856) (xy 130.4036 -49.216818) (xy 130.411904 -49.159489) (xy 130.435525 -49.046072)
			(xy 130.467037 -48.93459) (xy 130.506284 -48.82559) (xy 130.553074 -48.719609) (xy 130.607177 -48.617168)
			(xy 130.668327 -48.51877) (xy 130.736222 -48.4249) (xy 130.810529 -48.33602) (xy 130.890882 -48.252565)
			(xy 130.976887 -48.174948) (xy 131.068121 -48.103549) (xy 131.164134 -48.03872) (xy 131.264454 -47.980779)
			(xy 131.368588 -47.930011) (xy 131.476025 -47.886667) (xy 131.586235 -47.850959) (xy 131.698676 -47.823063)
			(xy 131.812797 -47.803116) (xy 131.928034 -47.791216) (xy 132.043822 -47.787422) (xy 132.159592 -47.791752)
			(xy 132.274773 -47.804185) (xy 132.3888 -47.82466) (xy 132.501111 -47.853076) (xy 132.611155 -47.889294)
			(xy 132.664962 -47.91075) (xy 132.688076 -47.920148) (xy 132.800852 -47.920148) (xy 133.0198 -47.7012)
			(xy 150.7744 -47.7012) (xy 151.2824 -48.2092) (xy 204.3938 -48.2092) (xy 204.4192 -48.1838) (xy 206.5528 -50.3174)
			(xy 207.05572 -50.3174) (xy 207.0784 -50.316899) (xy 207.123039 -50.308844) (xy 207.16554 -50.292992)
			(xy 207.204551 -50.269847) (xy 207.238835 -50.240145) (xy 207.267301 -50.204829) (xy 207.289046 -50.165021)
			(xy 207.303379 -50.121985) (xy 207.309845 -50.077087) (xy 207.308239 -50.031756) (xy 207.29861 -49.987429)
			(xy 207.281267 -49.945515) (xy 207.256758 -49.907346) (xy 207.241648 -49.890426) (xy 207.18542 -49.829297)
			(xy 207.078133 -49.702481) (xy 206.976968 -49.57073) (xy 206.882151 -49.434339) (xy 206.793896 -49.293614)
			(xy 206.712398 -49.14887) (xy 206.637842 -49.000431) (xy 206.570394 -48.84863) (xy 206.510206 -48.693807)
			(xy 206.457412 -48.53631) (xy 206.41213 -48.37649) (xy 206.374463 -48.214707) (xy 206.344494 -48.051323)
			(xy 206.322291 -47.886703) (xy 206.307903 -47.721217) (xy 206.301362 -47.555235) (xy 206.302684 -47.38913)
			(xy 206.311865 -47.223273) (xy 206.328885 -47.058037) (xy 206.353706 -46.893791) (xy 206.386272 -46.730904)
			(xy 206.426509 -46.569741) (xy 206.474329 -46.410663) (xy 206.529623 -46.254025) (xy 206.592267 -46.10018)
			(xy 206.662123 -45.949472) (xy 206.739032 -45.802239) (xy 206.822823 -45.65881) (xy 206.913307 -45.519507)
			(xy 207.010282 -45.384643) (xy 207.113532 -45.254519) (xy 207.222823 -45.129426) (xy 207.337912 -45.009646)
			(xy 207.397858 -44.952158) (xy 207.416762 -44.93382) (xy 207.450947 -44.893753) (xy 207.480636 -44.850248)
			(xy 207.493362 -44.82719) (xy 207.507203 -44.800347) (xy 207.52896 -44.744007) (xy 207.543654 -44.685425)
			(xy 207.551061 -44.625486) (xy 207.551528 -44.595288) (xy 207.551528 -43.047666) (xy 207.551274 -41.500044)
			(xy 207.551778 -41.431804) (xy 207.560016 -41.295573) (xy 207.576464 -41.160088) (xy 207.601063 -41.025843)
			(xy 207.633723 -40.893328) (xy 207.674324 -40.763027) (xy 207.722718 -40.635415) (xy 207.77873 -40.510958)
			(xy 207.842153 -40.39011) (xy 207.912758 -40.273312) (xy 207.990286 -40.16099) (xy 208.074455 -40.053554)
			(xy 208.164957 -39.951397) (xy 208.261462 -39.85489) (xy 208.363617 -39.764386) (xy 208.471052 -39.680215)
			(xy 208.583372 -39.602684) (xy 208.700168 -39.532077) (xy 208.821015 -39.468651) (xy 208.945471 -39.412637)
			(xy 209.073081 -39.36424) (xy 209.203382 -39.323636) (xy 209.335896 -39.290973) (xy 209.47014 -39.266371)
			(xy 209.605625 -39.24992) (xy 209.741856 -39.241679) (xy 209.810096 -39.241222) (xy 209.878333 -39.241727)
			(xy 210.014557 -39.249968) (xy 210.150035 -39.266418) (xy 210.284272 -39.29102) (xy 210.416779 -39.323682)
			(xy 210.547072 -39.364286) (xy 210.674675 -39.412683) (xy 210.799123 -39.468696) (xy 210.919962 -39.532123)
			(xy 211.036751 -39.602729) (xy 211.149063 -39.68026) (xy 211.256488 -39.76443) (xy 211.358635 -39.854933)
			(xy 211.455131 -39.951439) (xy 211.545624 -40.053596) (xy 211.629783 -40.161031) (xy 211.707301 -40.273351)
			(xy 211.777895 -40.390147) (xy 211.841309 -40.510993) (xy 211.897309 -40.635447) (xy 211.945693 -40.763055)
			(xy 211.986282 -40.893352) (xy 212.018931 -41.025863) (xy 212.043518 -41.160103) (xy 212.059954 -41.295582)
			(xy 212.06818 -41.431807) (xy 212.068664 -41.500044) (xy 212.068664 -44.595288) (xy 212.069125 -44.625486)
			(xy 212.076528 -44.685427) (xy 212.091224 -44.744008) (xy 212.112991 -44.800345) (xy 212.12683 -44.82719)
			(xy 212.13958 -44.850233) (xy 212.169282 -44.893724) (xy 212.203451 -44.933801) (xy 212.222334 -44.952158)
			(xy 212.282312 -45.009613) (xy 212.397397 -45.129398) (xy 212.506684 -45.254494) (xy 212.609929 -45.384622)
			(xy 212.706901 -45.51949) (xy 212.797381 -45.658795) (xy 212.881169 -45.802226) (xy 212.958075 -45.949462)
			(xy 213.027927 -46.100172) (xy 213.090569 -46.254018) (xy 213.145861 -46.410657) (xy 213.193678 -46.569737)
			(xy 213.233914 -46.730901) (xy 213.266478 -46.893788) (xy 213.291297 -47.058035) (xy 213.308316 -47.223271)
			(xy 213.317497 -47.389128) (xy 213.318819 -47.555234) (xy 213.312279 -47.721216) (xy 213.297892 -47.886703)
			(xy 213.27569 -48.051323) (xy 213.245722 -48.214708) (xy 213.238702 -48.244861) (xy 217.042992 -48.244861)
			(xy 217.042992 -48.173539) (xy 217.050978 -48.102665) (xy 217.066848 -48.03313) (xy 217.090405 -47.96581)
			(xy 217.12135 -47.901551) (xy 217.159296 -47.84116) (xy 217.203765 -47.785398) (xy 217.254198 -47.734965)
			(xy 217.30996 -47.690496) (xy 217.370351 -47.65255) (xy 217.43461 -47.621605) (xy 217.50193 -47.598048)
			(xy 217.571465 -47.582178) (xy 217.642339 -47.574192) (xy 217.713661 -47.574192) (xy 217.784535 -47.582178)
			(xy 217.85407 -47.598048) (xy 217.92139 -47.621605) (xy 217.985649 -47.65255) (xy 218.04604 -47.690496)
			(xy 218.101802 -47.734965) (xy 218.152235 -47.785398) (xy 218.196704 -47.84116) (xy 218.23465 -47.901551)
			(xy 218.265595 -47.96581) (xy 218.289152 -48.03313) (xy 218.305022 -48.102665) (xy 218.313008 -48.173539)
			(xy 218.313508 -48.2092) (xy 218.313008 -48.244861) (xy 224.662992 -48.244861) (xy 224.662992 -48.173539)
			(xy 224.670978 -48.102665) (xy 224.686848 -48.03313) (xy 224.710405 -47.96581) (xy 224.74135 -47.901551)
			(xy 224.779296 -47.84116) (xy 224.823765 -47.785398) (xy 224.874198 -47.734965) (xy 224.92996 -47.690496)
			(xy 224.990351 -47.65255) (xy 225.05461 -47.621605) (xy 225.12193 -47.598048) (xy 225.191465 -47.582178)
			(xy 225.262339 -47.574192) (xy 225.333661 -47.574192) (xy 225.404535 -47.582178) (xy 225.47407 -47.598048)
			(xy 225.54139 -47.621605) (xy 225.605649 -47.65255) (xy 225.66604 -47.690496) (xy 225.721802 -47.734965)
			(xy 225.772235 -47.785398) (xy 225.816704 -47.84116) (xy 225.85465 -47.901551) (xy 225.885595 -47.96581)
			(xy 225.909152 -48.03313) (xy 225.925022 -48.102665) (xy 225.933008 -48.173539) (xy 225.933508 -48.2092)
			(xy 225.933008 -48.244861) (xy 232.282992 -48.244861) (xy 232.282992 -48.173539) (xy 232.290978 -48.102665)
			(xy 232.306848 -48.03313) (xy 232.330405 -47.96581) (xy 232.36135 -47.901551) (xy 232.399296 -47.84116)
			(xy 232.443765 -47.785398) (xy 232.494198 -47.734965) (xy 232.54996 -47.690496) (xy 232.610351 -47.65255)
			(xy 232.67461 -47.621605) (xy 232.74193 -47.598048) (xy 232.811465 -47.582178) (xy 232.882339 -47.574192)
			(xy 232.953661 -47.574192) (xy 233.024535 -47.582178) (xy 233.09407 -47.598048) (xy 233.16139 -47.621605)
			(xy 233.225649 -47.65255) (xy 233.28604 -47.690496) (xy 233.341802 -47.734965) (xy 233.392235 -47.785398)
			(xy 233.436704 -47.84116) (xy 233.47465 -47.901551) (xy 233.505595 -47.96581) (xy 233.529152 -48.03313)
			(xy 233.545022 -48.102665) (xy 233.553008 -48.173539) (xy 233.553508 -48.2092) (xy 233.553008 -48.244861)
			(xy 239.902992 -48.244861) (xy 239.902992 -48.173539) (xy 239.910978 -48.102665) (xy 239.926848 -48.03313)
			(xy 239.950405 -47.96581) (xy 239.98135 -47.901551) (xy 240.019296 -47.84116) (xy 240.063765 -47.785398)
			(xy 240.114198 -47.734965) (xy 240.16996 -47.690496) (xy 240.230351 -47.65255) (xy 240.29461 -47.621605)
			(xy 240.36193 -47.598048) (xy 240.431465 -47.582178) (xy 240.502339 -47.574192) (xy 240.573661 -47.574192)
			(xy 240.644535 -47.582178) (xy 240.71407 -47.598048) (xy 240.78139 -47.621605) (xy 240.845649 -47.65255)
			(xy 240.90604 -47.690496) (xy 240.961802 -47.734965) (xy 241.012235 -47.785398) (xy 241.056704 -47.84116)
			(xy 241.09465 -47.901551) (xy 241.125595 -47.96581) (xy 241.149152 -48.03313) (xy 241.165022 -48.102665)
			(xy 241.173008 -48.173539) (xy 241.173508 -48.2092) (xy 241.173008 -48.244861) (xy 247.522992 -48.244861)
			(xy 247.522992 -48.173539) (xy 247.530978 -48.102665) (xy 247.546848 -48.03313) (xy 247.570405 -47.96581)
			(xy 247.60135 -47.901551) (xy 247.639296 -47.84116) (xy 247.683765 -47.785398) (xy 247.734198 -47.734965)
			(xy 247.78996 -47.690496) (xy 247.850351 -47.65255) (xy 247.91461 -47.621605) (xy 247.98193 -47.598048)
			(xy 248.051465 -47.582178) (xy 248.122339 -47.574192) (xy 248.193661 -47.574192) (xy 248.264535 -47.582178)
			(xy 248.33407 -47.598048) (xy 248.40139 -47.621605) (xy 248.465649 -47.65255) (xy 248.52604 -47.690496)
			(xy 248.581802 -47.734965) (xy 248.632235 -47.785398) (xy 248.676704 -47.84116) (xy 248.71465 -47.901551)
			(xy 248.745595 -47.96581) (xy 248.769152 -48.03313) (xy 248.785022 -48.102665) (xy 248.793008 -48.173539)
			(xy 248.793508 -48.2092) (xy 248.793008 -48.244861) (xy 255.142992 -48.244861) (xy 255.142992 -48.173539)
			(xy 255.150978 -48.102665) (xy 255.166848 -48.03313) (xy 255.190405 -47.96581) (xy 255.22135 -47.901551)
			(xy 255.259296 -47.84116) (xy 255.303765 -47.785398) (xy 255.354198 -47.734965) (xy 255.40996 -47.690496)
			(xy 255.470351 -47.65255) (xy 255.53461 -47.621605) (xy 255.60193 -47.598048) (xy 255.671465 -47.582178)
			(xy 255.742339 -47.574192) (xy 255.813661 -47.574192) (xy 255.884535 -47.582178) (xy 255.95407 -47.598048)
			(xy 256.02139 -47.621605) (xy 256.085649 -47.65255) (xy 256.14604 -47.690496) (xy 256.201802 -47.734965)
			(xy 256.252235 -47.785398) (xy 256.296704 -47.84116) (xy 256.33465 -47.901551) (xy 256.365595 -47.96581)
			(xy 256.389152 -48.03313) (xy 256.405022 -48.102665) (xy 256.413008 -48.173539) (xy 256.413508 -48.2092)
			(xy 256.413008 -48.244861) (xy 262.762992 -48.244861) (xy 262.762992 -48.173539) (xy 262.770978 -48.102665)
			(xy 262.786848 -48.03313) (xy 262.810405 -47.96581) (xy 262.84135 -47.901551) (xy 262.879296 -47.84116)
			(xy 262.923765 -47.785398) (xy 262.974198 -47.734965) (xy 263.02996 -47.690496) (xy 263.090351 -47.65255)
			(xy 263.15461 -47.621605) (xy 263.22193 -47.598048) (xy 263.291465 -47.582178) (xy 263.362339 -47.574192)
			(xy 263.433661 -47.574192) (xy 263.504535 -47.582178) (xy 263.57407 -47.598048) (xy 263.64139 -47.621605)
			(xy 263.705649 -47.65255) (xy 263.76604 -47.690496) (xy 263.821802 -47.734965) (xy 263.872235 -47.785398)
			(xy 263.916704 -47.84116) (xy 263.95465 -47.901551) (xy 263.985595 -47.96581) (xy 264.009152 -48.03313)
			(xy 264.025022 -48.102665) (xy 264.033008 -48.173539) (xy 264.033508 -48.2092) (xy 264.033008 -48.244861)
			(xy 270.382992 -48.244861) (xy 270.382992 -48.173539) (xy 270.390978 -48.102665) (xy 270.406848 -48.03313)
			(xy 270.430405 -47.96581) (xy 270.46135 -47.901551) (xy 270.499296 -47.84116) (xy 270.543765 -47.785398)
			(xy 270.594198 -47.734965) (xy 270.64996 -47.690496) (xy 270.710351 -47.65255) (xy 270.77461 -47.621605)
			(xy 270.84193 -47.598048) (xy 270.911465 -47.582178) (xy 270.982339 -47.574192) (xy 271.053661 -47.574192)
			(xy 271.124535 -47.582178) (xy 271.19407 -47.598048) (xy 271.26139 -47.621605) (xy 271.325649 -47.65255)
			(xy 271.38604 -47.690496) (xy 271.441802 -47.734965) (xy 271.492235 -47.785398) (xy 271.536704 -47.84116)
			(xy 271.57465 -47.901551) (xy 271.605595 -47.96581) (xy 271.629152 -48.03313) (xy 271.645022 -48.102665)
			(xy 271.653008 -48.173539) (xy 271.653508 -48.2092) (xy 271.653008 -48.244861) (xy 278.002992 -48.244861)
			(xy 278.002992 -48.173539) (xy 278.010978 -48.102665) (xy 278.026848 -48.03313) (xy 278.050405 -47.96581)
			(xy 278.08135 -47.901551) (xy 278.119296 -47.84116) (xy 278.163765 -47.785398) (xy 278.214198 -47.734965)
			(xy 278.26996 -47.690496) (xy 278.330351 -47.65255) (xy 278.39461 -47.621605) (xy 278.46193 -47.598048)
			(xy 278.531465 -47.582178) (xy 278.602339 -47.574192) (xy 278.673661 -47.574192) (xy 278.744535 -47.582178)
			(xy 278.81407 -47.598048) (xy 278.88139 -47.621605) (xy 278.945649 -47.65255) (xy 279.00604 -47.690496)
			(xy 279.061802 -47.734965) (xy 279.112235 -47.785398) (xy 279.156704 -47.84116) (xy 279.19465 -47.901551)
			(xy 279.225595 -47.96581) (xy 279.249152 -48.03313) (xy 279.265022 -48.102665) (xy 279.273008 -48.173539)
			(xy 279.273508 -48.2092) (xy 279.273008 -48.244861) (xy 285.622992 -48.244861) (xy 285.622992 -48.173539)
			(xy 285.630978 -48.102665) (xy 285.646848 -48.03313) (xy 285.670405 -47.96581) (xy 285.70135 -47.901551)
			(xy 285.739296 -47.84116) (xy 285.783765 -47.785398) (xy 285.834198 -47.734965) (xy 285.88996 -47.690496)
			(xy 285.950351 -47.65255) (xy 286.01461 -47.621605) (xy 286.08193 -47.598048) (xy 286.151465 -47.582178)
			(xy 286.222339 -47.574192) (xy 286.293661 -47.574192) (xy 286.364535 -47.582178) (xy 286.43407 -47.598048)
			(xy 286.50139 -47.621605) (xy 286.565649 -47.65255) (xy 286.62604 -47.690496) (xy 286.681802 -47.734965)
			(xy 286.732235 -47.785398) (xy 286.776704 -47.84116) (xy 286.81465 -47.901551) (xy 286.845595 -47.96581)
			(xy 286.869152 -48.03313) (xy 286.885022 -48.102665) (xy 286.893008 -48.173539) (xy 286.893508 -48.2092)
			(xy 286.893008 -48.244861) (xy 293.242992 -48.244861) (xy 293.242992 -48.173539) (xy 293.250978 -48.102665)
			(xy 293.266848 -48.03313) (xy 293.290405 -47.96581) (xy 293.32135 -47.901551) (xy 293.359296 -47.84116)
			(xy 293.403765 -47.785398) (xy 293.454198 -47.734965) (xy 293.50996 -47.690496) (xy 293.570351 -47.65255)
			(xy 293.63461 -47.621605) (xy 293.70193 -47.598048) (xy 293.771465 -47.582178) (xy 293.842339 -47.574192)
			(xy 293.913661 -47.574192) (xy 293.984535 -47.582178) (xy 294.05407 -47.598048) (xy 294.12139 -47.621605)
			(xy 294.185649 -47.65255) (xy 294.24604 -47.690496) (xy 294.301802 -47.734965) (xy 294.352235 -47.785398)
			(xy 294.396704 -47.84116) (xy 294.43465 -47.901551) (xy 294.465595 -47.96581) (xy 294.489152 -48.03313)
			(xy 294.505022 -48.102665) (xy 294.513008 -48.173539) (xy 294.513508 -48.2092) (xy 294.513008 -48.244861)
			(xy 294.505022 -48.315735) (xy 294.489152 -48.38527) (xy 294.465595 -48.45259) (xy 294.43465 -48.516849)
			(xy 294.396704 -48.57724) (xy 294.352235 -48.633002) (xy 294.301802 -48.683435) (xy 294.24604 -48.727904)
			(xy 294.185649 -48.76585) (xy 294.12139 -48.796795) (xy 294.05407 -48.820352) (xy 293.984535 -48.836222)
			(xy 293.913661 -48.844208) (xy 293.842339 -48.844208) (xy 293.771465 -48.836222) (xy 293.70193 -48.820352)
			(xy 293.63461 -48.796795) (xy 293.570351 -48.76585) (xy 293.50996 -48.727904) (xy 293.454198 -48.683435)
			(xy 293.403765 -48.633002) (xy 293.359296 -48.57724) (xy 293.32135 -48.516849) (xy 293.290405 -48.45259)
			(xy 293.266848 -48.38527) (xy 293.250978 -48.315735) (xy 293.242992 -48.244861) (xy 286.893008 -48.244861)
			(xy 286.885022 -48.315735) (xy 286.869152 -48.38527) (xy 286.845595 -48.45259) (xy 286.81465 -48.516849)
			(xy 286.776704 -48.57724) (xy 286.732235 -48.633002) (xy 286.681802 -48.683435) (xy 286.62604 -48.727904)
			(xy 286.565649 -48.76585) (xy 286.50139 -48.796795) (xy 286.43407 -48.820352) (xy 286.364535 -48.836222)
			(xy 286.293661 -48.844208) (xy 286.222339 -48.844208) (xy 286.151465 -48.836222) (xy 286.08193 -48.820352)
			(xy 286.01461 -48.796795) (xy 285.950351 -48.76585) (xy 285.88996 -48.727904) (xy 285.834198 -48.683435)
			(xy 285.783765 -48.633002) (xy 285.739296 -48.57724) (xy 285.70135 -48.516849) (xy 285.670405 -48.45259)
			(xy 285.646848 -48.38527) (xy 285.630978 -48.315735) (xy 285.622992 -48.244861) (xy 279.273008 -48.244861)
			(xy 279.265022 -48.315735) (xy 279.249152 -48.38527) (xy 279.225595 -48.45259) (xy 279.19465 -48.516849)
			(xy 279.156704 -48.57724) (xy 279.112235 -48.633002) (xy 279.061802 -48.683435) (xy 279.00604 -48.727904)
			(xy 278.945649 -48.76585) (xy 278.88139 -48.796795) (xy 278.81407 -48.820352) (xy 278.744535 -48.836222)
			(xy 278.673661 -48.844208) (xy 278.602339 -48.844208) (xy 278.531465 -48.836222) (xy 278.46193 -48.820352)
			(xy 278.39461 -48.796795) (xy 278.330351 -48.76585) (xy 278.26996 -48.727904) (xy 278.214198 -48.683435)
			(xy 278.163765 -48.633002) (xy 278.119296 -48.57724) (xy 278.08135 -48.516849) (xy 278.050405 -48.45259)
			(xy 278.026848 -48.38527) (xy 278.010978 -48.315735) (xy 278.002992 -48.244861) (xy 271.653008 -48.244861)
			(xy 271.645022 -48.315735) (xy 271.629152 -48.38527) (xy 271.605595 -48.45259) (xy 271.57465 -48.516849)
			(xy 271.536704 -48.57724) (xy 271.492235 -48.633002) (xy 271.441802 -48.683435) (xy 271.38604 -48.727904)
			(xy 271.325649 -48.76585) (xy 271.26139 -48.796795) (xy 271.19407 -48.820352) (xy 271.124535 -48.836222)
			(xy 271.053661 -48.844208) (xy 270.982339 -48.844208) (xy 270.911465 -48.836222) (xy 270.84193 -48.820352)
			(xy 270.77461 -48.796795) (xy 270.710351 -48.76585) (xy 270.64996 -48.727904) (xy 270.594198 -48.683435)
			(xy 270.543765 -48.633002) (xy 270.499296 -48.57724) (xy 270.46135 -48.516849) (xy 270.430405 -48.45259)
			(xy 270.406848 -48.38527) (xy 270.390978 -48.315735) (xy 270.382992 -48.244861) (xy 264.033008 -48.244861)
			(xy 264.025022 -48.315735) (xy 264.009152 -48.38527) (xy 263.985595 -48.45259) (xy 263.95465 -48.516849)
			(xy 263.916704 -48.57724) (xy 263.872235 -48.633002) (xy 263.821802 -48.683435) (xy 263.76604 -48.727904)
			(xy 263.705649 -48.76585) (xy 263.64139 -48.796795) (xy 263.57407 -48.820352) (xy 263.504535 -48.836222)
			(xy 263.433661 -48.844208) (xy 263.362339 -48.844208) (xy 263.291465 -48.836222) (xy 263.22193 -48.820352)
			(xy 263.15461 -48.796795) (xy 263.090351 -48.76585) (xy 263.02996 -48.727904) (xy 262.974198 -48.683435)
			(xy 262.923765 -48.633002) (xy 262.879296 -48.57724) (xy 262.84135 -48.516849) (xy 262.810405 -48.45259)
			(xy 262.786848 -48.38527) (xy 262.770978 -48.315735) (xy 262.762992 -48.244861) (xy 256.413008 -48.244861)
			(xy 256.405022 -48.315735) (xy 256.389152 -48.38527) (xy 256.365595 -48.45259) (xy 256.33465 -48.516849)
			(xy 256.296704 -48.57724) (xy 256.252235 -48.633002) (xy 256.201802 -48.683435) (xy 256.14604 -48.727904)
			(xy 256.085649 -48.76585) (xy 256.02139 -48.796795) (xy 255.95407 -48.820352) (xy 255.884535 -48.836222)
			(xy 255.813661 -48.844208) (xy 255.742339 -48.844208) (xy 255.671465 -48.836222) (xy 255.60193 -48.820352)
			(xy 255.53461 -48.796795) (xy 255.470351 -48.76585) (xy 255.40996 -48.727904) (xy 255.354198 -48.683435)
			(xy 255.303765 -48.633002) (xy 255.259296 -48.57724) (xy 255.22135 -48.516849) (xy 255.190405 -48.45259)
			(xy 255.166848 -48.38527) (xy 255.150978 -48.315735) (xy 255.142992 -48.244861) (xy 248.793008 -48.244861)
			(xy 248.785022 -48.315735) (xy 248.769152 -48.38527) (xy 248.745595 -48.45259) (xy 248.71465 -48.516849)
			(xy 248.676704 -48.57724) (xy 248.632235 -48.633002) (xy 248.581802 -48.683435) (xy 248.52604 -48.727904)
			(xy 248.465649 -48.76585) (xy 248.40139 -48.796795) (xy 248.33407 -48.820352) (xy 248.264535 -48.836222)
			(xy 248.193661 -48.844208) (xy 248.122339 -48.844208) (xy 248.051465 -48.836222) (xy 247.98193 -48.820352)
			(xy 247.91461 -48.796795) (xy 247.850351 -48.76585) (xy 247.78996 -48.727904) (xy 247.734198 -48.683435)
			(xy 247.683765 -48.633002) (xy 247.639296 -48.57724) (xy 247.60135 -48.516849) (xy 247.570405 -48.45259)
			(xy 247.546848 -48.38527) (xy 247.530978 -48.315735) (xy 247.522992 -48.244861) (xy 241.173008 -48.244861)
			(xy 241.165022 -48.315735) (xy 241.149152 -48.38527) (xy 241.125595 -48.45259) (xy 241.09465 -48.516849)
			(xy 241.056704 -48.57724) (xy 241.012235 -48.633002) (xy 240.961802 -48.683435) (xy 240.90604 -48.727904)
			(xy 240.845649 -48.76585) (xy 240.78139 -48.796795) (xy 240.71407 -48.820352) (xy 240.644535 -48.836222)
			(xy 240.573661 -48.844208) (xy 240.502339 -48.844208) (xy 240.431465 -48.836222) (xy 240.36193 -48.820352)
			(xy 240.29461 -48.796795) (xy 240.230351 -48.76585) (xy 240.16996 -48.727904) (xy 240.114198 -48.683435)
			(xy 240.063765 -48.633002) (xy 240.019296 -48.57724) (xy 239.98135 -48.516849) (xy 239.950405 -48.45259)
			(xy 239.926848 -48.38527) (xy 239.910978 -48.315735) (xy 239.902992 -48.244861) (xy 233.553008 -48.244861)
			(xy 233.545022 -48.315735) (xy 233.529152 -48.38527) (xy 233.505595 -48.45259) (xy 233.47465 -48.516849)
			(xy 233.436704 -48.57724) (xy 233.392235 -48.633002) (xy 233.341802 -48.683435) (xy 233.28604 -48.727904)
			(xy 233.225649 -48.76585) (xy 233.16139 -48.796795) (xy 233.09407 -48.820352) (xy 233.024535 -48.836222)
			(xy 232.953661 -48.844208) (xy 232.882339 -48.844208) (xy 232.811465 -48.836222) (xy 232.74193 -48.820352)
			(xy 232.67461 -48.796795) (xy 232.610351 -48.76585) (xy 232.54996 -48.727904) (xy 232.494198 -48.683435)
			(xy 232.443765 -48.633002) (xy 232.399296 -48.57724) (xy 232.36135 -48.516849) (xy 232.330405 -48.45259)
			(xy 232.306848 -48.38527) (xy 232.290978 -48.315735) (xy 232.282992 -48.244861) (xy 225.933008 -48.244861)
			(xy 225.925022 -48.315735) (xy 225.909152 -48.38527) (xy 225.885595 -48.45259) (xy 225.85465 -48.516849)
			(xy 225.816704 -48.57724) (xy 225.772235 -48.633002) (xy 225.721802 -48.683435) (xy 225.66604 -48.727904)
			(xy 225.605649 -48.76585) (xy 225.54139 -48.796795) (xy 225.47407 -48.820352) (xy 225.404535 -48.836222)
			(xy 225.333661 -48.844208) (xy 225.262339 -48.844208) (xy 225.191465 -48.836222) (xy 225.12193 -48.820352)
			(xy 225.05461 -48.796795) (xy 224.990351 -48.76585) (xy 224.92996 -48.727904) (xy 224.874198 -48.683435)
			(xy 224.823765 -48.633002) (xy 224.779296 -48.57724) (xy 224.74135 -48.516849) (xy 224.710405 -48.45259)
			(xy 224.686848 -48.38527) (xy 224.670978 -48.315735) (xy 224.662992 -48.244861) (xy 218.313008 -48.244861)
			(xy 218.305022 -48.315735) (xy 218.289152 -48.38527) (xy 218.265595 -48.45259) (xy 218.23465 -48.516849)
			(xy 218.196704 -48.57724) (xy 218.152235 -48.633002) (xy 218.101802 -48.683435) (xy 218.04604 -48.727904)
			(xy 217.985649 -48.76585) (xy 217.92139 -48.796795) (xy 217.85407 -48.820352) (xy 217.784535 -48.836222)
			(xy 217.713661 -48.844208) (xy 217.642339 -48.844208) (xy 217.571465 -48.836222) (xy 217.50193 -48.820352)
			(xy 217.43461 -48.796795) (xy 217.370351 -48.76585) (xy 217.30996 -48.727904) (xy 217.254198 -48.683435)
			(xy 217.203765 -48.633002) (xy 217.159296 -48.57724) (xy 217.12135 -48.516849) (xy 217.090405 -48.45259)
			(xy 217.066848 -48.38527) (xy 217.050978 -48.315735) (xy 217.042992 -48.244861) (xy 213.238702 -48.244861)
			(xy 213.208057 -48.376492) (xy 213.162777 -48.536313) (xy 213.109985 -48.693812) (xy 213.0498 -48.848636)
			(xy 212.982355 -49.000438) (xy 212.907802 -49.148879) (xy 212.826308 -49.293626) (xy 212.738056 -49.434354)
			(xy 212.643244 -49.570748) (xy 212.542083 -49.702502) (xy 212.4348 -49.829322) (xy 212.378544 -49.890426)
			(xy 212.363464 -49.90737) (xy 212.33896 -49.945534) (xy 212.321619 -49.987441) (xy 212.311993 -50.031761)
			(xy 212.310387 -50.077086) (xy 212.316852 -50.121977) (xy 212.331183 -50.165007) (xy 212.352925 -50.204809)
			(xy 212.381386 -50.24012) (xy 212.415664 -50.269819) (xy 212.454669 -50.29296) (xy 212.497163 -50.308811)
			(xy 212.541795 -50.316866) (xy 212.564472 -50.3174) (xy 298.055792 -50.3174) (xy 298.078474 -50.316902)
			(xy 298.123118 -50.30885) (xy 298.165623 -50.293) (xy 298.204639 -50.269856) (xy 298.238926 -50.240154)
			(xy 298.267396 -50.204836) (xy 298.289144 -50.165025) (xy 298.303479 -50.121985) (xy 298.309945 -50.077085)
			(xy 298.308338 -50.031749) (xy 298.298707 -49.987419) (xy 298.28136 -49.945503) (xy 298.256847 -49.907332)
			(xy 298.24172 -49.890426) (xy 298.185492 -49.829296) (xy 298.078206 -49.70248) (xy 297.977042 -49.570729)
			(xy 297.882226 -49.434338) (xy 297.793971 -49.293613) (xy 297.712474 -49.148868) (xy 297.637919 -49.000429)
			(xy 297.570472 -48.848629) (xy 297.510284 -48.693806) (xy 297.45749 -48.536309) (xy 297.412209 -48.376489)
			(xy 297.374542 -48.214706) (xy 297.344573 -48.051322) (xy 297.32237 -47.886702) (xy 297.307982 -47.721216)
			(xy 297.301442 -47.555235) (xy 297.302764 -47.38913) (xy 297.311945 -47.223273) (xy 297.328965 -47.058037)
			(xy 297.353785 -46.893792) (xy 297.38635 -46.730905) (xy 297.426588 -46.569742) (xy 297.474407 -46.410664)
			(xy 297.5297 -46.254026) (xy 297.592345 -46.100181) (xy 297.662199 -45.949473) (xy 297.739108 -45.80224)
			(xy 297.822898 -45.658811) (xy 297.913382 -45.519508) (xy 298.010356 -45.384643) (xy 298.113605 -45.254519)
			(xy 298.222895 -45.129426) (xy 298.337983 -45.009646) (xy 298.39793 -44.952158) (xy 298.416835 -44.933821)
			(xy 298.451022 -44.893754) (xy 298.480712 -44.850251) (xy 298.493434 -44.82719) (xy 298.507276 -44.800347)
			(xy 298.529034 -44.744007) (xy 298.543728 -44.685426) (xy 298.551137 -44.625486) (xy 298.5516 -44.595288)
			(xy 298.5516 -41.500044) (xy 298.552096 -41.4331) (xy 298.560028 -41.299448) (xy 298.575863 -41.166501)
			(xy 298.599546 -41.034725) (xy 298.630994 -40.904584) (xy 298.670097 -40.776534) (xy 298.716717 -40.651025)
			(xy 298.77069 -40.528499) (xy 298.831827 -40.409386) (xy 298.899913 -40.294103) (xy 298.974708 -40.183056)
			(xy 299.055951 -40.076635) (xy 299.143355 -39.975214) (xy 299.236615 -39.879149) (xy 299.335401 -39.788778)
			(xy 299.439368 -39.704417) (xy 299.548149 -39.626363) (xy 299.661364 -39.554891) (xy 299.778613 -39.490252)
			(xy 299.899486 -39.432671) (xy 300.023558 -39.382353) (xy 300.150393 -39.339473) (xy 300.279545 -39.304182)
			(xy 300.410562 -39.276604) (xy 300.542981 -39.256836) (xy 300.67634 -39.244948) (xy 300.810168 -39.24098)
			(xy 300.943996 -39.244948) (xy 301.077355 -39.256836) (xy 301.209774 -39.276604) (xy 301.340791 -39.304182)
			(xy 301.469943 -39.339473) (xy 301.596778 -39.382353) (xy 301.72085 -39.432671) (xy 301.841723 -39.490252)
			(xy 301.958972 -39.554891) (xy 302.072187 -39.626363) (xy 302.180968 -39.704417) (xy 302.284935 -39.788778)
			(xy 302.383721 -39.879149) (xy 302.476981 -39.975214) (xy 302.564385 -40.076635) (xy 302.645628 -40.183056)
			(xy 302.720423 -40.294103) (xy 302.788509 -40.409386) (xy 302.849646 -40.528499) (xy 302.903619 -40.651025)
			(xy 302.950239 -40.776534) (xy 302.989342 -40.904584) (xy 303.02079 -41.034725) (xy 303.044473 -41.166501)
			(xy 303.060308 -41.299448) (xy 303.06824 -41.4331) (xy 303.068736 -41.500044) (xy 303.068736 -44.595288)
			(xy 303.069196 -44.625486) (xy 303.076599 -44.685427) (xy 303.091294 -44.744009) (xy 303.11306 -44.800347)
			(xy 303.126902 -44.82719) (xy 303.139651 -44.850234) (xy 303.169353 -44.893725) (xy 303.202867 -44.933038)
			(xy 336.785706 -44.933038) (xy 336.785706 -44.805162) (xy 336.793735 -44.677538) (xy 336.809763 -44.55067)
			(xy 336.833724 -44.425058) (xy 336.865526 -44.3012) (xy 336.905042 -44.179582) (xy 336.952116 -44.060685)
			(xy 337.006563 -43.944979) (xy 337.068168 -43.83292) (xy 337.136688 -43.724951) (xy 337.211852 -43.621497)
			(xy 337.293363 -43.522966) (xy 337.3809 -43.429748) (xy 337.474118 -43.342211) (xy 337.572649 -43.2607)
			(xy 337.676103 -43.185536) (xy 337.784072 -43.117016) (xy 337.896131 -43.055411) (xy 338.011837 -43.000964)
			(xy 338.130734 -42.95389) (xy 338.252352 -42.914374) (xy 338.37621 -42.882572) (xy 338.501822 -42.858611)
			(xy 338.62869 -42.842583) (xy 338.756314 -42.834554) (xy 338.88419 -42.834554) (xy 339.011814 -42.842583)
			(xy 339.138682 -42.858611) (xy 339.264294 -42.882572) (xy 339.388152 -42.914374) (xy 339.50977 -42.95389)
			(xy 339.628667 -43.000964) (xy 339.744373 -43.055411) (xy 339.856432 -43.117016) (xy 339.964401 -43.185536)
			(xy 340.067855 -43.2607) (xy 340.166386 -43.342211) (xy 340.259604 -43.429748) (xy 340.347141 -43.522966)
			(xy 340.428652 -43.621497) (xy 340.503816 -43.724951) (xy 340.572336 -43.83292) (xy 340.633941 -43.944979)
			(xy 340.688388 -44.060685) (xy 340.735462 -44.179582) (xy 340.774978 -44.3012) (xy 340.80678 -44.425058)
			(xy 340.830741 -44.55067) (xy 340.846769 -44.677538) (xy 340.854798 -44.805162) (xy 340.8553 -44.8691)
			(xy 340.854798 -44.932982) (xy 348.217484 -44.932982) (xy 348.217484 -44.805218) (xy 348.225506 -44.677705)
			(xy 348.241519 -44.550948) (xy 348.26546 -44.425446) (xy 348.297234 -44.301696) (xy 348.336715 -44.180184)
			(xy 348.383748 -44.061392) (xy 348.438148 -43.945787) (xy 348.499699 -43.833826) (xy 348.568159 -43.725951)
			(xy 348.643257 -43.622587) (xy 348.724697 -43.524142) (xy 348.812158 -43.431006) (xy 348.905294 -43.343545)
			(xy 349.003739 -43.262105) (xy 349.107103 -43.187007) (xy 349.214978 -43.118547) (xy 349.326939 -43.056996)
			(xy 349.442544 -43.002596) (xy 349.561336 -42.955563) (xy 349.682848 -42.916082) (xy 349.806598 -42.884308)
			(xy 349.9321 -42.860367) (xy 350.058857 -42.844354) (xy 350.18637 -42.836332) (xy 350.314134 -42.836332)
			(xy 350.441647 -42.844354) (xy 350.568404 -42.860367) (xy 350.693906 -42.884308) (xy 350.817656 -42.916082)
			(xy 350.939168 -42.955563) (xy 351.05796 -43.002596) (xy 351.173565 -43.056996) (xy 351.285526 -43.118547)
			(xy 351.393401 -43.187007) (xy 351.496765 -43.262105) (xy 351.59521 -43.343545) (xy 351.688346 -43.431006)
			(xy 351.775807 -43.524142) (xy 351.857247 -43.622587) (xy 351.932345 -43.725951) (xy 352.000805 -43.833826)
			(xy 352.062356 -43.945787) (xy 352.116756 -44.061392) (xy 352.163789 -44.180184) (xy 352.20327 -44.301696)
			(xy 352.235044 -44.425446) (xy 352.258985 -44.550948) (xy 352.274998 -44.677705) (xy 352.28302 -44.805218)
			(xy 352.283522 -44.8691) (xy 352.28302 -44.932982) (xy 352.274998 -45.060495) (xy 352.258985 -45.187252)
			(xy 352.235044 -45.312754) (xy 352.20327 -45.436504) (xy 352.163789 -45.558016) (xy 352.116756 -45.676808)
			(xy 352.062356 -45.792413) (xy 352.000805 -45.904374) (xy 351.932345 -46.012249) (xy 351.857247 -46.115613)
			(xy 351.775807 -46.214058) (xy 351.688346 -46.307194) (xy 351.59521 -46.394655) (xy 351.496765 -46.476095)
			(xy 351.393401 -46.551193) (xy 351.285526 -46.619653) (xy 351.173565 -46.681204) (xy 351.05796 -46.735604)
			(xy 350.939168 -46.782637) (xy 350.817656 -46.822118) (xy 350.693906 -46.853892) (xy 350.568404 -46.877833)
			(xy 350.441647 -46.893846) (xy 350.314134 -46.901868) (xy 350.18637 -46.901868) (xy 350.058857 -46.893846)
			(xy 349.9321 -46.877833) (xy 349.806598 -46.853892) (xy 349.682848 -46.822118) (xy 349.561336 -46.782637)
			(xy 349.442544 -46.735604) (xy 349.326939 -46.681204) (xy 349.214978 -46.619653) (xy 349.107103 -46.551193)
			(xy 349.003739 -46.476095) (xy 348.905294 -46.394655) (xy 348.812158 -46.307194) (xy 348.724697 -46.214058)
			(xy 348.643257 -46.115613) (xy 348.568159 -46.012249) (xy 348.499699 -45.904374) (xy 348.438148 -45.792413)
			(xy 348.383748 -45.676808) (xy 348.336715 -45.558016) (xy 348.297234 -45.436504) (xy 348.26546 -45.312754)
			(xy 348.241519 -45.187252) (xy 348.225506 -45.060495) (xy 348.217484 -44.932982) (xy 340.854798 -44.932982)
			(xy 340.854798 -44.933038) (xy 340.846769 -45.060662) (xy 340.830741 -45.18753) (xy 340.80678 -45.313142)
			(xy 340.774978 -45.437) (xy 340.735462 -45.558618) (xy 340.688388 -45.677515) (xy 340.633941 -45.793221)
			(xy 340.572336 -45.90528) (xy 340.503816 -46.013249) (xy 340.428652 -46.116703) (xy 340.347141 -46.215234)
			(xy 340.259604 -46.308452) (xy 340.166386 -46.395989) (xy 340.067855 -46.4775) (xy 339.964401 -46.552664)
			(xy 339.856432 -46.621184) (xy 339.744373 -46.682789) (xy 339.628667 -46.737236) (xy 339.50977 -46.78431)
			(xy 339.388152 -46.823826) (xy 339.264294 -46.855628) (xy 339.138682 -46.879589) (xy 339.011814 -46.895617)
			(xy 338.88419 -46.903646) (xy 338.756314 -46.903646) (xy 338.62869 -46.895617) (xy 338.501822 -46.879589)
			(xy 338.37621 -46.855628) (xy 338.252352 -46.823826) (xy 338.130734 -46.78431) (xy 338.011837 -46.737236)
			(xy 337.896131 -46.682789) (xy 337.784072 -46.621184) (xy 337.676103 -46.552664) (xy 337.572649 -46.4775)
			(xy 337.474118 -46.395989) (xy 337.3809 -46.308452) (xy 337.293363 -46.215234) (xy 337.211852 -46.116703)
			(xy 337.136688 -46.013249) (xy 337.068168 -45.90528) (xy 337.006563 -45.793221) (xy 336.952116 -45.677515)
			(xy 336.905042 -45.558618) (xy 336.865526 -45.437) (xy 336.833724 -45.313142) (xy 336.809763 -45.18753)
			(xy 336.793735 -45.060662) (xy 336.785706 -44.933038) (xy 303.202867 -44.933038) (xy 303.20352 -44.933804)
			(xy 303.222406 -44.952158) (xy 303.282384 -45.009613) (xy 303.39747 -45.129397) (xy 303.506758 -45.254493)
			(xy 303.610004 -45.38462) (xy 303.706976 -45.519488) (xy 303.797458 -45.658794) (xy 303.881246 -45.802225)
			(xy 303.958152 -45.94946) (xy 304.028005 -46.10017) (xy 304.090648 -46.254017) (xy 304.14594 -46.410656)
			(xy 304.193758 -46.569735) (xy 304.233994 -46.7309) (xy 304.266558 -46.893788) (xy 304.291378 -47.058034)
			(xy 304.308397 -47.223271) (xy 304.317578 -47.389128) (xy 304.3189 -47.555234) (xy 304.31236 -47.721216)
			(xy 304.297972 -47.886703) (xy 304.27577 -48.051324) (xy 304.245802 -48.21471) (xy 304.208136 -48.376494)
			(xy 304.162856 -48.536315) (xy 304.110064 -48.693814) (xy 304.049878 -48.848638) (xy 303.982433 -49.00044)
			(xy 303.907879 -49.148881) (xy 303.826385 -49.293628) (xy 303.738132 -49.434356) (xy 303.643319 -49.57075)
			(xy 303.542157 -49.702504) (xy 303.434873 -49.829323) (xy 303.378616 -49.890426) (xy 303.363538 -49.907371)
			(xy 303.339036 -49.945536) (xy 303.321697 -49.987445) (xy 303.312072 -50.031765) (xy 303.310467 -50.07709)
			(xy 303.316932 -50.121981) (xy 303.331262 -50.165011) (xy 303.353003 -50.204814) (xy 303.381463 -50.240126)
			(xy 303.41574 -50.269826) (xy 303.454743 -50.292971) (xy 303.497236 -50.308825) (xy 303.541867 -50.316884)
			(xy 303.564544 -50.3174) (xy 313.3344 -50.3174) (xy 315.5696 -48.0822) (xy 334.1624 -48.0822) (xy 334.429608 -48.349408)
			(xy 334.446208 -48.365306) (xy 334.48402 -48.391428) (xy 334.525914 -48.410325) (xy 334.570522 -48.421381)
			(xy 334.616392 -48.424235) (xy 334.662027 -48.418795) (xy 334.70594 -48.405237) (xy 334.746699 -48.384003)
			(xy 334.782975 -48.355787) (xy 334.79867 -48.338994) (xy 334.837444 -48.296342) (xy 334.920052 -48.215934)
			(xy 335.008067 -48.141483) (xy 335.10106 -48.073352) (xy 335.198578 -48.011871) (xy 335.300146 -47.957342)
			(xy 335.405269 -47.910028) (xy 335.513437 -47.870162) (xy 335.624121 -47.837936) (xy 335.736783 -47.813507)
			(xy 335.850875 -47.796995) (xy 335.96584 -47.788481) (xy 336.08112 -47.788005) (xy 336.196151 -47.795569)
			(xy 336.310376 -47.811138) (xy 336.423236 -47.834634) (xy 336.534183 -47.865945) (xy 336.642676 -47.904917)
			(xy 336.748187 -47.95136) (xy 336.850202 -48.005049) (xy 336.948224 -48.065721) (xy 337.041776 -48.133082)
			(xy 337.130403 -48.206803) (xy 337.213673 -48.286526) (xy 337.29118 -48.371862) (xy 337.362547 -48.462395)
			(xy 337.427426 -48.557685) (xy 337.485502 -48.657268) (xy 337.536491 -48.760659) (xy 337.580145 -48.867354)
			(xy 337.616253 -48.976834) (xy 337.644637 -49.088565) (xy 337.66516 -49.202004) (xy 337.677721 -49.316597)
			(xy 337.682261 -49.431788) (xy 337.678755 -49.547015) (xy 337.667222 -49.661717) (xy 337.647718 -49.775335)
			(xy 337.620338 -49.887317) (xy 337.585214 -49.997116) (xy 337.542519 -50.104199) (xy 337.517994 -50.156364)
			(xy 337.508341 -50.177617) (xy 337.496102 -50.222656) (xy 337.492292 -50.269173) (xy 337.497041 -50.315603)
			(xy 337.510189 -50.360386) (xy 337.531292 -50.402015) (xy 337.559643 -50.43909) (xy 337.594286 -50.470366)
			(xy 337.634059 -50.494789) (xy 337.677622 -50.511539) (xy 337.723512 -50.520053) (xy 337.746848 -50.5206)
		)
		(stroke
			(width 0)
			(type solid)
		)
		(fill yes)
		(layer "In2.Cu")
		(net "GND")
	)
	(gr_line
		(start 0 -51.799998)
		(end 0 -1.999996)
		(stroke
			(width 2.032)
			(type default)
		)
		(layer "In3.Cu")
	)
	(gr_poly
		(pts
			(xy 77.43698 -51.303936) (xy 77.460144 -51.303425) (xy 77.505705 -51.29503) (xy 77.548988 -51.278514)
			(xy 77.58856 -51.254425) (xy 77.62311 -51.223561) (xy 77.651491 -51.186944) (xy 77.672764 -51.145789)
			(xy 77.686223 -51.10146) (xy 77.691422 -51.055425) (xy 77.68819 -51.00921) (xy 77.676632 -50.964347)
			(xy 77.657133 -50.922323) (xy 77.630339 -50.88453) (xy 77.597136 -50.852221) (xy 77.578204 -50.838862)
			(xy 77.504474 -50.788989) (xy 77.361001 -50.683592) (xy 77.22234 -50.571942) (xy 77.088762 -50.454256)
			(xy 76.960531 -50.330767) (xy 76.837898 -50.201716) (xy 76.721104 -50.067358) (xy 76.610378 -49.927957)
			(xy 76.505939 -49.783786) (xy 76.407991 -49.635128) (xy 76.316727 -49.482276) (xy 76.232326 -49.32553)
			(xy 76.154954 -49.165198) (xy 76.084762 -49.001595) (xy 76.02189 -48.835042) (xy 75.966459 -48.665866)
			(xy 75.91858 -48.4944) (xy 75.878347 -48.320982) (xy 75.845837 -48.14595) (xy 75.821116 -47.96965)
			(xy 75.804231 -47.792428) (xy 75.795216 -47.614631) (xy 75.794089 -47.43661) (xy 75.800852 -47.258713)
			(xy 75.815492 -47.081291) (xy 75.837979 -46.904692) (xy 75.86827 -46.729263) (xy 75.906305 -46.555349)
			(xy 75.952009 -46.383291) (xy 76.005293 -46.213427) (xy 76.066052 -46.046091) (xy 76.134166 -45.881612)
			(xy 76.209502 -45.720313) (xy 76.291912 -45.562511) (xy 76.381233 -45.408516) (xy 76.477291 -45.25863)
			(xy 76.579897 -45.113148) (xy 76.688848 -44.972356) (xy 76.803932 -44.83653) (xy 76.924921 -44.705938)
			(xy 76.987908 -44.64304) (xy 77.005688 -44.62526) (xy 77.044042 -44.534582) (xy 77.044042 -41.549574)
			(xy 77.044042 -41.450514) (xy 77.044042 -41.287192) (xy 77.051916 -41.279318) (xy 77.056488 -41.233852)
			(xy 77.056488 -41.233598) (xy 77.064096 -41.160097) (xy 77.086174 -41.013971) (xy 77.116023 -40.869232)
			(xy 77.153558 -40.726294) (xy 77.198672 -40.585564) (xy 77.251236 -40.447443) (xy 77.311101 -40.312327)
			(xy 77.378095 -40.1806) (xy 77.452027 -40.052638) (xy 77.532687 -39.928806) (xy 77.619843 -39.809458)
			(xy 77.713249 -39.694935) (xy 77.812636 -39.585562) (xy 77.917722 -39.481652) (xy 78.028207 -39.383502)
			(xy 78.143774 -39.291392) (xy 78.264096 -39.205584) (xy 78.388827 -39.126323) (xy 78.517613 -39.053836)
			(xy 78.650086 -38.988329) (xy 78.785868 -38.929989) (xy 78.924571 -38.878982) (xy 79.0658 -38.835455)
			(xy 79.209152 -38.799531) (xy 79.354217 -38.771313) (xy 79.500582 -38.750882) (xy 79.64783 -38.738295)
			(xy 79.795539 -38.733588) (xy 79.943289 -38.736776) (xy 80.090658 -38.747849) (xy 80.237226 -38.766775)
			(xy 80.382574 -38.7935) (xy 80.526287 -38.827948) (xy 80.667956 -38.870021) (xy 80.807177 -38.919599)
			(xy 80.943551 -38.97654) (xy 81.07669 -39.040682) (xy 81.206214 -39.111841) (xy 81.331754 -39.189816)
			(xy 81.452951 -39.274382) (xy 81.56946 -39.3653) (xy 81.680947 -39.462309) (xy 81.787096 -39.565133)
			(xy 81.887602 -39.673478) (xy 81.98218 -39.787036) (xy 82.070559 -39.905481) (xy 82.152488 -40.028477)
			(xy 82.227732 -40.155672) (xy 82.296076 -40.286704) (xy 82.357327 -40.421198) (xy 82.411308 -40.55877)
			(xy 82.457866 -40.699029) (xy 82.496869 -40.841574) (xy 82.528204 -40.985998) (xy 82.551783 -41.13189)
			(xy 82.567538 -41.278832) (xy 82.575424 -41.426406) (xy 82.575908 -41.500298) (xy 82.575908 -44.534582)
			(xy 82.614262 -44.62526) (xy 82.632042 -44.64304) (xy 82.695033 -44.705936) (xy 82.816032 -44.836524)
			(xy 82.897816 -44.933038) (xy 115.78564 -44.933038) (xy 115.78564 -44.805162) (xy 115.793669 -44.677538)
			(xy 115.809697 -44.55067) (xy 115.833658 -44.425058) (xy 115.86546 -44.3012) (xy 115.904976 -44.179582)
			(xy 115.95205 -44.060685) (xy 116.006497 -43.944979) (xy 116.068102 -43.83292) (xy 116.136622 -43.724951)
			(xy 116.211786 -43.621497) (xy 116.293297 -43.522966) (xy 116.380834 -43.429748) (xy 116.474052 -43.342211)
			(xy 116.572583 -43.2607) (xy 116.676037 -43.185536) (xy 116.784006 -43.117016) (xy 116.896065 -43.055411)
			(xy 117.011771 -43.000964) (xy 117.130668 -42.95389) (xy 117.252286 -42.914374) (xy 117.376144 -42.882572)
			(xy 117.501756 -42.858611) (xy 117.628624 -42.842583) (xy 117.756248 -42.834554) (xy 117.884124 -42.834554)
			(xy 118.011748 -42.842583) (xy 118.138616 -42.858611) (xy 118.264228 -42.882572) (xy 118.388086 -42.914374)
			(xy 118.509704 -42.95389) (xy 118.628601 -43.000964) (xy 118.744307 -43.055411) (xy 118.856366 -43.117016)
			(xy 118.964335 -43.185536) (xy 119.067789 -43.2607) (xy 119.16632 -43.342211) (xy 119.259538 -43.429748)
			(xy 119.347075 -43.522966) (xy 119.428586 -43.621497) (xy 119.50375 -43.724951) (xy 119.57227 -43.83292)
			(xy 119.633875 -43.944979) (xy 119.688322 -44.060685) (xy 119.735396 -44.179582) (xy 119.774912 -44.3012)
			(xy 119.806714 -44.425058) (xy 119.830675 -44.55067) (xy 119.846703 -44.677538) (xy 119.854732 -44.805162)
			(xy 119.855234 -44.8691) (xy 119.854732 -44.932982) (xy 127.217418 -44.932982) (xy 127.217418 -44.805218)
			(xy 127.22544 -44.677705) (xy 127.241453 -44.550948) (xy 127.265394 -44.425446) (xy 127.297168 -44.301696)
			(xy 127.336649 -44.180184) (xy 127.383682 -44.061392) (xy 127.438082 -43.945787) (xy 127.499633 -43.833826)
			(xy 127.568093 -43.725951) (xy 127.643191 -43.622587) (xy 127.724631 -43.524142) (xy 127.812092 -43.431006)
			(xy 127.905228 -43.343545) (xy 128.003673 -43.262105) (xy 128.107037 -43.187007) (xy 128.214912 -43.118547)
			(xy 128.326873 -43.056996) (xy 128.442478 -43.002596) (xy 128.56127 -42.955563) (xy 128.682782 -42.916082)
			(xy 128.806532 -42.884308) (xy 128.932034 -42.860367) (xy 129.058791 -42.844354) (xy 129.186304 -42.836332)
			(xy 129.314068 -42.836332) (xy 129.441581 -42.844354) (xy 129.568338 -42.860367) (xy 129.69384 -42.884308)
			(xy 129.81759 -42.916082) (xy 129.939102 -42.955563) (xy 130.057894 -43.002596) (xy 130.173499 -43.056996)
			(xy 130.28546 -43.118547) (xy 130.393335 -43.187007) (xy 130.496699 -43.262105) (xy 130.595144 -43.343545)
			(xy 130.68828 -43.431006) (xy 130.775741 -43.524142) (xy 130.857181 -43.622587) (xy 130.932279 -43.725951)
			(xy 131.000739 -43.833826) (xy 131.06229 -43.945787) (xy 131.11669 -44.061392) (xy 131.163723 -44.180184)
			(xy 131.203204 -44.301696) (xy 131.234978 -44.425446) (xy 131.258919 -44.550948) (xy 131.274932 -44.677705)
			(xy 131.282954 -44.805218) (xy 131.283456 -44.8691) (xy 131.282954 -44.932982) (xy 131.274932 -45.060495)
			(xy 131.258919 -45.187252) (xy 131.234978 -45.312754) (xy 131.203204 -45.436504) (xy 131.163723 -45.558016)
			(xy 131.11669 -45.676808) (xy 131.06229 -45.792413) (xy 131.000739 -45.904374) (xy 130.932279 -46.012249)
			(xy 130.857181 -46.115613) (xy 130.775741 -46.214058) (xy 130.68828 -46.307194) (xy 130.595144 -46.394655)
			(xy 130.496699 -46.476095) (xy 130.393335 -46.551193) (xy 130.28546 -46.619653) (xy 130.173499 -46.681204)
			(xy 130.057894 -46.735604) (xy 129.939102 -46.782637) (xy 129.81759 -46.822118) (xy 129.69384 -46.853892)
			(xy 129.568338 -46.877833) (xy 129.441581 -46.893846) (xy 129.314068 -46.901868) (xy 129.186304 -46.901868)
			(xy 129.058791 -46.893846) (xy 128.932034 -46.877833) (xy 128.806532 -46.853892) (xy 128.682782 -46.822118)
			(xy 128.56127 -46.782637) (xy 128.442478 -46.735604) (xy 128.326873 -46.681204) (xy 128.214912 -46.619653)
			(xy 128.107037 -46.551193) (xy 128.003673 -46.476095) (xy 127.905228 -46.394655) (xy 127.812092 -46.307194)
			(xy 127.724631 -46.214058) (xy 127.643191 -46.115613) (xy 127.568093 -46.012249) (xy 127.499633 -45.904374)
			(xy 127.438082 -45.792413) (xy 127.383682 -45.676808) (xy 127.336649 -45.558016) (xy 127.297168 -45.436504)
			(xy 127.265394 -45.312754) (xy 127.241453 -45.187252) (xy 127.22544 -45.060495) (xy 127.217418 -44.932982)
			(xy 119.854732 -44.932982) (xy 119.854732 -44.933038) (xy 119.846703 -45.060662) (xy 119.830675 -45.18753)
			(xy 119.806714 -45.313142) (xy 119.774912 -45.437) (xy 119.735396 -45.558618) (xy 119.688322 -45.677515)
			(xy 119.633875 -45.793221) (xy 119.57227 -45.90528) (xy 119.50375 -46.013249) (xy 119.428586 -46.116703)
			(xy 119.347075 -46.215234) (xy 119.259538 -46.308452) (xy 119.16632 -46.395989) (xy 119.067789 -46.4775)
			(xy 118.964335 -46.552664) (xy 118.856366 -46.621184) (xy 118.744307 -46.682789) (xy 118.628601 -46.737236)
			(xy 118.509704 -46.78431) (xy 118.388086 -46.823826) (xy 118.264228 -46.855628) (xy 118.138616 -46.879589)
			(xy 118.011748 -46.895617) (xy 117.884124 -46.903646) (xy 117.756248 -46.903646) (xy 117.628624 -46.895617)
			(xy 117.501756 -46.879589) (xy 117.376144 -46.855628) (xy 117.252286 -46.823826) (xy 117.130668 -46.78431)
			(xy 117.011771 -46.737236) (xy 116.896065 -46.682789) (xy 116.784006 -46.621184) (xy 116.676037 -46.552664)
			(xy 116.572583 -46.4775) (xy 116.474052 -46.395989) (xy 116.380834 -46.308452) (xy 116.293297 -46.215234)
			(xy 116.211786 -46.116703) (xy 116.136622 -46.013249) (xy 116.068102 -45.90528) (xy 116.006497 -45.793221)
			(xy 115.95205 -45.677515) (xy 115.904976 -45.558618) (xy 115.86546 -45.437) (xy 115.833658 -45.313142)
			(xy 115.809697 -45.18753) (xy 115.793669 -45.060662) (xy 115.78564 -44.933038) (xy 82.897816 -44.933038)
			(xy 82.931125 -44.972346) (xy 83.040086 -45.113136) (xy 83.1427 -45.258615) (xy 83.238766 -45.4085)
			(xy 83.328096 -45.562494) (xy 83.410514 -45.720296) (xy 83.485857 -45.881595) (xy 83.553978 -46.046075)
			(xy 83.614743 -46.213412) (xy 83.668032 -46.383277) (xy 83.713742 -46.555337) (xy 83.751781 -46.729254)
			(xy 83.782076 -46.904686) (xy 83.804566 -47.081288) (xy 83.819208 -47.258713) (xy 83.825972 -47.436612)
			(xy 83.824846 -47.614637) (xy 83.815832 -47.792437) (xy 83.798947 -47.969663) (xy 83.774225 -48.145966)
			(xy 83.741714 -48.321) (xy 83.701478 -48.494422) (xy 83.653596 -48.66589) (xy 83.598162 -48.835068)
			(xy 83.535285 -49.001623) (xy 83.465089 -49.165228) (xy 83.387711 -49.325561) (xy 83.303304 -49.482308)
			(xy 83.212034 -49.63516) (xy 83.114079 -49.783817) (xy 83.009633 -49.927987) (xy 82.8989 -50.067387)
			(xy 82.782098 -50.201742) (xy 82.659457 -50.33079) (xy 82.531218 -50.454275) (xy 82.397631 -50.571956)
			(xy 82.258961 -50.683601) (xy 82.11548 -50.788992) (xy 82.041746 -50.838862) (xy 82.022784 -50.85217)
			(xy 81.989599 -50.884484) (xy 81.962821 -50.922278) (xy 81.943336 -50.9643) (xy 81.93179 -51.009157)
			(xy 81.928566 -51.055365) (xy 81.933771 -51.101391) (xy 81.947232 -51.145711) (xy 81.968503 -51.186857)
			(xy 81.99688 -51.223467) (xy 82.031422 -51.254327) (xy 82.070985 -51.278415) (xy 82.114259 -51.294933)
			(xy 82.15981 -51.303334) (xy 82.18297 -51.303936) (xy 94.5388 -51.303936) (xy 94.55545 -51.303393)
			(xy 94.587616 -51.294776) (xy 94.616456 -51.278128) (xy 94.640006 -51.254585) (xy 94.656662 -51.225749)
			(xy 94.665288 -51.193586) (xy 94.6658 -51.176936) (xy 94.6658 -50.8) (xy 94.666298 -50.73666) (xy 94.674252 -50.610231)
			(xy 94.690129 -50.48455) (xy 94.713866 -50.360115) (xy 94.74537 -50.237415) (xy 94.784516 -50.116936)
			(xy 94.83115 -49.999153) (xy 94.885087 -49.88453) (xy 94.946116 -49.77352) (xy 95.013994 -49.666561)
			(xy 95.088454 -49.564075) (xy 95.169202 -49.466467) (xy 95.25592 -49.374122) (xy 95.348265 -49.287404)
			(xy 95.445874 -49.206655) (xy 95.548359 -49.132195) (xy 95.655318 -49.064317) (xy 95.766328 -49.003288)
			(xy 95.880951 -48.949351) (xy 95.998734 -48.902717) (xy 96.119214 -48.863571) (xy 96.241913 -48.832067)
			(xy 96.366349 -48.808329) (xy 96.492029 -48.792452) (xy 96.618458 -48.784498) (xy 96.681798 -48.784002)
			(xy 112.06988 -48.784002) (xy 112.13322 -48.784489) (xy 112.259651 -48.792442) (xy 112.385333 -48.808318)
			(xy 112.50977 -48.832055) (xy 112.632471 -48.863558) (xy 112.752952 -48.902703) (xy 112.870737 -48.949337)
			(xy 112.985362 -49.003274) (xy 113.096373 -49.064302) (xy 113.203334 -49.132181) (xy 113.305821 -49.206641)
			(xy 113.403431 -49.28739) (xy 113.495778 -49.374108) (xy 113.582497 -49.466454) (xy 113.663247 -49.564063)
			(xy 113.737708 -49.666549) (xy 113.805588 -49.773509) (xy 113.866617 -49.88452) (xy 113.920555 -49.999144)
			(xy 113.96719 -50.116929) (xy 114.006336 -50.237409) (xy 114.037841 -50.36011) (xy 114.061579 -50.484547)
			(xy 114.077456 -50.610229) (xy 114.08541 -50.73666) (xy 114.085878 -50.8) (xy 114.085878 -51.176936)
			(xy 114.086425 -51.193582) (xy 114.095049 -51.225739) (xy 114.111699 -51.254569) (xy 114.135242 -51.278109)
			(xy 114.164074 -51.294756) (xy 114.196232 -51.303376) (xy 114.212878 -51.303936) (xy 132.84708 -51.303936)
			(xy 132.863732 -51.303395) (xy 132.895902 -51.294781) (xy 132.924747 -51.278135) (xy 132.948301 -51.254592)
			(xy 132.96496 -51.225754) (xy 132.973588 -51.193588) (xy 132.97408 -51.176936) (xy 132.97408 -50.8)
			(xy 132.974578 -50.73666) (xy 132.982532 -50.61023) (xy 132.998409 -50.484549) (xy 133.022146 -50.360113)
			(xy 133.05365 -50.237413) (xy 133.092796 -50.116934) (xy 133.139429 -49.99915) (xy 133.193367 -49.884526)
			(xy 133.254395 -49.773516) (xy 133.322273 -49.666556) (xy 133.396733 -49.56407) (xy 133.477481 -49.466461)
			(xy 133.564199 -49.374115) (xy 133.656544 -49.287396) (xy 133.754152 -49.206646) (xy 133.856638 -49.132185)
			(xy 133.963597 -49.064306) (xy 134.074606 -49.003277) (xy 134.189229 -48.949338) (xy 134.307013 -48.902703)
			(xy 134.427492 -48.863556) (xy 134.550192 -48.832051) (xy 134.674628 -48.808312) (xy 134.800308 -48.792434)
			(xy 134.926738 -48.784478) (xy 134.990078 -48.784002) (xy 149.990048 -48.784002) (xy 150.053387 -48.784501)
			(xy 150.179814 -48.792458) (xy 150.305492 -48.808338) (xy 150.429925 -48.832077) (xy 150.552622 -48.863583)
			(xy 150.673099 -48.902731) (xy 150.79088 -48.949366) (xy 150.9055 -49.003305) (xy 151.016507 -49.064334)
			(xy 151.123463 -49.132212) (xy 151.225946 -49.206673) (xy 151.323552 -49.287422) (xy 151.415895 -49.374139)
			(xy 151.50261 -49.466484) (xy 151.583356 -49.564092) (xy 151.657815 -49.666576) (xy 151.725691 -49.773534)
			(xy 151.786717 -49.884543) (xy 151.840653 -49.999165) (xy 151.887285 -50.116946) (xy 151.92643 -50.237424)
			(xy 151.957933 -50.360122) (xy 151.98167 -50.484555) (xy 151.997546 -50.610234) (xy 152.005501 -50.736661)
			(xy 152.006046 -50.8) (xy 152.006046 -51.176936) (xy 152.006545 -51.193585) (xy 152.015173 -51.225747)
			(xy 152.031832 -51.25458) (xy 152.055385 -51.278119) (xy 152.084229 -51.294758) (xy 152.116396 -51.303366)
			(xy 152.133046 -51.303936) (xy 158.856172 -51.303936) (xy 158.873545 -51.303415) (xy 158.907007 -51.294061)
			(xy 158.936696 -51.276013) (xy 158.960405 -51.250615) (xy 158.976369 -51.219755) (xy 158.980378 -51.202844)
			(xy 158.99003 -51.156616) (xy 159.12465 -50.580036) (xy 159.334454 -50.272696) (xy 159.378142 -50.060606)
			(xy 159.562546 -49.93894) (xy 159.68726 -49.756568) (xy 159.899858 -49.716436) (xy 160.218882 -49.506124)
			(xy 160.89122 -49.374044) (xy 202.680316 -49.374044) (xy 202.772772 -49.312068) (xy 203.088748 -49.374044)
			(xy 203.41082 -49.374044) (xy 203.48956 -49.452784) (xy 203.761086 -49.506124) (xy 204.08011 -49.716436)
			(xy 204.292708 -49.756568) (xy 204.417422 -49.93894) (xy 204.601826 -50.060606) (xy 204.645514 -50.272696)
			(xy 204.855318 -50.580036) (xy 204.989938 -51.156616) (xy 204.99959 -51.202844) (xy 205.003719 -51.219706)
			(xy 205.01971 -51.250502) (xy 205.043401 -51.275856) (xy 205.073043 -51.293897) (xy 205.106447 -51.303292)
			(xy 205.123796 -51.303936) (xy 207.437482 -51.303936) (xy 207.460633 -51.303399) (xy 207.506161 -51.294958)
			(xy 207.549405 -51.278408) (xy 207.588935 -51.254296) (xy 207.623441 -51.22342) (xy 207.651781 -51.186803)
			(xy 207.673018 -51.145656) (xy 207.686447 -51.101343) (xy 207.691624 -51.05533) (xy 207.688379 -51.009141)
			(xy 207.676817 -50.964304) (xy 207.657323 -50.922304) (xy 207.630541 -50.884532) (xy 207.597358 -50.852239)
			(xy 207.578452 -50.838862) (xy 207.504712 -50.788993) (xy 207.36122 -50.683603) (xy 207.222539 -50.571958)
			(xy 207.088943 -50.454277) (xy 206.960692 -50.330791) (xy 206.838041 -50.201743) (xy 206.721228 -50.067386)
			(xy 206.610485 -49.927984) (xy 206.506028 -49.783811) (xy 206.408063 -49.635151) (xy 206.316783 -49.482296)
			(xy 206.232366 -49.325545) (xy 206.154979 -49.165207) (xy 206.084773 -49.001598) (xy 206.021888 -48.835038)
			(xy 205.966445 -48.665854) (xy 205.918554 -48.49438) (xy 205.87831 -48.320952) (xy 205.845791 -48.14591)
			(xy 205.821061 -47.9696) (xy 205.804168 -47.792367) (xy 205.795147 -47.614559) (xy 205.794015 -47.436526)
			(xy 205.800773 -47.258618) (xy 205.815409 -47.081185) (xy 205.837894 -46.904574) (xy 205.868184 -46.729133)
			(xy 205.906218 -46.555207) (xy 205.951924 -46.383137) (xy 206.00521 -46.213262) (xy 206.065971 -46.045915)
			(xy 206.13409 -45.881426) (xy 206.209431 -45.720116) (xy 206.291847 -45.562305) (xy 206.381175 -45.4083)
			(xy 206.477241 -45.258406) (xy 206.579855 -45.112916) (xy 206.688816 -44.972116) (xy 206.803909 -44.836284)
			(xy 206.924909 -44.705686) (xy 206.987902 -44.642786) (xy 207.005682 -44.625006) (xy 207.044036 -44.534328)
			(xy 207.044036 -41.54932) (xy 207.044036 -41.45026) (xy 207.044036 -41.286938) (xy 207.05191 -41.279064)
			(xy 207.056482 -41.233598) (xy 207.056482 -41.233344) (xy 207.064089 -41.159841) (xy 207.086165 -41.013711)
			(xy 207.116012 -40.868968) (xy 207.153546 -40.726025) (xy 207.198659 -40.58529) (xy 207.251222 -40.447166)
			(xy 207.311086 -40.312045) (xy 207.37808 -40.180313) (xy 207.452013 -40.052347) (xy 207.532673 -39.928511)
			(xy 207.619831 -39.809159) (xy 207.713237 -39.694631) (xy 207.812626 -39.585254) (xy 207.917714 -39.481341)
			(xy 208.0282 -39.383187) (xy 208.14377 -39.291073) (xy 208.264094 -39.205262) (xy 208.388828 -39.125998)
			(xy 208.517617 -39.053508) (xy 208.650093 -38.987998) (xy 208.785878 -38.929656) (xy 208.924585 -38.878648)
			(xy 209.065817 -38.835119) (xy 209.209172 -38.799193) (xy 209.354242 -38.770974) (xy 209.500611 -38.750541)
			(xy 209.647862 -38.737954) (xy 209.795575 -38.733247) (xy 209.943329 -38.736435) (xy 210.090702 -38.747508)
			(xy 210.237274 -38.766434) (xy 210.382625 -38.79316) (xy 210.526343 -38.827609) (xy 210.668015 -38.869684)
			(xy 210.807239 -38.919263) (xy 210.943617 -38.976206) (xy 211.076759 -39.04035) (xy 211.206287 -39.111512)
			(xy 211.331829 -39.189489) (xy 211.453029 -39.274059) (xy 211.56954 -39.36498) (xy 211.68103 -39.461992)
			(xy 211.78718 -39.564819) (xy 211.887689 -39.673168) (xy 211.982268 -39.78673) (xy 212.070648 -39.905179)
			(xy 212.152578 -40.028179) (xy 212.227822 -40.155378) (xy 212.296167 -40.286414) (xy 212.357418 -40.420912)
			(xy 212.411399 -40.558489) (xy 212.457956 -40.698752) (xy 212.496958 -40.841302) (xy 212.528292 -40.98573)
			(xy 212.551869 -41.131626) (xy 212.567622 -41.278572) (xy 212.575506 -41.42615) (xy 212.575902 -41.500044)
			(xy 212.575902 -44.534328) (xy 212.614256 -44.625006) (xy 212.632036 -44.642786) (xy 212.69503 -44.705686)
			(xy 212.816034 -44.836282) (xy 212.931132 -44.972112) (xy 213.040097 -45.112909) (xy 213.142715 -45.258398)
			(xy 213.238784 -45.408291) (xy 213.328116 -45.562295) (xy 213.410535 -45.720106) (xy 213.485879 -45.881415)
			(xy 213.554 -46.045905) (xy 213.614765 -46.213252) (xy 213.668053 -46.383128) (xy 213.71376 -46.555198)
			(xy 213.751797 -46.729125) (xy 213.782088 -46.904567) (xy 213.804574 -47.081178) (xy 213.819211 -47.258613)
			(xy 213.82597 -47.436522) (xy 213.824837 -47.614556) (xy 213.815816 -47.792365) (xy 213.798923 -47.969599)
			(xy 213.774192 -48.145911) (xy 213.741672 -48.320953) (xy 213.701426 -48.494382) (xy 213.653533 -48.665857)
			(xy 213.598089 -48.835041) (xy 213.5352 -49.001601) (xy 213.464992 -49.165211) (xy 213.387602 -49.325549)
			(xy 213.303182 -49.482299) (xy 213.211899 -49.635154) (xy 213.11393 -49.783813) (xy 213.00947 -49.927984)
			(xy 212.898723 -50.067384) (xy 212.781906 -50.201739) (xy 212.65925 -50.330785) (xy 212.530996 -50.454269)
			(xy 212.397395 -50.571947) (xy 212.25871 -50.683588) (xy 212.115213 -50.788974) (xy 212.041486 -50.838862)
			(xy 212.022522 -50.852168) (xy 211.989333 -50.884479) (xy 211.96255 -50.922272) (xy 211.943062 -50.964293)
			(xy 211.931514 -51.009151) (xy 211.928289 -51.05536) (xy 211.933493 -51.101387) (xy 211.946955 -51.145708)
			(xy 211.968228 -51.186855) (xy 211.996607 -51.223464) (xy 212.031152 -51.254322) (xy 212.070719 -51.278407)
			(xy 212.113996 -51.29492) (xy 212.15955 -51.303315) (xy 212.18271 -51.303936) (xy 298.437554 -51.303936)
			(xy 298.460707 -51.303401) (xy 298.506239 -51.294964) (xy 298.549488 -51.278416) (xy 298.589023 -51.254305)
			(xy 298.623533 -51.223428) (xy 298.651877 -51.186809) (xy 298.673116 -51.14566) (xy 298.686547 -51.101344)
			(xy 298.691724 -51.055327) (xy 298.688477 -51.009134) (xy 298.676914 -50.964294) (xy 298.657416 -50.922292)
			(xy 298.630629 -50.884519) (xy 298.597441 -50.852225) (xy 298.578524 -50.838862) (xy 298.504785 -50.788992)
			(xy 298.361293 -50.683603) (xy 298.222614 -50.571957) (xy 298.089018 -50.454276) (xy 297.960768 -50.330789)
			(xy 297.838117 -50.201741) (xy 297.721306 -50.067383) (xy 297.610563 -49.927981) (xy 297.506107 -49.783809)
			(xy 297.408143 -49.635149) (xy 297.316863 -49.482293) (xy 297.232447 -49.325543) (xy 297.155061 -49.165205)
			(xy 297.084856 -49.001596) (xy 297.02197 -48.835036) (xy 296.966528 -48.665852) (xy 296.918638 -48.494378)
			(xy 296.878394 -48.320951) (xy 296.845875 -48.14591) (xy 296.821145 -47.9696) (xy 296.804253 -47.792367)
			(xy 296.795232 -47.614559) (xy 296.794099 -47.436527) (xy 296.800857 -47.258619) (xy 296.815493 -47.081186)
			(xy 296.837978 -46.904576) (xy 296.868267 -46.729135) (xy 296.906302 -46.555209) (xy 296.952007 -46.38314)
			(xy 297.005292 -46.213265) (xy 297.066053 -46.045919) (xy 297.134171 -45.881429) (xy 297.209512 -45.72012)
			(xy 297.291927 -45.562308) (xy 297.381254 -45.408304) (xy 297.477319 -45.258409) (xy 297.579933 -45.11292)
			(xy 297.688893 -44.97212) (xy 297.803985 -44.836287) (xy 297.924985 -44.705689) (xy 297.987974 -44.642786)
			(xy 298.005754 -44.625006) (xy 298.044108 -44.534328) (xy 298.044108 -41.54932) (xy 298.044108 -41.45026)
			(xy 298.044108 -41.286938) (xy 298.051982 -41.279064) (xy 298.056554 -41.233598) (xy 298.056554 -41.233344)
			(xy 298.064161 -41.159843) (xy 298.086236 -41.013716) (xy 298.116083 -40.868977) (xy 298.153616 -40.726039)
			(xy 298.198728 -40.585308) (xy 298.251291 -40.447187) (xy 298.311154 -40.31207) (xy 298.378146 -40.180342)
			(xy 298.452077 -40.052379) (xy 298.532735 -39.928547) (xy 298.619891 -39.809198) (xy 298.713295 -39.694674)
			(xy 298.812682 -39.5853) (xy 298.917767 -39.48139) (xy 299.02825 -39.383239) (xy 299.143817 -39.291128)
			(xy 299.264138 -39.205319) (xy 299.388869 -39.126057) (xy 299.517655 -39.053569) (xy 299.650127 -38.988062)
			(xy 299.785909 -38.929721) (xy 299.924612 -38.878714) (xy 300.06584 -38.835187) (xy 300.209192 -38.799262)
			(xy 300.354257 -38.771044) (xy 300.500623 -38.750612) (xy 300.64787 -38.738025) (xy 300.795579 -38.733319)
			(xy 300.943329 -38.736507) (xy 301.090698 -38.747579) (xy 301.237266 -38.766505) (xy 301.382614 -38.793231)
			(xy 301.526327 -38.827679) (xy 301.667996 -38.869753) (xy 301.807216 -38.919331) (xy 301.94359 -38.976273)
			(xy 302.076729 -39.040415) (xy 302.206253 -39.111575) (xy 302.331792 -39.189551) (xy 302.452988 -39.274118)
			(xy 302.569496 -39.365036) (xy 302.680983 -39.462046) (xy 302.78713 -39.564871) (xy 302.887636 -39.673217)
			(xy 302.982213 -39.786775) (xy 303.070591 -39.905222) (xy 303.152518 -40.028218) (xy 303.22776 -40.155414)
			(xy 303.296103 -40.286446) (xy 303.357352 -40.420941) (xy 303.411332 -40.558514) (xy 303.457888 -40.698774)
			(xy 303.496889 -40.841319) (xy 303.528222 -40.985744) (xy 303.551798 -41.131635) (xy 303.567551 -41.278578)
			(xy 303.575435 -41.426152) (xy 303.575974 -41.500044) (xy 303.575974 -44.534328) (xy 303.614328 -44.625006)
			(xy 303.632108 -44.642786) (xy 303.695101 -44.705686) (xy 303.816103 -44.836283) (xy 303.898088 -44.933038)
			(xy 336.785706 -44.933038) (xy 336.785706 -44.805162) (xy 336.793735 -44.677538) (xy 336.809763 -44.55067)
			(xy 336.833724 -44.425058) (xy 336.865526 -44.3012) (xy 336.905042 -44.179582) (xy 336.952116 -44.060685)
			(xy 337.006563 -43.944979) (xy 337.068168 -43.83292) (xy 337.136688 -43.724951) (xy 337.211852 -43.621497)
			(xy 337.293363 -43.522966) (xy 337.3809 -43.429748) (xy 337.474118 -43.342211) (xy 337.572649 -43.2607)
			(xy 337.676103 -43.185536) (xy 337.784072 -43.117016) (xy 337.896131 -43.055411) (xy 338.011837 -43.000964)
			(xy 338.130734 -42.95389) (xy 338.252352 -42.914374) (xy 338.37621 -42.882572) (xy 338.501822 -42.858611)
			(xy 338.62869 -42.842583) (xy 338.756314 -42.834554) (xy 338.88419 -42.834554) (xy 339.011814 -42.842583)
			(xy 339.138682 -42.858611) (xy 339.264294 -42.882572) (xy 339.388152 -42.914374) (xy 339.50977 -42.95389)
			(xy 339.628667 -43.000964) (xy 339.744373 -43.055411) (xy 339.856432 -43.117016) (xy 339.964401 -43.185536)
			(xy 340.067855 -43.2607) (xy 340.166386 -43.342211) (xy 340.259604 -43.429748) (xy 340.347141 -43.522966)
			(xy 340.428652 -43.621497) (xy 340.503816 -43.724951) (xy 340.572336 -43.83292) (xy 340.633941 -43.944979)
			(xy 340.688388 -44.060685) (xy 340.735462 -44.179582) (xy 340.774978 -44.3012) (xy 340.80678 -44.425058)
			(xy 340.830741 -44.55067) (xy 340.846769 -44.677538) (xy 340.854798 -44.805162) (xy 340.8553 -44.8691)
			(xy 340.854798 -44.932982) (xy 348.217484 -44.932982) (xy 348.217484 -44.805218) (xy 348.225506 -44.677705)
			(xy 348.241519 -44.550948) (xy 348.26546 -44.425446) (xy 348.297234 -44.301696) (xy 348.336715 -44.180184)
			(xy 348.383748 -44.061392) (xy 348.438148 -43.945787) (xy 348.499699 -43.833826) (xy 348.568159 -43.725951)
			(xy 348.643257 -43.622587) (xy 348.724697 -43.524142) (xy 348.812158 -43.431006) (xy 348.905294 -43.343545)
			(xy 349.003739 -43.262105) (xy 349.107103 -43.187007) (xy 349.214978 -43.118547) (xy 349.326939 -43.056996)
			(xy 349.442544 -43.002596) (xy 349.561336 -42.955563) (xy 349.682848 -42.916082) (xy 349.806598 -42.884308)
			(xy 349.9321 -42.860367) (xy 350.058857 -42.844354) (xy 350.18637 -42.836332) (xy 350.314134 -42.836332)
			(xy 350.441647 -42.844354) (xy 350.568404 -42.860367) (xy 350.693906 -42.884308) (xy 350.817656 -42.916082)
			(xy 350.939168 -42.955563) (xy 351.05796 -43.002596) (xy 351.173565 -43.056996) (xy 351.285526 -43.118547)
			(xy 351.393401 -43.187007) (xy 351.496765 -43.262105) (xy 351.59521 -43.343545) (xy 351.688346 -43.431006)
			(xy 351.775807 -43.524142) (xy 351.857247 -43.622587) (xy 351.932345 -43.725951) (xy 352.000805 -43.833826)
			(xy 352.062356 -43.945787) (xy 352.116756 -44.061392) (xy 352.163789 -44.180184) (xy 352.20327 -44.301696)
			(xy 352.235044 -44.425446) (xy 352.258985 -44.550948) (xy 352.274998 -44.677705) (xy 352.28302 -44.805218)
			(xy 352.283522 -44.8691) (xy 352.28302 -44.932982) (xy 352.274998 -45.060495) (xy 352.258985 -45.187252)
			(xy 352.235044 -45.312754) (xy 352.20327 -45.436504) (xy 352.163789 -45.558016) (xy 352.116756 -45.676808)
			(xy 352.062356 -45.792413) (xy 352.000805 -45.904374) (xy 351.932345 -46.012249) (xy 351.857247 -46.115613)
			(xy 351.775807 -46.214058) (xy 351.688346 -46.307194) (xy 351.59521 -46.394655) (xy 351.496765 -46.476095)
			(xy 351.393401 -46.551193) (xy 351.285526 -46.619653) (xy 351.173565 -46.681204) (xy 351.05796 -46.735604)
			(xy 350.939168 -46.782637) (xy 350.817656 -46.822118) (xy 350.693906 -46.853892) (xy 350.568404 -46.877833)
			(xy 350.441647 -46.893846) (xy 350.314134 -46.901868) (xy 350.18637 -46.901868) (xy 350.058857 -46.893846)
			(xy 349.9321 -46.877833) (xy 349.806598 -46.853892) (xy 349.682848 -46.822118) (xy 349.561336 -46.782637)
			(xy 349.442544 -46.735604) (xy 349.326939 -46.681204) (xy 349.214978 -46.619653) (xy 349.107103 -46.551193)
			(xy 349.003739 -46.476095) (xy 348.905294 -46.394655) (xy 348.812158 -46.307194) (xy 348.724697 -46.214058)
			(xy 348.643257 -46.115613) (xy 348.568159 -46.012249) (xy 348.499699 -45.904374) (xy 348.438148 -45.792413)
			(xy 348.383748 -45.676808) (xy 348.336715 -45.558016) (xy 348.297234 -45.436504) (xy 348.26546 -45.312754)
			(xy 348.241519 -45.187252) (xy 348.225506 -45.060495) (xy 348.217484 -44.932982) (xy 340.854798 -44.932982)
			(xy 340.854798 -44.933038) (xy 340.846769 -45.060662) (xy 340.830741 -45.18753) (xy 340.80678 -45.313142)
			(xy 340.774978 -45.437) (xy 340.735462 -45.558618) (xy 340.688388 -45.677515) (xy 340.633941 -45.793221)
			(xy 340.572336 -45.90528) (xy 340.503816 -46.013249) (xy 340.428652 -46.116703) (xy 340.347141 -46.215234)
			(xy 340.259604 -46.308452) (xy 340.166386 -46.395989) (xy 340.067855 -46.4775) (xy 339.964401 -46.552664)
			(xy 339.856432 -46.621184) (xy 339.744373 -46.682789) (xy 339.628667 -46.737236) (xy 339.50977 -46.78431)
			(xy 339.388152 -46.823826) (xy 339.264294 -46.855628) (xy 339.138682 -46.879589) (xy 339.011814 -46.895617)
			(xy 338.88419 -46.903646) (xy 338.756314 -46.903646) (xy 338.62869 -46.895617) (xy 338.501822 -46.879589)
			(xy 338.37621 -46.855628) (xy 338.252352 -46.823826) (xy 338.130734 -46.78431) (xy 338.011837 -46.737236)
			(xy 337.896131 -46.682789) (xy 337.784072 -46.621184) (xy 337.676103 -46.552664) (xy 337.572649 -46.4775)
			(xy 337.474118 -46.395989) (xy 337.3809 -46.308452) (xy 337.293363 -46.215234) (xy 337.211852 -46.116703)
			(xy 337.136688 -46.013249) (xy 337.068168 -45.90528) (xy 337.006563 -45.793221) (xy 336.952116 -45.677515)
			(xy 336.905042 -45.558618) (xy 336.865526 -45.437) (xy 336.833724 -45.313142) (xy 336.809763 -45.18753)
			(xy 336.793735 -45.060662) (xy 336.785706 -44.933038) (xy 303.898088 -44.933038) (xy 303.931199 -44.972114)
			(xy 304.040162 -45.112913) (xy 304.142778 -45.258402) (xy 304.238846 -45.408296) (xy 304.328176 -45.5623)
			(xy 304.410594 -45.720111) (xy 304.485937 -45.88142) (xy 304.554057 -46.04591) (xy 304.61482 -46.213257)
			(xy 304.668107 -46.383132) (xy 304.713813 -46.555202) (xy 304.751849 -46.729129) (xy 304.78214 -46.90457)
			(xy 304.804625 -47.081181) (xy 304.819262 -47.258615) (xy 304.82602 -47.436524) (xy 304.824888 -47.614557)
			(xy 304.815866 -47.792366) (xy 304.798974 -47.969599) (xy 304.774243 -48.14591) (xy 304.741724 -48.320952)
			(xy 304.701478 -48.494381) (xy 304.653587 -48.665855) (xy 304.598143 -48.835039) (xy 304.535256 -49.001599)
			(xy 304.465049 -49.165209) (xy 304.38766 -49.325547) (xy 304.303242 -49.482297) (xy 304.211959 -49.635152)
			(xy 304.113992 -49.783812) (xy 304.009534 -49.927984) (xy 303.898788 -50.067384) (xy 303.781974 -50.20174)
			(xy 303.65932 -50.330787) (xy 303.531067 -50.454272) (xy 303.397468 -50.571951) (xy 303.258785 -50.683594)
			(xy 303.11529 -50.788981) (xy 303.041558 -50.838862) (xy 303.022596 -50.852169) (xy 302.989409 -50.884483)
			(xy 302.962629 -50.922276) (xy 302.943144 -50.964298) (xy 302.931597 -51.009156) (xy 302.928373 -51.055363)
			(xy 302.933578 -51.101389) (xy 302.947039 -51.14571) (xy 302.96831 -51.186857) (xy 302.996688 -51.223466)
			(xy 303.031231 -51.254325) (xy 303.070795 -51.278412) (xy 303.11407 -51.294929) (xy 303.159622 -51.303328)
			(xy 303.182782 -51.303936) (xy 315.926978 -51.303936) (xy 315.94363 -51.303396) (xy 315.975801 -51.294782)
			(xy 316.004646 -51.278136) (xy 316.028201 -51.254592) (xy 316.04486 -51.225754) (xy 316.053488 -51.193588)
			(xy 316.053978 -51.176936) (xy 316.053978 -50.8) (xy 316.054476 -50.73666) (xy 316.06243 -50.61023)
			(xy 316.078307 -50.484549) (xy 316.102044 -50.360113) (xy 316.133548 -50.237413) (xy 316.172694 -50.116933)
			(xy 316.219327 -49.999149) (xy 316.273265 -49.884526) (xy 316.334293 -49.773515) (xy 316.402171 -49.666555)
			(xy 316.476631 -49.564069) (xy 316.557379 -49.46646) (xy 316.644097 -49.374114) (xy 316.736442 -49.287395)
			(xy 316.83405 -49.206646) (xy 316.936536 -49.132184) (xy 317.043494 -49.064305) (xy 317.154504 -49.003276)
			(xy 317.269127 -48.949337) (xy 317.386911 -48.902702) (xy 317.50739 -48.863555) (xy 317.63009 -48.832049)
			(xy 317.754526 -48.808311) (xy 317.880206 -48.792432) (xy 318.006636 -48.784476) (xy 318.069976 -48.784002)
			(xy 333.069946 -48.784002) (xy 333.133285 -48.784501) (xy 333.259712 -48.792458) (xy 333.38539 -48.808337)
			(xy 333.509823 -48.832077) (xy 333.632521 -48.863583) (xy 333.752997 -48.90273) (xy 333.870778 -48.949365)
			(xy 333.985398 -49.003304) (xy 334.096406 -49.064333) (xy 334.203362 -49.132212) (xy 334.305845 -49.206672)
			(xy 334.403451 -49.287421) (xy 334.495794 -49.374139) (xy 334.58251 -49.466483) (xy 334.663256 -49.564091)
			(xy 334.737714 -49.666576) (xy 334.80559 -49.773534) (xy 334.866617 -49.884542) (xy 334.920553 -49.999164)
			(xy 334.967185 -50.116946) (xy 335.00633 -50.237424) (xy 335.037833 -50.360121) (xy 335.06157 -50.484555)
			(xy 335.077446 -50.610234) (xy 335.085401 -50.736661) (xy 335.085944 -50.8) (xy 335.085944 -51.176936)
			(xy 335.086443 -51.193586) (xy 335.095071 -51.225748) (xy 335.111729 -51.254581) (xy 335.135283 -51.278119)
			(xy 335.164127 -51.29476) (xy 335.196294 -51.303367) (xy 335.212944 -51.303936) (xy 353.846892 -51.303936)
			(xy 353.863543 -51.303394) (xy 353.89571 -51.294778) (xy 353.924553 -51.278131) (xy 353.948104 -51.254588)
			(xy 353.964761 -51.225751) (xy 353.973388 -51.193587) (xy 353.973892 -51.176936) (xy 353.973892 -50.8)
			(xy 353.97439 -50.73666) (xy 353.982344 -50.610231) (xy 353.998221 -50.48455) (xy 354.021958 -50.360114)
			(xy 354.053462 -50.237415) (xy 354.092608 -50.116935) (xy 354.139242 -49.999151) (xy 354.193179 -49.884528)
			(xy 354.254207 -49.773518) (xy 354.322085 -49.666559) (xy 354.396545 -49.564073) (xy 354.477294 -49.466464)
			(xy 354.564012 -49.374119) (xy 354.656357 -49.2874) (xy 354.753965 -49.206652) (xy 354.856451 -49.132191)
			(xy 354.96341 -49.064312) (xy 355.074419 -49.003284) (xy 355.189042 -48.949346) (xy 355.306826 -48.902711)
			(xy 355.427305 -48.863565) (xy 355.550005 -48.83206) (xy 355.67444 -48.808322) (xy 355.800121 -48.792445)
			(xy 355.92655 -48.78449) (xy 355.98989 -48.784002) (xy 370.98986 -48.784002) (xy 371.053201 -48.784488)
			(xy 371.179632 -48.79244) (xy 371.305315 -48.808315) (xy 371.429753 -48.832051) (xy 371.552456 -48.863553)
			(xy 371.672938 -48.902698) (xy 371.790724 -48.949331) (xy 371.905349 -49.003268) (xy 372.016362 -49.064296)
			(xy 372.123324 -49.132174) (xy 372.225812 -49.206634) (xy 372.323423 -49.287383) (xy 372.415771 -49.374101)
			(xy 372.502491 -49.466447) (xy 372.583242 -49.564056) (xy 372.657704 -49.666543) (xy 372.725584 -49.773503)
			(xy 372.786614 -49.884515) (xy 372.840553 -49.99914) (xy 372.887188 -50.116925) (xy 372.926335 -50.237406)
			(xy 372.95784 -50.360107) (xy 372.981578 -50.484545) (xy 372.997456 -50.610228) (xy 373.00541 -50.736659)
			(xy 373.005858 -50.8) (xy 373.005858 -51.176936) (xy 373.006405 -51.193583) (xy 373.015029 -51.225742)
			(xy 373.031678 -51.254575) (xy 373.055221 -51.278118) (xy 373.084053 -51.294769) (xy 373.116211 -51.303394)
			(xy 373.132858 -51.303936) (xy 379.856238 -51.303936) (xy 379.873605 -51.303407) (xy 379.907053 -51.294041)
			(xy 379.936727 -51.275988) (xy 379.960422 -51.250591) (xy 379.976376 -51.219737) (xy 379.980444 -51.202844)
			(xy 379.990096 -51.156616) (xy 380.124716 -50.580036) (xy 380.687326 -49.756568) (xy 380.899924 -49.716436)
			(xy 381.218948 -49.506124) (xy 381.891286 -49.374044) (xy 425.61002 -49.374044) (xy 425.655489 -49.373518)
			(xy 425.746038 -49.365126) (xy 425.835427 -49.348415) (xy 425.922893 -49.323528) (xy 426.00769 -49.290677)
			(xy 426.089094 -49.250143) (xy 426.166411 -49.202271) (xy 426.238981 -49.147469) (xy 426.306186 -49.086206)
			(xy 426.367451 -49.019003) (xy 426.422255 -48.946434) (xy 426.470129 -48.869119) (xy 426.510666 -48.787716)
			(xy 426.543519 -48.70292) (xy 426.568409 -48.615455) (xy 426.585122 -48.526066) (xy 426.593517 -48.435517)
			(xy 426.594016 -48.390048) (xy 426.594016 -44.114212) (xy 426.594098 -44.084986) (xy 426.595748 -44.026556)
			(xy 426.597318 -43.997372) (xy 426.597572 -43.993816) (xy 426.597572 -42.65549) (xy 426.48632 -42.544238)
			(xy 426.443394 -42.544238) (xy 426.4152 -42.516044) (xy 424.589194 -42.516044) (xy 423.994072 -41.920922)
			(xy 423.994072 -30.484064) (xy 426.4406 -30.484064) (xy 426.457253 -30.483569) (xy 426.489424 -30.474948)
			(xy 426.518266 -30.458292) (xy 426.541814 -30.434737) (xy 426.558461 -30.40589) (xy 426.567074 -30.373717)
			(xy 426.5676 -30.357064) (xy 426.5676 -10.3378) (xy 427.4058 -9.4996) (xy 427.666912 -9.4996) (xy 427.683559 -9.499055)
			(xy 427.715719 -9.490436) (xy 427.744552 -9.473786) (xy 427.768094 -9.450242) (xy 427.78474 -9.421408)
			(xy 427.793357 -9.389247) (xy 427.793912 -9.3726) (xy 427.793912 -7.493) (xy 427.793369 -7.476351)
			(xy 427.784751 -7.444188) (xy 427.768103 -7.41535) (xy 427.744559 -7.391804) (xy 427.715723 -7.375153)
			(xy 427.683561 -7.366533) (xy 427.666912 -7.366) (xy 427.508162 -7.366) (xy 427.45787 -7.389114)
			(xy 427.439836 -7.409942) (xy 427.380152 -7.478111) (xy 427.255646 -7.609772) (xy 427.1255 -7.735859)
			(xy 426.989961 -7.85613) (xy 426.849289 -7.970356) (xy 426.703754 -8.078317) (xy 426.553635 -8.179807)
			(xy 426.399218 -8.274632) (xy 426.240801 -8.362609) (xy 426.078686 -8.44357) (xy 425.913183 -8.51736)
			(xy 425.744611 -8.583838) (xy 425.573291 -8.642877) (xy 425.399551 -8.694363) (xy 425.223726 -8.738197)
			(xy 425.046151 -8.774297) (xy 424.956732 -8.788908) (xy 424.866524 -8.802668) (xy 424.685183 -8.823204)
			(xy 424.503113 -8.835727) (xy 424.320668 -8.840215) (xy 424.138203 -8.836659) (xy 423.956072 -8.825065)
			(xy 423.774628 -8.805456) (xy 423.594225 -8.777869) (xy 423.415213 -8.74236) (xy 423.23794 -8.698996)
			(xy 423.06275 -8.647862) (xy 422.889983 -8.589057) (xy 422.719976 -8.522696) (xy 422.553059 -8.448907)
			(xy 422.389555 -8.367834) (xy 422.229783 -8.279634) (xy 422.074053 -8.184479) (xy 421.922668 -8.082553)
			(xy 421.775922 -7.974055) (xy 421.6341 -7.859196) (xy 421.497477 -7.738198) (xy 421.366319 -7.611297)
			(xy 421.240881 -7.478739) (xy 421.121407 -7.340782) (xy 421.008128 -7.197694) (xy 420.901265 -7.049753)
			(xy 420.801026 -6.897246) (xy 420.707604 -6.74047) (xy 420.621183 -6.57973) (xy 420.541929 -6.415337)
			(xy 420.469996 -6.247611) (xy 420.405525 -6.076878) (xy 420.348641 -5.903469) (xy 420.299454 -5.727723)
			(xy 420.25806 -5.549979) (xy 420.224539 -5.370584) (xy 420.198956 -5.189886) (xy 420.181361 -5.008236)
			(xy 420.171788 -4.825987) (xy 420.170257 -4.643494) (xy 420.176769 -4.46111) (xy 420.191312 -4.27919)
			(xy 420.213858 -4.098088) (xy 420.244363 -3.918156) (xy 420.282768 -3.739743) (xy 420.328998 -3.563195)
			(xy 420.382964 -3.388856) (xy 420.44456 -3.217065) (xy 420.513667 -3.048156) (xy 420.59015 -2.882455)
			(xy 420.673861 -2.720287) (xy 420.764638 -2.561965) (xy 420.862304 -2.407797) (xy 420.966668 -2.258083)
			(xy 421.077529 -2.113114) (xy 421.194671 -1.973171) (xy 421.317866 -1.838526) (xy 421.446876 -1.709441)
			(xy 421.581448 -1.586167) (xy 421.721323 -1.468943) (xy 421.793416 -1.413002) (xy 421.817038 -1.394968)
			(xy 421.8432 -1.341882) (xy 421.8432 -1.143) (xy 421.842657 -1.126352) (xy 421.834039 -1.094189)
			(xy 421.817391 -1.065354) (xy 421.793846 -1.041809) (xy 421.765011 -1.025161) (xy 421.732848 -1.016543)
			(xy 421.7162 -1.016) (xy 388.38505 -1.016) (xy 388.369624 -1.016428) (xy 388.339676 -1.023838) (xy 388.31239 -1.038234)
			(xy 388.289368 -1.058771) (xy 388.271963 -1.084244) (xy 388.266178 -1.09855) (xy 388.260597 -1.113105)
			(xy 388.247374 -1.141335) (xy 388.239762 -1.154938) (xy 388.222998 -1.184402) (xy 388.222998 -1.218184)
			(xy 388.223491 -1.23484) (xy 388.232109 -1.267018) (xy 388.248763 -1.295869) (xy 388.272316 -1.319426)
			(xy 388.301165 -1.336084) (xy 388.333342 -1.344707) (xy 388.349998 -1.345184) (xy 388.531862 -1.345184)
			(xy 395.236446 -1.345184) (xy 396.531846 -1.345184) (xy 396.531846 -4.21386) (xy 395.236446 -4.21386)
			(xy 395.236446 -1.345184) (xy 388.531862 -1.345184) (xy 388.531862 -2.699512) (xy 393.23645 -2.699512)
			(xy 394.53185 -2.699512) (xy 394.53185 -5.468112) (xy 393.23645 -5.468112) (xy 393.23645 -2.699512)
			(xy 388.531862 -2.699512) (xy 388.531862 -4.21386) (xy 387.236462 -4.21386) (xy 387.236462 -1.345184)
			(xy 387.467602 -1.345184) (xy 387.484256 -1.344689) (xy 387.516428 -1.336067) (xy 387.545273 -1.319412)
			(xy 387.568823 -1.295858) (xy 387.585474 -1.267012) (xy 387.594091 -1.234838) (xy 387.594602 -1.218184)
			(xy 387.594602 -1.184402) (xy 387.577838 -1.154938) (xy 387.570235 -1.14133) (xy 387.557007 -1.113103)
			(xy 387.551422 -1.09855) (xy 387.545609 -1.084262) (xy 387.528179 -1.058822) (xy 387.50516 -1.0383)
			(xy 387.477893 -1.023895) (xy 387.447968 -1.016444) (xy 387.43255 -1.016) (xy 120.966484 -1.016)
			(xy 120.899428 -1.065276) (xy 120.886982 -1.1049) (xy 120.877962 -1.131873) (xy 120.853056 -1.183002)
			(xy 120.820837 -1.229868) (xy 120.782017 -1.271431) (xy 120.737457 -1.306771) (xy 120.688145 -1.335104)
			(xy 120.662349 -1.345184) (xy 166.236396 -1.345184) (xy 167.531796 -1.345184) (xy 174.23638 -1.345184)
			(xy 175.53178 -1.345184) (xy 175.53178 -4.21386) (xy 174.23638 -4.21386) (xy 174.23638 -1.345184)
			(xy 167.531796 -1.345184) (xy 167.531796 -2.699512) (xy 172.236384 -2.699512) (xy 173.531784 -2.699512)
			(xy 173.531784 -5.468112) (xy 172.236384 -5.468112) (xy 172.236384 -2.699512) (xy 167.531796 -2.699512)
			(xy 167.531796 -4.21386) (xy 166.236396 -4.21386) (xy 166.236396 -1.345184) (xy 120.662349 -1.345184)
			(xy 120.635173 -1.355803) (xy 120.579715 -1.368409) (xy 120.523 -1.372642) (xy 120.466285 -1.368409)
			(xy 120.410827 -1.355803) (xy 120.357855 -1.335104) (xy 120.308543 -1.306771) (xy 120.263983 -1.271431)
			(xy 120.225163 -1.229868) (xy 120.192944 -1.183002) (xy 120.168038 -1.131873) (xy 120.159018 -1.1049)
			(xy 120.153734 -1.089679) (xy 120.136678 -1.062356) (xy 120.11332 -1.040178) (xy 120.08515 -1.02456)
			(xy 120.053965 -1.016499) (xy 120.03786 -1.016) (xy 7.1628 -1.016) (xy 7.146152 -1.016543) (xy 7.113989 -1.025161)
			(xy 7.085154 -1.041809) (xy 7.061609 -1.065354) (xy 7.044961 -1.094189) (xy 7.036343 -1.126352) (xy 7.0358 -1.143)
			(xy 7.0358 -1.367536) (xy 7.0612 -1.41986) (xy 7.08406 -1.437894) (xy 7.155289 -1.494948) (xy 7.29326 -1.614438)
			(xy 7.42586 -1.739863) (xy 7.552833 -1.870981) (xy 7.673935 -2.007539) (xy 7.788933 -2.149276) (xy 7.897606 -2.295919)
			(xy 7.999745 -2.447186) (xy 8.095154 -2.602785) (xy 8.148775 -2.699512) (xy 164.2364 -2.699512) (xy 165.5318 -2.699512)
			(xy 165.5318 -5.468112) (xy 164.2364 -5.468112) (xy 164.2364 -2.699512) (xy 8.148775 -2.699512) (xy 8.183648 -2.762418)
			(xy 8.265059 -2.925777) (xy 8.339229 -3.092549) (xy 8.406015 -3.262412) (xy 8.46529 -3.43504) (xy 8.516939 -3.610101)
			(xy 8.560863 -3.787258) (xy 8.596977 -3.966171) (xy 8.625212 -4.146495) (xy 8.645514 -4.327884) (xy 8.657843 -4.509988)
			(xy 8.662177 -4.692458) (xy 8.658505 -4.874942) (xy 8.646837 -5.05709) (xy 8.627193 -5.238551) (xy 8.599612 -5.418976)
			(xy 8.564147 -5.598018) (xy 8.520866 -5.775334) (xy 8.517135 -5.788152) (xy 101.226874 -5.788152)
			(xy 101.226874 -5.367528) (xy 101.524562 -5.06984) (xy 103.215186 -5.06984) (xy 103.512874 -5.367528)
			(xy 103.512874 -5.4356) (xy 132.4102 -5.4356) (xy 132.4102 -3.7592) (xy 132.7404 -3.429) (xy 133.1214 -3.429)
			(xy 133.4262 -3.7338) (xy 133.4262 -5.4356) (xy 133.1214 -5.7404) (xy 132.715 -5.7404) (xy 132.4102 -5.4356)
			(xy 103.512874 -5.4356) (xy 103.512874 -5.574538) (xy 127.80518 -5.574538) (xy 129.25298 -5.574538)
			(xy 129.25298 -5.9182) (xy 143.9418 -5.9182) (xy 143.9418 -5.5118) (xy 144.272 -5.1816) (xy 145.923 -5.1816)
			(xy 146.2278 -5.4864) (xy 146.2278 -5.545328) (xy 166.236396 -5.545328) (xy 167.531796 -5.545328)
			(xy 170.236388 -5.545328) (xy 171.531788 -5.545328) (xy 174.23638 -5.545328) (xy 175.53178 -5.545328)
			(xy 175.53178 -8.414004) (xy 174.23638 -8.414004) (xy 174.23638 -5.545328) (xy 171.531788 -5.545328)
			(xy 171.531788 -6.899656) (xy 172.236384 -6.899656) (xy 173.531784 -6.899656) (xy 173.531784 -9.668256)
			(xy 172.236384 -9.668256) (xy 172.236384 -6.899656) (xy 171.531788 -6.899656) (xy 171.531788 -8.414004)
			(xy 170.236388 -8.414004) (xy 170.236388 -5.545328) (xy 167.531796 -5.545328) (xy 167.531796 -6.899656)
			(xy 168.236392 -6.899656) (xy 169.531792 -6.899656) (xy 169.531792 -9.668256) (xy 168.236392 -9.668256)
			(xy 168.236392 -6.899656) (xy 167.531796 -6.899656) (xy 167.531796 -8.414004) (xy 166.236396 -8.414004)
			(xy 166.236396 -5.545328) (xy 146.2278 -5.545328) (xy 146.2278 -5.9436) (xy 145.9484 -6.223) (xy 144.2466 -6.223)
			(xy 143.9418 -5.9182) (xy 129.25298 -5.9182) (xy 129.25298 -6.899656) (xy 164.2364 -6.899656) (xy 165.5318 -6.899656)
			(xy 165.5318 -9.668256) (xy 164.2364 -9.668256) (xy 164.2364 -6.899656) (xy 129.25298 -6.899656)
			(xy 129.25298 -8.393938) (xy 127.80518 -8.393938) (xy 127.80518 -5.574538) (xy 103.512874 -5.574538)
			(xy 103.512874 -5.788152) (xy 103.215186 -6.08584) (xy 101.524562 -6.08584) (xy 101.226874 -5.788152)
			(xy 8.517135 -5.788152) (xy 8.469853 -5.950581) (xy 8.411204 -6.123423) (xy 8.345035 -6.293527) (xy 8.27147 -6.460567)
			(xy 8.190653 -6.62422) (xy 8.102737 -6.784173) (xy 8.007894 -6.940117) (xy 7.906304 -7.091754) (xy 7.798164 -7.23879)
			(xy 7.68368 -7.380943) (xy 7.57877 -7.500112) (xy 9.403341 -7.500112) (xy 9.407346 -7.412204) (xy 9.419329 -7.325024)
			(xy 9.439189 -7.239295) (xy 9.466764 -7.155727) (xy 9.501823 -7.075013) (xy 9.544076 -6.997821) (xy 9.593174 -6.924792)
			(xy 9.64871 -6.85653) (xy 9.710222 -6.7936) (xy 9.777203 -6.736526) (xy 9.849096 -6.685778) (xy 9.925305 -6.641778)
			(xy 10.0052 -6.604891) (xy 10.088119 -6.575422) (xy 10.173374 -6.553615) (xy 10.260258 -6.539651)
			(xy 10.348052 -6.533645) (xy 10.436029 -6.535649) (xy 10.523459 -6.545644) (xy 10.609618 -6.563548)
			(xy 10.693792 -6.589212) (xy 10.775283 -6.622425) (xy 10.853417 -6.662911) (xy 10.927545 -6.710333)
			(xy 10.997053 -6.7643) (xy 11.061367 -6.824365) (xy 11.106105 -6.87451) (xy 117.8052 -6.87451) (xy 119.253 -6.87451)
			(xy 119.253 -9.0678) (xy 139.3698 -9.0678) (xy 141.1986 -9.0678) (xy 144.169892 -9.0678) (xy 145.998692 -9.0678)
			(xy 145.998692 -9.745472) (xy 166.236396 -9.745472) (xy 167.531796 -9.745472) (xy 170.236388 -9.745472)
			(xy 171.531788 -9.745472) (xy 174.23638 -9.745472) (xy 175.53178 -9.745472) (xy 175.53178 -10.636885)
			(xy 195.033965 -10.636885) (xy 195.040797 -10.457527) (xy 195.055635 -10.278653) (xy 195.07845 -10.100621)
			(xy 195.109196 -9.923786) (xy 195.147811 -9.7485) (xy 195.194219 -9.575116) (xy 195.248327 -9.403977)
			(xy 195.310026 -9.235427) (xy 195.379194 -9.069801) (xy 195.455693 -8.907431) (xy 195.539369 -8.748641)
			(xy 195.630055 -8.593748) (xy 195.727571 -8.443061) (xy 195.831722 -8.296881) (xy 195.9423 -8.1555)
			(xy 196.059083 -8.0192) (xy 196.181839 -7.888254) (xy 196.245734 -7.825232) (xy 196.257486 -7.813044)
			(xy 196.274658 -7.783878) (xy 196.283558 -7.751223) (xy 196.284088 -7.7343) (xy 196.284088 -4.750308)
			(xy 196.284088 -4.649216) (xy 196.284088 -4.48691) (xy 196.291962 -4.479036) (xy 196.296534 -4.43357)
			(xy 196.304123 -4.360068) (xy 196.326196 -4.213943) (xy 196.356041 -4.069205) (xy 196.393572 -3.926267)
			(xy 196.438681 -3.785538) (xy 196.491241 -3.647417) (xy 196.551101 -3.512301) (xy 196.61809 -3.380573)
			(xy 196.692017 -3.25261) (xy 196.772672 -3.128777) (xy 196.859824 -3.009428) (xy 196.953225 -2.894903)
			(xy 197.052607 -2.785528) (xy 197.157688 -2.681616) (xy 197.268168 -2.583463) (xy 197.383731 -2.491349)
			(xy 197.504048 -2.405538) (xy 197.628775 -2.326273) (xy 197.757556 -2.253782) (xy 197.890025 -2.18827)
			(xy 198.025803 -2.129926) (xy 198.164503 -2.078914) (xy 198.305728 -2.035382) (xy 198.449077 -1.999452)
			(xy 198.594139 -1.971229) (xy 198.740502 -1.950791) (xy 198.887747 -1.938198) (xy 199.035455 -1.933485)
			(xy 199.183203 -1.936666) (xy 199.330571 -1.947731) (xy 199.477138 -1.96665) (xy 199.622485 -1.993368)
			(xy 199.766199 -2.027809) (xy 199.907868 -2.069875) (xy 200.047089 -2.119445) (xy 200.183465 -2.176379)
			(xy 200.316606 -2.240513) (xy 200.446132 -2.311665) (xy 200.571675 -2.389632) (xy 200.692875 -2.474191)
			(xy 200.809387 -2.565101) (xy 200.920879 -2.662103) (xy 201.027031 -2.76492) (xy 201.127543 -2.873258)
			(xy 201.222126 -2.986809) (xy 201.310511 -3.105248) (xy 201.392445 -3.228238) (xy 201.467696 -3.355427)
			(xy 201.536048 -3.486453) (xy 201.597305 -3.620942) (xy 201.651294 -3.75851) (xy 201.697861 -3.898764)
			(xy 201.736872 -4.041305) (xy 201.768216 -4.185725) (xy 201.791804 -4.331613) (xy 201.807568 -4.478553)
			(xy 201.815463 -4.626125) (xy 201.815954 -4.700016) (xy 201.815954 -7.7343) (xy 201.816506 -7.751221)
			(xy 201.825401 -7.783872) (xy 201.842565 -7.813038) (xy 201.854308 -7.825232) (xy 201.918203 -7.888254)
			(xy 202.040959 -8.0192) (xy 202.157742 -8.1555) (xy 202.26832 -8.296881) (xy 202.372471 -8.443061)
			(xy 202.469987 -8.593748) (xy 202.560673 -8.748641) (xy 202.644349 -8.907431) (xy 202.720848 -9.069801)
			(xy 202.790016 -9.235427) (xy 202.851715 -9.403977) (xy 202.905823 -9.575116) (xy 202.952231 -9.7485)
			(xy 202.990846 -9.923786) (xy 203.021592 -10.100621) (xy 203.044407 -10.278653) (xy 203.059245 -10.457527)
			(xy 203.066067 -10.636631) (xy 275.794027 -10.636631) (xy 275.800859 -10.457273) (xy 275.815697 -10.278399)
			(xy 275.838512 -10.100367) (xy 275.869258 -9.923532) (xy 275.907873 -9.748246) (xy 275.954281 -9.574862)
			(xy 276.008389 -9.403723) (xy 276.070088 -9.235173) (xy 276.139256 -9.069547) (xy 276.215755 -8.907177)
			(xy 276.299431 -8.748387) (xy 276.390117 -8.593494) (xy 276.487633 -8.442807) (xy 276.591784 -8.296627)
			(xy 276.702362 -8.155246) (xy 276.819145 -8.018946) (xy 276.941901 -7.888) (xy 277.005796 -7.824978)
			(xy 277.017567 -7.812806) (xy 277.034736 -7.783633) (xy 277.043626 -7.750971) (xy 277.04415 -7.734046)
			(xy 277.04415 -4.750054) (xy 277.04415 -4.648962) (xy 277.04415 -4.486656) (xy 277.052024 -4.478782)
			(xy 277.056596 -4.433316) (xy 277.064254 -4.359821) (xy 277.086325 -4.213696) (xy 277.116168 -4.068958)
			(xy 277.153696 -3.92602) (xy 277.198803 -3.78529) (xy 277.251361 -3.647169) (xy 277.311218 -3.512052)
			(xy 277.378206 -3.380324) (xy 277.452131 -3.25236) (xy 277.532784 -3.128527) (xy 277.619935 -3.009177)
			(xy 277.713334 -2.89465) (xy 277.812715 -2.785275) (xy 277.917794 -2.681362) (xy 278.028273 -2.583208)
			(xy 278.143835 -2.491094) (xy 278.264151 -2.405282) (xy 278.388877 -2.326016) (xy 278.517658 -2.253524)
			(xy 278.650126 -2.188012) (xy 278.785903 -2.129667) (xy 278.924602 -2.078655) (xy 279.065827 -2.035122)
			(xy 279.209175 -1.999192) (xy 279.354237 -1.970967) (xy 279.5006 -1.950529) (xy 279.647844 -1.937936)
			(xy 279.795552 -1.933223) (xy 279.9433 -1.936403) (xy 280.090667 -1.947469) (xy 280.237234 -1.966388)
			(xy 280.382581 -1.993106) (xy 280.526294 -2.027547) (xy 280.667963 -2.069613) (xy 280.807183 -2.119183)
			(xy 280.943558 -2.176117) (xy 281.076699 -2.240252) (xy 281.206225 -2.311404) (xy 281.331766 -2.389372)
			(xy 281.452966 -2.473931) (xy 281.569477 -2.564842) (xy 281.680968 -2.661845) (xy 281.719856 -2.699512)
			(xy 385.236466 -2.699512) (xy 386.531866 -2.699512) (xy 386.531866 -5.468112) (xy 385.236466 -5.468112)
			(xy 385.236466 -2.699512) (xy 281.719856 -2.699512) (xy 281.787119 -2.764662) (xy 281.88763 -2.873001)
			(xy 281.982212 -2.986552) (xy 282.070595 -3.104992) (xy 282.152528 -3.227982) (xy 282.227777 -3.355172)
			(xy 282.296127 -3.486198) (xy 282.357383 -3.620687) (xy 282.411371 -3.758256) (xy 282.457935 -3.89851)
			(xy 282.496944 -4.041051) (xy 282.528286 -4.185472) (xy 282.551872 -4.33136) (xy 282.567633 -4.478299)
			(xy 282.575527 -4.625871) (xy 282.576016 -4.699762) (xy 282.576016 -5.7912) (xy 322.2244 -5.7912)
			(xy 322.2244 -5.3848) (xy 322.5546 -5.0546) (xy 324.231 -5.0546) (xy 324.5104 -5.334) (xy 324.5104 -5.461)
			(xy 353.4156 -5.461) (xy 353.4156 -3.7592) (xy 353.7458 -3.429) (xy 354.1268 -3.429) (xy 354.4316 -3.7338)
			(xy 354.4316 -5.4356) (xy 354.1268 -5.7404) (xy 353.695 -5.7404) (xy 353.4156 -5.461) (xy 324.5104 -5.461)
			(xy 324.5104 -5.574538) (xy 348.805246 -5.574538) (xy 350.253046 -5.574538) (xy 350.253046 -5.9182)
			(xy 364.9472 -5.9182) (xy 364.9472 -5.5118) (xy 365.2774 -5.1816) (xy 366.903 -5.1816) (xy 367.2332 -5.5118)
			(xy 367.2332 -5.545328) (xy 387.236462 -5.545328) (xy 388.531862 -5.545328) (xy 391.236454 -5.545328)
			(xy 392.531854 -5.545328) (xy 395.236446 -5.545328) (xy 396.531846 -5.545328) (xy 396.531846 -8.414004)
			(xy 395.236446 -8.414004) (xy 395.236446 -5.545328) (xy 392.531854 -5.545328) (xy 392.531854 -6.899656)
			(xy 393.23645 -6.899656) (xy 394.53185 -6.899656) (xy 394.53185 -9.668256) (xy 393.23645 -9.668256)
			(xy 393.23645 -6.899656) (xy 392.531854 -6.899656) (xy 392.531854 -8.414004) (xy 391.236454 -8.414004)
			(xy 391.236454 -5.545328) (xy 388.531862 -5.545328) (xy 388.531862 -6.899656) (xy 389.236458 -6.899656)
			(xy 390.531858 -6.899656) (xy 390.531858 -9.668256) (xy 389.236458 -9.668256) (xy 389.236458 -6.899656)
			(xy 388.531862 -6.899656) (xy 388.531862 -8.414004) (xy 387.236462 -8.414004) (xy 387.236462 -5.545328)
			(xy 367.2332 -5.545328) (xy 367.2332 -5.9436) (xy 366.9538 -6.223) (xy 365.252 -6.223) (xy 364.9472 -5.9182)
			(xy 350.253046 -5.9182) (xy 350.253046 -6.899656) (xy 385.236466 -6.899656) (xy 386.531866 -6.899656)
			(xy 386.531866 -9.668256) (xy 385.236466 -9.668256) (xy 385.236466 -6.899656) (xy 350.253046 -6.899656)
			(xy 350.253046 -8.393938) (xy 348.805246 -8.393938) (xy 348.805246 -5.574538) (xy 324.5104 -5.574538)
			(xy 324.5104 -5.7912) (xy 324.2056 -6.096) (xy 322.5292 -6.096) (xy 322.2244 -5.7912) (xy 282.576016 -5.7912)
			(xy 282.576016 -6.87451) (xy 338.805266 -6.87451) (xy 340.253066 -6.87451) (xy 340.253066 -9.067546)
			(xy 360.369866 -9.067546) (xy 362.198666 -9.067546) (xy 365.169958 -9.067546) (xy 366.998758 -9.067546)
			(xy 366.998758 -9.745472) (xy 387.236462 -9.745472) (xy 388.531862 -9.745472) (xy 391.236454 -9.745472)
			(xy 392.531854 -9.745472) (xy 395.236446 -9.745472) (xy 396.531846 -9.745472) (xy 396.531846 -12.614148)
			(xy 395.236446 -12.614148) (xy 395.236446 -9.745472) (xy 392.531854 -9.745472) (xy 392.531854 -11.0998)
			(xy 393.23645 -11.0998) (xy 394.53185 -11.0998) (xy 394.53185 -13.8684) (xy 393.23645 -13.8684) (xy 393.23645 -11.0998)
			(xy 392.531854 -11.0998) (xy 392.531854 -12.614148) (xy 391.236454 -12.614148) (xy 391.236454 -9.745472)
			(xy 388.531862 -9.745472) (xy 388.531862 -11.0998) (xy 389.236458 -11.0998) (xy 390.531858 -11.0998)
			(xy 390.531858 -13.8684) (xy 389.236458 -13.8684) (xy 389.236458 -11.0998) (xy 388.531862 -11.0998)
			(xy 388.531862 -12.614148) (xy 387.236462 -12.614148) (xy 387.236462 -9.745472) (xy 366.998758 -9.745472)
			(xy 366.998758 -11.0998) (xy 385.236466 -11.0998) (xy 386.531866 -11.0998) (xy 386.531866 -13.8684)
			(xy 385.236466 -13.8684) (xy 385.236466 -11.0998) (xy 366.998758 -11.0998) (xy 366.998758 -11.505946)
			(xy 365.169958 -11.505946) (xy 365.169958 -9.067546) (xy 362.198666 -9.067546) (xy 362.198666 -11.505946)
			(xy 360.369866 -11.505946) (xy 360.369866 -9.067546) (xy 340.253066 -9.067546) (xy 340.253066 -9.69391)
			(xy 338.805266 -9.69391) (xy 338.805266 -6.87451) (xy 282.576016 -6.87451) (xy 282.576016 -7.734046)
			(xy 282.576552 -7.750968) (xy 282.585456 -7.783619) (xy 282.602625 -7.812784) (xy 282.61437 -7.824978)
			(xy 282.678265 -7.888) (xy 282.801021 -8.018946) (xy 282.917804 -8.155246) (xy 283.028382 -8.296627)
			(xy 283.132533 -8.442807) (xy 283.230049 -8.593494) (xy 283.320735 -8.748387) (xy 283.404411 -8.907177)
			(xy 283.48091 -9.069547) (xy 283.550078 -9.235173) (xy 283.611777 -9.403723) (xy 283.659262 -9.553914)
			(xy 308.833762 -9.553914) (xy 308.833762 -9.445286) (xy 308.841691 -9.336948) (xy 308.857508 -9.229477)
			(xy 308.881127 -9.123448) (xy 308.912423 -9.019426) (xy 308.951228 -8.917965) (xy 308.997336 -8.819608)
			(xy 309.0505 -8.724879) (xy 309.110438 -8.634284) (xy 309.176828 -8.548305) (xy 309.249318 -8.467402)
			(xy 309.327519 -8.392006) (xy 309.411016 -8.32252) (xy 309.499362 -8.259313) (xy 309.592086 -8.202725)
			(xy 309.688694 -8.153055) (xy 309.788669 -8.11057) (xy 309.891479 -8.075497) (xy 309.996575 -8.048021)
			(xy 310.103396 -8.02829) (xy 310.211372 -8.016409) (xy 310.319928 -8.012442) (xy 310.428484 -8.016409)
			(xy 310.53646 -8.02829) (xy 310.643281 -8.048021) (xy 310.748377 -8.075497) (xy 310.851187 -8.11057)
			(xy 310.951162 -8.153055) (xy 311.04777 -8.202725) (xy 311.140494 -8.259313) (xy 311.22884 -8.32252)
			(xy 311.312337 -8.392006) (xy 311.390538 -8.467402) (xy 311.463028 -8.548305) (xy 311.529418 -8.634284)
			(xy 311.589356 -8.724879) (xy 311.64252 -8.819608) (xy 311.688628 -8.917965) (xy 311.727433 -9.019426)
			(xy 311.741987 -9.0678) (xy 322.449698 -9.0678) (xy 324.278498 -9.0678) (xy 327.24979 -9.0678) (xy 329.07859 -9.0678)
			(xy 329.07859 -9.398) (xy 334.2386 -9.398) (xy 334.2386 -8.9916) (xy 334.5434 -8.6868) (xy 336.3976 -8.6868)
			(xy 336.7024 -8.9916) (xy 336.7024 -9.398) (xy 336.3976 -9.7028) (xy 334.5434 -9.7028) (xy 334.2386 -9.398)
			(xy 329.07859 -9.398) (xy 329.07859 -9.774428) (xy 348.805246 -9.774428) (xy 350.253046 -9.774428)
			(xy 350.253046 -12.593828) (xy 348.805246 -12.593828) (xy 348.805246 -9.774428) (xy 329.07859 -9.774428)
			(xy 329.07859 -11.0744) (xy 338.805266 -11.0744) (xy 340.253066 -11.0744) (xy 340.253066 -13.8938)
			(xy 338.805266 -13.8938) (xy 338.805266 -11.0744) (xy 329.07859 -11.0744) (xy 329.07859 -11.5062)
			(xy 327.24979 -11.5062) (xy 327.24979 -9.0678) (xy 324.278498 -9.0678) (xy 324.278498 -11.5062) (xy 322.449698 -11.5062)
			(xy 322.449698 -9.0678) (xy 311.741987 -9.0678) (xy 311.758729 -9.123448) (xy 311.782348 -9.229477)
			(xy 311.798165 -9.336948) (xy 311.806094 -9.445286) (xy 311.80659 -9.4996) (xy 311.806094 -9.553914)
			(xy 311.798165 -9.662252) (xy 311.782348 -9.769723) (xy 311.758729 -9.875752) (xy 311.727433 -9.979774)
			(xy 311.688628 -10.081235) (xy 311.64252 -10.179592) (xy 311.589356 -10.274321) (xy 311.529418 -10.364916)
			(xy 311.463028 -10.450895) (xy 311.390538 -10.531798) (xy 311.312337 -10.607194) (xy 311.22884 -10.67668)
			(xy 311.140494 -10.739887) (xy 311.04777 -10.796475) (xy 310.951162 -10.846145) (xy 310.851187 -10.88863)
			(xy 310.748377 -10.923703) (xy 310.643281 -10.951179) (xy 310.53646 -10.97091) (xy 310.428484 -10.982791)
			(xy 310.319928 -10.986758) (xy 310.211372 -10.982791) (xy 310.103396 -10.97091) (xy 309.996575 -10.951179)
			(xy 309.891479 -10.923703) (xy 309.788669 -10.88863) (xy 309.688694 -10.846145) (xy 309.592086 -10.796475)
			(xy 309.499362 -10.739887) (xy 309.411016 -10.67668) (xy 309.327519 -10.607194) (xy 309.249318 -10.531798)
			(xy 309.176828 -10.450895) (xy 309.110438 -10.364916) (xy 309.0505 -10.274321) (xy 308.997336 -10.179592)
			(xy 308.951228 -10.081235) (xy 308.912423 -9.979774) (xy 308.881127 -9.875752) (xy 308.857508 -9.769723)
			(xy 308.841691 -9.662252) (xy 308.833762 -9.553914) (xy 283.659262 -9.553914) (xy 283.665885 -9.574862)
			(xy 283.712293 -9.748246) (xy 283.750908 -9.923532) (xy 283.781654 -10.100367) (xy 283.804469 -10.278399)
			(xy 283.819307 -10.457273) (xy 283.826139 -10.636631) (xy 283.824952 -10.816115) (xy 283.815747 -10.995367)
			(xy 283.798542 -11.174029) (xy 283.773373 -11.351744) (xy 283.74029 -11.528157) (xy 283.699358 -11.702915)
			(xy 283.65066 -11.875671) (xy 283.594292 -12.046078) (xy 283.530368 -12.213797) (xy 283.459014 -12.378493)
			(xy 283.380373 -12.539836) (xy 283.294603 -12.697505) (xy 283.201875 -12.851185) (xy 283.102373 -13.000568)
			(xy 282.996297 -13.145357) (xy 282.883858 -13.285262) (xy 282.765281 -13.420005) (xy 282.640803 -13.549315)
			(xy 282.510672 -13.672935) (xy 282.375148 -13.790618) (xy 282.234501 -13.902129) (xy 282.089014 -14.007244)
			(xy 281.938975 -14.105755) (xy 281.784685 -14.197465) (xy 281.626452 -14.28219) (xy 281.464592 -14.359761)
			(xy 281.299428 -14.430023) (xy 281.274705 -14.439259) (xy 319.550021 -14.439259) (xy 319.550021 -14.340973)
			(xy 319.55793 -14.243006) (xy 319.573696 -14.145993) (xy 319.597217 -14.050564) (xy 319.628341 -13.957336)
			(xy 319.666866 -13.866915) (xy 319.712541 -13.779888) (xy 319.765072 -13.696817) (xy 319.824116 -13.618244)
			(xy 319.889291 -13.544676) (xy 319.960175 -13.476591) (xy 320.036308 -13.41443) (xy 320.117195 -13.358598)
			(xy 320.202313 -13.309455) (xy 320.29111 -13.267321) (xy 320.383008 -13.232468) (xy 320.477414 -13.205123)
			(xy 320.573713 -13.185464) (xy 320.671282 -13.173617) (xy 320.769488 -13.169659) (xy 320.867694 -13.173617)
			(xy 320.965263 -13.185464) (xy 321.061562 -13.205123) (xy 321.155968 -13.232468) (xy 321.247866 -13.267321)
			(xy 321.336663 -13.309455) (xy 321.421781 -13.358598) (xy 321.502668 -13.41443) (xy 321.578801 -13.476591)
			(xy 321.649685 -13.544676) (xy 321.71486 -13.618244) (xy 321.773904 -13.696817) (xy 321.826435 -13.779888)
			(xy 321.87211 -13.866915) (xy 321.910635 -13.957336) (xy 321.941759 -14.050564) (xy 321.944064 -14.059916)
			(xy 329.480926 -14.059916) (xy 329.481436 -14.017565) (xy 329.489498 -13.933249) (xy 329.505539 -13.85008)
			(xy 329.529411 -13.768812) (xy 329.5609 -13.690182) (xy 329.59972 -13.6149) (xy 329.645519 -13.543649)
			(xy 329.697884 -13.477073) (xy 329.756339 -13.415776) (xy 329.820356 -13.360313) (xy 329.889354 -13.311185)
			(xy 329.96271 -13.268838) (xy 330.039758 -13.233655) (xy 330.119802 -13.205954) (xy 330.202116 -13.185987)
			(xy 330.285956 -13.173933) (xy 330.370561 -13.169903) (xy 330.455166 -13.173933) (xy 330.539006 -13.185987)
			(xy 330.62132 -13.205954) (xy 330.701364 -13.233655) (xy 330.778412 -13.268838) (xy 330.851768 -13.311185)
			(xy 330.920766 -13.360313) (xy 330.984783 -13.415776) (xy 331.043238 -13.477073) (xy 331.095603 -13.543649)
			(xy 331.141402 -13.6149) (xy 331.180222 -13.690182) (xy 331.211711 -13.768812) (xy 331.235583 -13.85008)
			(xy 331.251624 -13.933249) (xy 331.259686 -14.017565) (xy 331.260196 -14.059916) (xy 331.260196 -14.439005)
			(xy 357.470189 -14.439005) (xy 357.470189 -14.340719) (xy 357.478098 -14.242752) (xy 357.493864 -14.145739)
			(xy 357.517385 -14.05031) (xy 357.548509 -13.957082) (xy 357.587034 -13.866661) (xy 357.632709 -13.779634)
			(xy 357.68524 -13.696563) (xy 357.744284 -13.61799) (xy 357.809459 -13.544422) (xy 357.880343 -13.476337)
			(xy 357.956476 -13.414176) (xy 358.037363 -13.358344) (xy 358.122481 -13.309201) (xy 358.211278 -13.267067)
			(xy 358.303176 -13.232214) (xy 358.397582 -13.204869) (xy 358.493881 -13.18521) (xy 358.59145 -13.173363)
			(xy 358.689656 -13.169405) (xy 358.787862 -13.173363) (xy 358.885431 -13.18521) (xy 358.98173 -13.204869)
			(xy 359.076136 -13.232214) (xy 359.168034 -13.267067) (xy 359.256831 -13.309201) (xy 359.341949 -13.358344)
			(xy 359.422836 -13.414176) (xy 359.498969 -13.476337) (xy 359.569853 -13.544422) (xy 359.635028 -13.61799)
			(xy 359.694072 -13.696563) (xy 359.746603 -13.779634) (xy 359.792278 -13.866661) (xy 359.830803 -13.957082)
			(xy 359.861927 -14.05031) (xy 359.885448 -14.145739) (xy 359.901214 -14.242752) (xy 359.909123 -14.340719)
			(xy 359.909618 -14.389862) (xy 359.909123 -14.439005) (xy 359.901214 -14.536972) (xy 359.885448 -14.633985)
			(xy 359.861927 -14.729414) (xy 359.856569 -14.745462) (xy 367.401348 -14.745462) (xy 367.401348 -14.059662)
			(xy 367.401852 -14.017314) (xy 367.409903 -13.933) (xy 367.425932 -13.849834) (xy 367.449793 -13.768567)
			(xy 367.481272 -13.689937) (xy 367.520083 -13.614656) (xy 367.565873 -13.543404) (xy 367.618229 -13.476828)
			(xy 367.676677 -13.41553) (xy 367.740687 -13.360065) (xy 367.809679 -13.310936) (xy 367.883029 -13.268587)
			(xy 367.960072 -13.233403) (xy 368.040111 -13.205701) (xy 368.12242 -13.185733) (xy 368.206255 -13.17368)
			(xy 368.290856 -13.16965) (xy 368.375457 -13.17368) (xy 368.459292 -13.185733) (xy 368.541601 -13.205701)
			(xy 368.62164 -13.233403) (xy 368.698683 -13.268587) (xy 368.772033 -13.310936) (xy 368.841025 -13.360065)
			(xy 368.905035 -13.41553) (xy 368.963483 -13.476828) (xy 369.015839 -13.543404) (xy 369.061629 -13.614656)
			(xy 369.10044 -13.689937) (xy 369.131919 -13.768567) (xy 369.15578 -13.849834) (xy 369.171809 -13.933)
			(xy 369.17986 -14.017314) (xy 369.180364 -14.059662) (xy 369.180364 -14.694662) (xy 369.179898 -14.73694)
			(xy 369.1721 -14.821134) (xy 369.156565 -14.90425) (xy 369.133428 -14.985578) (xy 369.102885 -15.064424)
			(xy 369.065196 -15.140115) (xy 369.020685 -15.212005) (xy 368.969729 -15.279482) (xy 368.912765 -15.341969)
			(xy 368.850277 -15.398933) (xy 368.7828 -15.449888) (xy 368.71091 -15.494399) (xy 368.635218 -15.532087)
			(xy 368.556372 -15.56263) (xy 368.475044 -15.585767) (xy 368.391928 -15.601301) (xy 368.307734 -15.609099)
			(xy 368.265456 -15.60957) (xy 368.223029 -15.609129) (xy 368.138583 -15.600808) (xy 368.05536 -15.584249)
			(xy 367.97416 -15.559613) (xy 367.895766 -15.527137) (xy 367.820933 -15.487133) (xy 367.750381 -15.439987)
			(xy 367.684791 -15.386153) (xy 367.624792 -15.326149) (xy 367.570964 -15.260553) (xy 367.523825 -15.189996)
			(xy 367.483828 -15.115159) (xy 367.451359 -15.036763) (xy 367.426731 -14.955561) (xy 367.41018 -14.872336)
			(xy 367.401867 -14.787889) (xy 367.401348 -14.745462) (xy 359.856569 -14.745462) (xy 359.830803 -14.822642)
			(xy 359.792278 -14.913063) (xy 359.746603 -15.000091) (xy 359.694072 -15.083161) (xy 359.635028 -15.161734)
			(xy 359.569853 -15.235302) (xy 359.498969 -15.303387) (xy 359.422836 -15.365548) (xy 359.341949 -15.42138)
			(xy 359.256831 -15.470523) (xy 359.168034 -15.512657) (xy 359.076136 -15.54751) (xy 358.98173 -15.574855)
			(xy 358.885431 -15.594514) (xy 358.787862 -15.606361) (xy 358.689656 -15.610319) (xy 358.59145 -15.606361)
			(xy 358.493881 -15.594514) (xy 358.397582 -15.574855) (xy 358.303176 -15.54751) (xy 358.211278 -15.512657)
			(xy 358.122481 -15.470523) (xy 358.037363 -15.42138) (xy 357.956476 -15.365548) (xy 357.880343 -15.303387)
			(xy 357.809459 -15.235302) (xy 357.744284 -15.161734) (xy 357.68524 -15.083161) (xy 357.632709 -15.000091)
			(xy 357.587034 -14.913063) (xy 357.548509 -14.822642) (xy 357.517385 -14.729414) (xy 357.493864 -14.633985)
			(xy 357.478098 -14.536972) (xy 357.470189 -14.439005) (xy 331.260196 -14.439005) (xy 331.260196 -14.694916)
			(xy 331.259735 -14.737193) (xy 331.251932 -14.821386) (xy 331.236394 -14.904499) (xy 331.213253 -14.985825)
			(xy 331.182708 -15.064668) (xy 331.145018 -15.140357) (xy 331.100505 -15.212245) (xy 331.049549 -15.279719)
			(xy 330.992584 -15.342204) (xy 330.930098 -15.399167) (xy 330.862622 -15.450121) (xy 330.790732 -15.494631)
			(xy 330.715042 -15.532319) (xy 330.636198 -15.562862) (xy 330.554872 -15.586) (xy 330.471758 -15.601536)
			(xy 330.387565 -15.609336) (xy 330.345288 -15.609824) (xy 330.302863 -15.609299) (xy 330.218422 -15.600981)
			(xy 330.135202 -15.584427) (xy 330.054006 -15.559796) (xy 329.975615 -15.527324) (xy 329.900784 -15.487326)
			(xy 329.830233 -15.440186) (xy 329.764643 -15.386357) (xy 329.704645 -15.32636) (xy 329.650817 -15.26077)
			(xy 329.603676 -15.19022) (xy 329.563677 -15.115389) (xy 329.531206 -15.036998) (xy 329.506574 -14.955802)
			(xy 329.490019 -14.872582) (xy 329.481701 -14.788141) (xy 329.48118 -14.745716) (xy 329.480926 -14.059916)
			(xy 321.944064 -14.059916) (xy 321.96528 -14.145993) (xy 321.981046 -14.243006) (xy 321.988955 -14.340973)
			(xy 321.98945 -14.390116) (xy 321.988955 -14.439259) (xy 321.981046 -14.537226) (xy 321.96528 -14.634239)
			(xy 321.941759 -14.729668) (xy 321.910635 -14.822896) (xy 321.87211 -14.913317) (xy 321.826435 -15.000345)
			(xy 321.773904 -15.083415) (xy 321.71486 -15.161988) (xy 321.649685 -15.235556) (xy 321.578801 -15.303641)
			(xy 321.502668 -15.365802) (xy 321.421781 -15.421634) (xy 321.336663 -15.470777) (xy 321.247866 -15.512911)
			(xy 321.155968 -15.547764) (xy 321.061562 -15.575109) (xy 320.965263 -15.594768) (xy 320.867694 -15.606615)
			(xy 320.769488 -15.610573) (xy 320.671282 -15.606615) (xy 320.573713 -15.594768) (xy 320.477414 -15.575109)
			(xy 320.383008 -15.547764) (xy 320.29111 -15.512911) (xy 320.202313 -15.470777) (xy 320.117195 -15.421634)
			(xy 320.036308 -15.365802) (xy 319.960175 -15.303641) (xy 319.889291 -15.235556) (xy 319.824116 -15.161988)
			(xy 319.765072 -15.083415) (xy 319.712541 -15.000345) (xy 319.666866 -14.913317) (xy 319.628341 -14.822896)
			(xy 319.597217 -14.729668) (xy 319.573696 -14.634239) (xy 319.55793 -14.537226) (xy 319.550021 -14.439259)
			(xy 281.274705 -14.439259) (xy 281.131289 -14.492837) (xy 280.960513 -14.548076) (xy 280.787439 -14.59563)
			(xy 280.612413 -14.635404) (xy 280.435785 -14.66732) (xy 280.257908 -14.691312) (xy 280.079136 -14.707334)
			(xy 279.899827 -14.715352) (xy 279.720339 -14.715352) (xy 279.54103 -14.707334) (xy 279.362258 -14.691312)
			(xy 279.184381 -14.66732) (xy 279.007753 -14.635404) (xy 278.832727 -14.59563) (xy 278.659653 -14.548076)
			(xy 278.488877 -14.492837) (xy 278.320738 -14.430023) (xy 278.155574 -14.359761) (xy 277.993714 -14.28219)
			(xy 277.835481 -14.197465) (xy 277.681191 -14.105755) (xy 277.531152 -14.007244) (xy 277.385665 -13.902129)
			(xy 277.245018 -13.790618) (xy 277.109494 -13.672935) (xy 276.979363 -13.549315) (xy 276.854885 -13.420005)
			(xy 276.736308 -13.285262) (xy 276.623869 -13.145357) (xy 276.517793 -13.000568) (xy 276.418291 -12.851185)
			(xy 276.325563 -12.697505) (xy 276.239793 -12.539836) (xy 276.161152 -12.378493) (xy 276.089798 -12.213797)
			(xy 276.025874 -12.046078) (xy 275.969506 -11.875671) (xy 275.920808 -11.702915) (xy 275.879876 -11.528157)
			(xy 275.846793 -11.351744) (xy 275.821624 -11.174029) (xy 275.804419 -10.995367) (xy 275.795214 -10.816115)
			(xy 275.794027 -10.636631) (xy 203.066067 -10.636631) (xy 203.066077 -10.636885) (xy 203.06489 -10.816369)
			(xy 203.055685 -10.995621) (xy 203.03848 -11.174283) (xy 203.013311 -11.351998) (xy 202.980228 -11.528411)
			(xy 202.939296 -11.703169) (xy 202.890598 -11.875925) (xy 202.83423 -12.046332) (xy 202.770306 -12.214051)
			(xy 202.698952 -12.378747) (xy 202.620311 -12.54009) (xy 202.534541 -12.697759) (xy 202.441813 -12.851439)
			(xy 202.342311 -13.000822) (xy 202.236235 -13.145611) (xy 202.123796 -13.285516) (xy 202.005219 -13.420259)
			(xy 201.880741 -13.549569) (xy 201.75061 -13.673189) (xy 201.615086 -13.790872) (xy 201.474439 -13.902383)
			(xy 201.328952 -14.007498) (xy 201.178913 -14.106009) (xy 201.024623 -14.197719) (xy 200.86639 -14.282444)
			(xy 200.70453 -14.360015) (xy 200.539366 -14.430277) (xy 200.371227 -14.493091) (xy 200.200451 -14.54833)
			(xy 200.027377 -14.595884) (xy 199.852351 -14.635658) (xy 199.675723 -14.667574) (xy 199.497846 -14.691566)
			(xy 199.319074 -14.707588) (xy 199.139765 -14.715606) (xy 198.960277 -14.715606) (xy 198.780968 -14.707588)
			(xy 198.602196 -14.691566) (xy 198.424319 -14.667574) (xy 198.247691 -14.635658) (xy 198.072665 -14.595884)
			(xy 197.899591 -14.54833) (xy 197.728815 -14.493091) (xy 197.560676 -14.430277) (xy 197.395512 -14.360015)
			(xy 197.233652 -14.282444) (xy 197.075419 -14.197719) (xy 196.921129 -14.106009) (xy 196.77109 -14.007498)
			(xy 196.625603 -13.902383) (xy 196.484956 -13.790872) (xy 196.349432 -13.673189) (xy 196.219301 -13.549569)
			(xy 196.094823 -13.420259) (xy 195.976246 -13.285516) (xy 195.863807 -13.145611) (xy 195.757731 -13.000822)
			(xy 195.658229 -12.851439) (xy 195.565501 -12.697759) (xy 195.479731 -12.54009) (xy 195.40109 -12.378747)
			(xy 195.329736 -12.214051) (xy 195.265812 -12.046332) (xy 195.209444 -11.875925) (xy 195.160746 -11.703169)
			(xy 195.119814 -11.528411) (xy 195.086731 -11.351998) (xy 195.061562 -11.174283) (xy 195.044357 -10.995621)
			(xy 195.035152 -10.816369) (xy 195.033965 -10.636885) (xy 175.53178 -10.636885) (xy 175.53178 -12.614148)
			(xy 174.23638 -12.614148) (xy 174.23638 -9.745472) (xy 171.531788 -9.745472) (xy 171.531788 -11.0998)
			(xy 172.236384 -11.0998) (xy 173.531784 -11.0998) (xy 173.531784 -13.8684) (xy 172.236384 -13.8684)
			(xy 172.236384 -11.0998) (xy 171.531788 -11.0998) (xy 171.531788 -12.614148) (xy 170.236388 -12.614148)
			(xy 170.236388 -9.745472) (xy 167.531796 -9.745472) (xy 167.531796 -11.0998) (xy 168.236392 -11.0998)
			(xy 169.531792 -11.0998) (xy 169.531792 -13.8684) (xy 168.236392 -13.8684) (xy 168.236392 -11.0998)
			(xy 167.531796 -11.0998) (xy 167.531796 -12.614148) (xy 166.236396 -12.614148) (xy 166.236396 -9.745472)
			(xy 145.998692 -9.745472) (xy 145.998692 -11.0998) (xy 164.2364 -11.0998) (xy 165.5318 -11.0998)
			(xy 165.5318 -13.8684) (xy 164.2364 -13.8684) (xy 164.2364 -11.0998) (xy 145.998692 -11.0998) (xy 145.998692 -11.5062)
			(xy 144.169892 -11.5062) (xy 144.169892 -9.0678) (xy 141.1986 -9.0678) (xy 141.1986 -11.5062) (xy 139.3698 -11.5062)
			(xy 139.3698 -9.0678) (xy 119.253 -9.0678) (xy 119.253 -9.69391) (xy 117.8052 -9.69391) (xy 117.8052 -6.87451)
			(xy 11.106105 -6.87451) (xy 11.119951 -6.890029) (xy 11.172322 -6.960748) (xy 11.218045 -7.035936)
			(xy 11.256742 -7.114971) (xy 11.288091 -7.197197) (xy 11.311833 -7.281933) (xy 11.327771 -7.368477)
			(xy 11.335773 -7.456112) (xy 11.336274 -7.500112) (xy 11.335773 -7.544112) (xy 11.327771 -7.631747)
			(xy 11.311833 -7.718291) (xy 11.288091 -7.803027) (xy 11.256742 -7.885253) (xy 11.218045 -7.964288)
			(xy 11.172322 -8.039476) (xy 11.119951 -8.110195) (xy 11.061367 -8.175859) (xy 10.997053 -8.235924)
			(xy 10.927545 -8.289891) (xy 10.853417 -8.337313) (xy 10.775283 -8.377799) (xy 10.693792 -8.411012)
			(xy 10.609618 -8.436676) (xy 10.523459 -8.45458) (xy 10.436029 -8.464575) (xy 10.348052 -8.466579)
			(xy 10.260258 -8.460573) (xy 10.173374 -8.446609) (xy 10.088119 -8.424802) (xy 10.0052 -8.395333)
			(xy 9.925305 -8.358446) (xy 9.849096 -8.314446) (xy 9.777203 -8.263698) (xy 9.710222 -8.206624) (xy 9.64871 -8.143694)
			(xy 9.593174 -8.075432) (xy 9.544076 -8.002403) (xy 9.501823 -7.925211) (xy 9.466764 -7.844497) (xy 9.439189 -7.760929)
			(xy 9.419329 -7.6752) (xy 9.407346 -7.58802) (xy 9.403341 -7.500112) (xy 7.57877 -7.500112) (xy 7.563075 -7.51794)
			(xy 7.436578 -7.649518) (xy 7.304434 -7.775422) (xy 7.166898 -7.895412) (xy 7.024232 -8.009256) (xy 6.876712 -8.116736)
			(xy 6.724622 -8.217645) (xy 6.568254 -8.311788) (xy 6.407908 -8.398984) (xy 6.243894 -8.479067) (xy 6.076526 -8.551881)
			(xy 5.906126 -8.617287) (xy 5.733023 -8.675159) (xy 5.557548 -8.725386) (xy 5.380041 -8.767871) (xy 5.200841 -8.802533)
			(xy 5.020294 -8.829304) (xy 4.838747 -8.848133) (xy 4.656548 -8.858984) (xy 4.474049 -8.861837) (xy 4.291601 -8.856685)
			(xy 4.109554 -8.843539) (xy 3.928258 -8.822424) (xy 3.748063 -8.79338) (xy 3.569314 -8.756463) (xy 3.392356 -8.711745)
			(xy 3.217528 -8.659311) (xy 3.045168 -8.599262) (xy 2.875606 -8.531714) (xy 2.709169 -8.456797) (xy 2.546176 -8.374654)
			(xy 2.386942 -8.285444) (xy 2.231772 -8.189338) (xy 2.080965 -8.086522) (xy 1.934812 -7.977192) (xy 1.793592 -7.861559)
			(xy 1.657578 -7.739846) (xy 1.527031 -7.612286) (xy 1.402203 -7.479125) (xy 1.34239 -7.410196) (xy 1.324356 -7.389114)
			(xy 1.274064 -7.366) (xy 1.143 -7.366) (xy 1.126352 -7.366543) (xy 1.094189 -7.375161) (xy 1.065354 -7.391809)
			(xy 1.041809 -7.415354) (xy 1.025161 -7.444189) (xy 1.016543 -7.476352) (xy 1.016 -7.493) (xy 1.016 -9.554177)
			(xy 87.833696 -9.554177) (xy 87.833696 -9.445531) (xy 87.841627 -9.337174) (xy 87.857446 -9.229685)
			(xy 87.881069 -9.123638) (xy 87.91237 -9.019598) (xy 87.951182 -8.91812) (xy 87.997297 -8.819746)
			(xy 88.050471 -8.725001) (xy 88.110419 -8.63439) (xy 88.176821 -8.548396) (xy 88.249323 -8.467479)
			(xy 88.327538 -8.392071) (xy 88.411049 -8.322572) (xy 88.49941 -8.259355) (xy 88.59215 -8.202757)
			(xy 88.688774 -8.153079) (xy 88.788766 -8.110587) (xy 88.891594 -8.075507) (xy 88.996708 -8.048027)
			(xy 89.103547 -8.028292) (xy 89.211542 -8.016409) (xy 89.320116 -8.012442) (xy 89.42869 -8.016409)
			(xy 89.536685 -8.028292) (xy 89.643524 -8.048027) (xy 89.748638 -8.075507) (xy 89.851466 -8.110587)
			(xy 89.951458 -8.153079) (xy 90.048082 -8.202757) (xy 90.140822 -8.259355) (xy 90.229183 -8.322572)
			(xy 90.312694 -8.392071) (xy 90.390909 -8.467479) (xy 90.463411 -8.548396) (xy 90.529813 -8.63439)
			(xy 90.589761 -8.725001) (xy 90.642935 -8.819746) (xy 90.68905 -8.91812) (xy 90.727862 -9.019598)
			(xy 90.742287 -9.067546) (xy 101.449632 -9.067546) (xy 103.278432 -9.067546) (xy 106.249724 -9.067546)
			(xy 108.078524 -9.067546) (xy 108.078524 -9.398) (xy 113.2586 -9.398) (xy 113.2586 -8.9662) (xy 113.5634 -8.6614)
			(xy 115.3668 -8.6614) (xy 115.697 -8.9916) (xy 115.697 -9.4234) (xy 115.4176 -9.7028) (xy 113.5634 -9.7028)
			(xy 113.2586 -9.398) (xy 108.078524 -9.398) (xy 108.078524 -9.774428) (xy 127.80518 -9.774428) (xy 129.25298 -9.774428)
			(xy 129.25298 -12.593828) (xy 127.80518 -12.593828) (xy 127.80518 -9.774428) (xy 108.078524 -9.774428)
			(xy 108.078524 -11.0744) (xy 117.8052 -11.0744) (xy 119.253 -11.0744) (xy 119.253 -13.8938) (xy 117.8052 -13.8938)
			(xy 117.8052 -11.0744) (xy 108.078524 -11.0744) (xy 108.078524 -11.505946) (xy 106.249724 -11.505946)
			(xy 106.249724 -9.067546) (xy 103.278432 -9.067546) (xy 103.278432 -11.505946) (xy 101.449632 -11.505946)
			(xy 101.449632 -9.067546) (xy 90.742287 -9.067546) (xy 90.759163 -9.123638) (xy 90.782786 -9.229685)
			(xy 90.798605 -9.337174) (xy 90.806536 -9.445531) (xy 90.807032 -9.499854) (xy 90.806536 -9.554177)
			(xy 90.798605 -9.662534) (xy 90.782786 -9.770023) (xy 90.759163 -9.87607) (xy 90.727862 -9.98011)
			(xy 90.68905 -10.081588) (xy 90.642935 -10.179962) (xy 90.589761 -10.274707) (xy 90.529813 -10.365318)
			(xy 90.463411 -10.451312) (xy 90.390909 -10.532229) (xy 90.312694 -10.607637) (xy 90.229183 -10.677136)
			(xy 90.140822 -10.740353) (xy 90.048082 -10.796951) (xy 89.951458 -10.846629) (xy 89.851466 -10.889121)
			(xy 89.748638 -10.924201) (xy 89.643524 -10.951681) (xy 89.536685 -10.971416) (xy 89.42869 -10.983299)
			(xy 89.320116 -10.987267) (xy 89.211542 -10.983299) (xy 89.103547 -10.971416) (xy 88.996708 -10.951681)
			(xy 88.891594 -10.924201) (xy 88.788766 -10.889121) (xy 88.688774 -10.846629) (xy 88.59215 -10.796951)
			(xy 88.49941 -10.740353) (xy 88.411049 -10.677136) (xy 88.327538 -10.607637) (xy 88.249323 -10.532229)
			(xy 88.176821 -10.451312) (xy 88.110419 -10.365318) (xy 88.050471 -10.274707) (xy 87.997297 -10.179962)
			(xy 87.951182 -10.081588) (xy 87.91237 -9.98011) (xy 87.881069 -9.87607) (xy 87.857446 -9.770023)
			(xy 87.841627 -9.662534) (xy 87.833696 -9.554177) (xy 1.016 -9.554177) (xy 1.016 -14.439005) (xy 98.549955 -14.439005)
			(xy 98.549955 -14.340719) (xy 98.557864 -14.242752) (xy 98.57363 -14.145739) (xy 98.597151 -14.05031)
			(xy 98.628275 -13.957082) (xy 98.6668 -13.866661) (xy 98.712475 -13.779634) (xy 98.765006 -13.696563)
			(xy 98.82405 -13.61799) (xy 98.889225 -13.544422) (xy 98.960109 -13.476337) (xy 99.036242 -13.414176)
			(xy 99.117129 -13.358344) (xy 99.202247 -13.309201) (xy 99.291044 -13.267067) (xy 99.382942 -13.232214)
			(xy 99.477348 -13.204869) (xy 99.573647 -13.18521) (xy 99.671216 -13.173363) (xy 99.769422 -13.169405)
			(xy 99.867628 -13.173363) (xy 99.965197 -13.18521) (xy 100.061496 -13.204869) (xy 100.155902 -13.232214)
			(xy 100.2478 -13.267067) (xy 100.336597 -13.309201) (xy 100.421715 -13.358344) (xy 100.502602 -13.414176)
			(xy 100.578735 -13.476337) (xy 100.649619 -13.544422) (xy 100.714794 -13.61799) (xy 100.773838 -13.696563)
			(xy 100.826369 -13.779634) (xy 100.872044 -13.866661) (xy 100.910569 -13.957082) (xy 100.941693 -14.05031)
			(xy 100.965214 -14.145739) (xy 100.98098 -14.242752) (xy 100.988889 -14.340719) (xy 100.989384 -14.389862)
			(xy 100.988889 -14.439005) (xy 100.98098 -14.536972) (xy 100.965214 -14.633985) (xy 100.941693 -14.729414)
			(xy 100.936335 -14.745462) (xy 108.48086 -14.745462) (xy 108.48086 -14.059662) (xy 108.481364 -14.017301)
			(xy 108.489417 -13.932964) (xy 108.505451 -13.849774) (xy 108.529319 -13.768484) (xy 108.560807 -13.689832)
			(xy 108.599629 -13.614529) (xy 108.645432 -13.543257) (xy 108.697803 -13.476661) (xy 108.756268 -13.415346)
			(xy 108.820296 -13.359865) (xy 108.889308 -13.310722) (xy 108.962678 -13.268362) (xy 109.039743 -13.233167)
			(xy 109.119805 -13.205458) (xy 109.202138 -13.185484) (xy 109.285997 -13.173427) (xy 109.370622 -13.169396)
			(xy 109.455247 -13.173427) (xy 109.539106 -13.185484) (xy 109.621439 -13.205458) (xy 109.701501 -13.233167)
			(xy 109.778566 -13.268362) (xy 109.851936 -13.310722) (xy 109.920948 -13.359865) (xy 109.984976 -13.415346)
			(xy 110.043441 -13.476661) (xy 110.095812 -13.543257) (xy 110.141615 -13.614529) (xy 110.180437 -13.689832)
			(xy 110.211925 -13.768484) (xy 110.235793 -13.849774) (xy 110.251827 -13.932964) (xy 110.25988 -14.017301)
			(xy 110.260384 -14.059662) (xy 110.260384 -14.439259) (xy 136.470123 -14.439259) (xy 136.470123 -14.340973)
			(xy 136.478032 -14.243006) (xy 136.493798 -14.145993) (xy 136.517319 -14.050564) (xy 136.548443 -13.957336)
			(xy 136.586968 -13.866915) (xy 136.632643 -13.779888) (xy 136.685174 -13.696817) (xy 136.744218 -13.618244)
			(xy 136.809393 -13.544676) (xy 136.880277 -13.476591) (xy 136.95641 -13.41443) (xy 137.037297 -13.358598)
			(xy 137.122415 -13.309455) (xy 137.211212 -13.267321) (xy 137.30311 -13.232468) (xy 137.397516 -13.205123)
			(xy 137.493815 -13.185464) (xy 137.591384 -13.173617) (xy 137.68959 -13.169659) (xy 137.787796 -13.173617)
			(xy 137.885365 -13.185464) (xy 137.981664 -13.205123) (xy 138.07607 -13.232468) (xy 138.167968 -13.267321)
			(xy 138.256765 -13.309455) (xy 138.341883 -13.358598) (xy 138.42277 -13.41443) (xy 138.498903 -13.476591)
			(xy 138.569787 -13.544676) (xy 138.634962 -13.618244) (xy 138.694006 -13.696817) (xy 138.746537 -13.779888)
			(xy 138.792212 -13.866915) (xy 138.830737 -13.957336) (xy 138.861861 -14.050564) (xy 138.885382 -14.145993)
			(xy 138.901148 -14.243006) (xy 138.909057 -14.340973) (xy 138.909552 -14.390116) (xy 138.909057 -14.439259)
			(xy 138.901148 -14.537226) (xy 138.885382 -14.634239) (xy 138.861861 -14.729668) (xy 138.856503 -14.745716)
			(xy 146.401028 -14.745716) (xy 146.401028 -14.059916) (xy 146.401532 -14.017555) (xy 146.409585 -13.933218)
			(xy 146.425619 -13.850028) (xy 146.449487 -13.768738) (xy 146.480975 -13.690086) (xy 146.519797 -13.614783)
			(xy 146.5656 -13.543511) (xy 146.617971 -13.476915) (xy 146.676436 -13.4156) (xy 146.740464 -13.360119)
			(xy 146.809476 -13.310976) (xy 146.882846 -13.268616) (xy 146.959911 -13.233421) (xy 147.039973 -13.205712)
			(xy 147.122306 -13.185738) (xy 147.206165 -13.173681) (xy 147.29079 -13.16965) (xy 147.375415 -13.173681)
			(xy 147.459274 -13.185738) (xy 147.541607 -13.205712) (xy 147.621669 -13.233421) (xy 147.698734 -13.268616)
			(xy 147.772104 -13.310976) (xy 147.841116 -13.360119) (xy 147.905144 -13.4156) (xy 147.963609 -13.476915)
			(xy 148.01598 -13.543511) (xy 148.061783 -13.614783) (xy 148.100605 -13.690086) (xy 148.132093 -13.768738)
			(xy 148.155961 -13.850028) (xy 148.171995 -13.933218) (xy 148.180048 -14.017555) (xy 148.180552 -14.059916)
			(xy 148.180552 -14.694916) (xy 148.18005 -14.737199) (xy 148.172244 -14.821405) (xy 148.156702 -14.904531)
			(xy 148.133555 -14.985868) (xy 148.103 -15.064722) (xy 148.0653 -15.14042) (xy 148.020774 -15.212316)
			(xy 147.969805 -15.279796) (xy 147.912825 -15.342285) (xy 147.850322 -15.399249) (xy 147.782829 -15.450202)
			(xy 147.710922 -15.49471) (xy 147.635215 -15.532392) (xy 147.556354 -15.562926) (xy 147.475011 -15.586054)
			(xy 147.391881 -15.601576) (xy 147.307673 -15.60936) (xy 147.26539 -15.609824) (xy 147.265136 -15.609824)
			(xy 147.222711 -15.60927) (xy 147.138269 -15.600956) (xy 147.055049 -15.584406) (xy 146.973852 -15.559779)
			(xy 146.895459 -15.527311) (xy 146.820627 -15.487315) (xy 146.750075 -15.440177) (xy 146.684483 -15.386351)
			(xy 146.624484 -15.326355) (xy 146.570654 -15.260767) (xy 146.523511 -15.190218) (xy 146.483512 -15.115388)
			(xy 146.451039 -15.036997) (xy 146.426406 -14.955802) (xy 146.409851 -14.872582) (xy 146.401533 -14.788141)
			(xy 146.401028 -14.745716) (xy 138.856503 -14.745716) (xy 138.830737 -14.822896) (xy 138.792212 -14.913317)
			(xy 138.746537 -15.000345) (xy 138.694006 -15.083415) (xy 138.634962 -15.161988) (xy 138.569787 -15.235556)
			(xy 138.498903 -15.303641) (xy 138.42277 -15.365802) (xy 138.341883 -15.421634) (xy 138.256765 -15.470777)
			(xy 138.167968 -15.512911) (xy 138.07607 -15.547764) (xy 137.981664 -15.575109) (xy 137.885365 -15.594768)
			(xy 137.787796 -15.606615) (xy 137.68959 -15.610573) (xy 137.591384 -15.606615) (xy 137.493815 -15.594768)
			(xy 137.397516 -15.575109) (xy 137.30311 -15.547764) (xy 137.211212 -15.512911) (xy 137.122415 -15.470777)
			(xy 137.037297 -15.421634) (xy 136.95641 -15.365802) (xy 136.880277 -15.303641) (xy 136.809393 -15.235556)
			(xy 136.744218 -15.161988) (xy 136.685174 -15.083415) (xy 136.632643 -15.000345) (xy 136.586968 -14.913317)
			(xy 136.548443 -14.822896) (xy 136.517319 -14.729668) (xy 136.493798 -14.634239) (xy 136.478032 -14.537226)
			(xy 136.470123 -14.439259) (xy 110.260384 -14.439259) (xy 110.260384 -14.694662) (xy 110.259852 -14.736949)
			(xy 110.252052 -14.821164) (xy 110.236515 -14.904299) (xy 110.213373 -14.985646) (xy 110.182824 -15.06451)
			(xy 110.145129 -15.14022) (xy 110.100608 -15.212128) (xy 110.049643 -15.279622) (xy 109.992668 -15.342125)
			(xy 109.930168 -15.399105) (xy 109.862678 -15.450074) (xy 109.790772 -15.494599) (xy 109.715065 -15.5323)
			(xy 109.636203 -15.562854) (xy 109.554857 -15.586001) (xy 109.471723 -15.601544) (xy 109.387509 -15.609349)
			(xy 109.345222 -15.609824) (xy 109.302783 -15.609337) (xy 109.218312 -15.601019) (xy 109.135064 -15.584462)
			(xy 109.05384 -15.559824) (xy 108.975422 -15.527343) (xy 108.900565 -15.487331) (xy 108.829991 -15.440175)
			(xy 108.764379 -15.386328) (xy 108.704361 -15.326309) (xy 108.650515 -15.260696) (xy 108.60336 -15.190121)
			(xy 108.563351 -15.115264) (xy 108.530871 -15.036845) (xy 108.506234 -14.95562) (xy 108.489678 -14.872372)
			(xy 108.481362 -14.787901) (xy 108.48086 -14.745462) (xy 100.936335 -14.745462) (xy 100.910569 -14.822642)
			(xy 100.872044 -14.913063) (xy 100.826369 -15.000091) (xy 100.773838 -15.083161) (xy 100.714794 -15.161734)
			(xy 100.649619 -15.235302) (xy 100.578735 -15.303387) (xy 100.502602 -15.365548) (xy 100.421715 -15.42138)
			(xy 100.336597 -15.470523) (xy 100.2478 -15.512657) (xy 100.155902 -15.54751) (xy 100.061496 -15.574855)
			(xy 99.965197 -15.594514) (xy 99.867628 -15.606361) (xy 99.769422 -15.610319) (xy 99.671216 -15.606361)
			(xy 99.573647 -15.594514) (xy 99.477348 -15.574855) (xy 99.382942 -15.54751) (xy 99.291044 -15.512657)
			(xy 99.202247 -15.470523) (xy 99.117129 -15.42138) (xy 99.036242 -15.365548) (xy 98.960109 -15.303387)
			(xy 98.889225 -15.235302) (xy 98.82405 -15.161734) (xy 98.765006 -15.083161) (xy 98.712475 -15.000091)
			(xy 98.6668 -14.913063) (xy 98.628275 -14.822642) (xy 98.597151 -14.729414) (xy 98.57363 -14.633985)
			(xy 98.557864 -14.536972) (xy 98.549955 -14.439005) (xy 1.016 -14.439005) (xy 1.016 -18.545219) (xy 20.872007 -18.545219)
			(xy 20.87205 -18.453908) (xy 20.880966 -18.363033) (xy 20.898671 -18.273454) (xy 20.911312 -18.22958)
			(xy 21.129752 -18.22958) (xy 21.146337 -18.229101) (xy 21.178386 -18.220556) (xy 21.207146 -18.204033)
			(xy 21.23067 -18.180649) (xy 21.23948 -18.166588) (xy 21.257783 -18.136238) (xy 21.299908 -18.079238)
			(xy 21.347887 -18.02707) (xy 21.401171 -17.980332) (xy 21.459147 -17.939561) (xy 21.489924 -17.921986)
			(xy 21.504471 -17.913263) (xy 21.528754 -17.889601) (xy 21.545969 -17.860391) (xy 21.554909 -17.827686)
			(xy 21.555456 -17.810734) (xy 21.555456 -17.596866) (xy 21.596941 -17.585678) (xy 21.681432 -17.570032)
			(xy 21.767 -17.562177) (xy 21.852928 -17.562177) (xy 21.938496 -17.570032) (xy 22.022987 -17.585678)
			(xy 22.064472 -17.596866) (xy 22.064472 -17.810734) (xy 22.064965 -17.827699) (xy 22.073856 -17.860443)
			(xy 22.091078 -17.889676) (xy 22.115409 -17.913323) (xy 22.130004 -17.921986) (xy 22.160779 -17.939567)
			(xy 22.21877 -17.98032) (xy 22.272063 -18.02705) (xy 22.320044 -18.079219) (xy 22.362161 -18.136227)
			(xy 22.380448 -18.166588) (xy 22.389279 -18.180628) (xy 22.412809 -18.203988) (xy 22.441563 -18.220498)
			(xy 22.473598 -18.229044) (xy 22.490176 -18.22958) (xy 22.708616 -18.22958) (xy 22.72124 -18.273545)
			(xy 22.738897 -18.363302) (xy 22.747728 -18.454351) (xy 22.74824 -18.50009) (xy 22.747731 -18.545211)
			(xy 22.739127 -18.635041) (xy 22.730464 -18.679668) (xy 167.07104 -18.679668) (xy 167.07104 -18.353532)
			(xy 167.301672 -18.1229) (xy 168.897808 -18.1229) (xy 169.12844 -18.353532) (xy 169.12844 -18.679668)
			(xy 191.866266 -18.679668) (xy 191.866266 -18.353532) (xy 192.096898 -18.1229) (xy 193.693034 -18.1229)
			(xy 193.923666 -18.353532) (xy 193.923666 -18.679668) (xy 388.070852 -18.679668) (xy 388.070852 -18.353532)
			(xy 388.301484 -18.1229) (xy 389.89762 -18.1229) (xy 390.128252 -18.353532) (xy 390.128252 -18.679668)
			(xy 412.866078 -18.679668) (xy 412.866078 -18.353532) (xy 413.09671 -18.1229) (xy 414.692846 -18.1229)
			(xy 414.923478 -18.353532) (xy 414.923478 -18.679668) (xy 414.692846 -18.9103) (xy 413.09671 -18.9103)
			(xy 412.866078 -18.679668) (xy 390.128252 -18.679668) (xy 389.89762 -18.9103) (xy 388.301484 -18.9103)
			(xy 388.070852 -18.679668) (xy 193.923666 -18.679668) (xy 193.693034 -18.9103) (xy 192.096898 -18.9103)
			(xy 191.866266 -18.679668) (xy 169.12844 -18.679668) (xy 168.897808 -18.9103) (xy 167.301672 -18.9103)
			(xy 167.07104 -18.679668) (xy 22.730464 -18.679668) (xy 22.721931 -18.723629) (xy 22.709632 -18.767044)
			(xy 22.492208 -18.767044) (xy 22.475563 -18.767623) (xy 22.443406 -18.776234) (xy 22.414572 -18.792872)
			(xy 22.391024 -18.816404) (xy 22.382226 -18.830544) (xy 22.363929 -18.861244) (xy 22.321713 -18.918915)
			(xy 22.273522 -18.971695) (xy 22.219918 -19.018968) (xy 22.161527 -19.060183) (xy 22.130512 -19.07794)
			(xy 22.115939 -19.086623) (xy 22.091663 -19.110301) (xy 22.074455 -19.139522) (xy 22.065523 -19.172237)
			(xy 22.06498 -19.189192) (xy 22.06498 -19.40306) (xy 22.023416 -19.414293) (xy 21.938758 -19.430004)
			(xy 21.853016 -19.437893) (xy 21.766912 -19.437893) (xy 21.68117 -19.430004) (xy 21.596512 -19.414293)
			(xy 21.554948 -19.40306) (xy 21.554948 -19.189192) (xy 21.554425 -19.172229) (xy 21.545543 -19.139488)
			(xy 21.528329 -19.110255) (xy 21.504007 -19.086606) (xy 21.489416 -19.07794) (xy 21.458589 -19.060303)
			(xy 21.40052 -19.019407) (xy 21.347167 -18.972525) (xy 21.299145 -18.920195) (xy 21.257007 -18.863021)
			(xy 21.238718 -18.832576) (xy 21.229921 -18.818513) (xy 21.206378 -18.795158) (xy 21.177615 -18.778654)
			(xy 21.145571 -18.770116) (xy 21.12899 -18.769584) (xy 20.911058 -18.769584) (xy 20.89846 -18.725697)
			(xy 20.880839 -18.636102) (xy 20.872007 -18.545219) (xy 1.016 -18.545219) (xy 1.016 -24.826468) (xy 165.8239 -24.826468)
			(xy 165.8239 -23.230332) (xy 166.054532 -22.9997) (xy 166.380668 -22.9997) (xy 166.6113 -23.230332)
			(xy 166.6113 -23.858728) (xy 170.456352 -23.858728) (xy 170.456352 -23.532592) (xy 170.686984 -23.30196)
			(xy 172.28312 -23.30196) (xy 172.513752 -23.532592) (xy 172.513752 -23.858728) (xy 172.28312 -24.08936)
			(xy 170.686984 -24.08936) (xy 170.456352 -23.858728) (xy 166.6113 -23.858728) (xy 166.6113 -24.826468)
			(xy 177.83048 -24.826468) (xy 177.83048 -23.230332) (xy 178.061112 -22.9997) (xy 178.387248 -22.9997)
			(xy 178.61788 -23.230332) (xy 178.61788 -23.741888) (xy 189.46622 -23.741888) (xy 189.46622 -23.415752)
			(xy 189.696852 -23.18512) (xy 191.292988 -23.18512) (xy 191.52362 -23.415752) (xy 191.52362 -23.741888)
			(xy 191.292988 -23.97252) (xy 189.696852 -23.97252) (xy 189.46622 -23.741888) (xy 178.61788 -23.741888)
			(xy 178.61788 -24.826468) (xy 178.61026 -24.834088) (xy 197.2691 -24.834088) (xy 197.2691 -23.237952)
			(xy 197.499732 -23.00732) (xy 197.825868 -23.00732) (xy 198.0565 -23.237952) (xy 198.0565 -24.826468)
			(xy 386.823712 -24.826468) (xy 386.823712 -23.230332) (xy 387.054344 -22.9997) (xy 387.38048 -22.9997)
			(xy 387.611112 -23.230332) (xy 387.611112 -23.858728) (xy 391.456164 -23.858728) (xy 391.456164 -23.532592)
			(xy 391.686796 -23.30196) (xy 393.282932 -23.30196) (xy 393.513564 -23.532592) (xy 393.513564 -23.858728)
			(xy 393.282932 -24.08936) (xy 391.686796 -24.08936) (xy 391.456164 -23.858728) (xy 387.611112 -23.858728)
			(xy 387.611112 -24.826468) (xy 398.830292 -24.826468) (xy 398.830292 -23.230332) (xy 399.060924 -22.9997)
			(xy 399.38706 -22.9997) (xy 399.617692 -23.230332) (xy 399.617692 -23.741888) (xy 410.466032 -23.741888)
			(xy 410.466032 -23.415752) (xy 410.696664 -23.18512) (xy 412.2928 -23.18512) (xy 412.523432 -23.415752)
			(xy 412.523432 -23.741888) (xy 412.2928 -23.97252) (xy 410.696664 -23.97252) (xy 410.466032 -23.741888)
			(xy 399.617692 -23.741888) (xy 399.617692 -24.826468) (xy 399.610072 -24.834088) (xy 418.268912 -24.834088)
			(xy 418.268912 -23.237952) (xy 418.499544 -23.00732) (xy 418.82568 -23.00732) (xy 419.056312 -23.237952)
			(xy 419.056312 -24.834088) (xy 418.82568 -25.06472) (xy 418.499544 -25.06472) (xy 418.268912 -24.834088)
			(xy 399.610072 -24.834088) (xy 399.38706 -25.0571) (xy 399.060924 -25.0571) (xy 398.830292 -24.826468)
			(xy 387.611112 -24.826468) (xy 387.38048 -25.0571) (xy 387.054344 -25.0571) (xy 386.823712 -24.826468)
			(xy 198.0565 -24.826468) (xy 198.0565 -24.834088) (xy 197.825868 -25.06472) (xy 197.499732 -25.06472)
			(xy 197.2691 -24.834088) (xy 178.61026 -24.834088) (xy 178.387248 -25.0571) (xy 178.061112 -25.0571)
			(xy 177.83048 -24.826468) (xy 166.6113 -24.826468) (xy 166.380668 -25.0571) (xy 166.054532 -25.0571)
			(xy 165.8239 -24.826468) (xy 1.016 -24.826468) (xy 1.016 -32.2072) (xy 1.016476 -32.229251) (xy 1.024096 -32.272689)
			(xy 1.0391 -32.31416) (xy 1.061036 -32.352419) (xy 1.089246 -32.386318) (xy 1.122884 -32.414839)
			(xy 1.16094 -32.437126) (xy 1.202271 -32.452511) (xy 1.245637 -32.46053) (xy 1.289737 -32.460945)
			(xy 1.333246 -32.453741) (xy 1.374859 -32.439136) (xy 1.413327 -32.417568) (xy 1.447495 -32.389685)
			(xy 1.462278 -32.373316) (xy 1.514188 -32.313818) (xy 1.622042 -32.198468) (xy 1.677924 -32.142684)
			(xy 1.695704 -32.124904) (xy 1.734058 -32.034226) (xy 1.734058 -29.049218) (xy 1.734058 -28.950158)
			(xy 1.734058 -28.786836) (xy 1.741932 -28.778962) (xy 1.746504 -28.733496) (xy 1.746504 -28.733242)
			(xy 1.754112 -28.659741) (xy 1.776189 -28.513615) (xy 1.806038 -28.368876) (xy 1.843573 -28.225938)
			(xy 1.888687 -28.085207) (xy 1.941251 -27.947087) (xy 2.001116 -27.81197) (xy 2.068109 -27.680243)
			(xy 2.142042 -27.552281) (xy 2.222701 -27.428449) (xy 2.309858 -27.309101) (xy 2.403263 -27.194577)
			(xy 2.502651 -27.085205) (xy 2.607737 -26.981295) (xy 2.718221 -26.883145) (xy 2.833789 -26.791034)
			(xy 2.95411 -26.705226) (xy 3.078842 -26.625965) (xy 3.207628 -26.553478) (xy 3.340101 -26.48797)
			(xy 3.475882 -26.42963) (xy 3.614586 -26.378624) (xy 3.755815 -26.335097) (xy 3.899166 -26.299173)
			(xy 4.044232 -26.270955) (xy 4.190597 -26.250523) (xy 4.337845 -26.237936) (xy 4.485554 -26.23323)
			(xy 4.633304 -26.236418) (xy 4.780674 -26.24749) (xy 4.927241 -26.266416) (xy 5.072589 -26.293141)
			(xy 5.216303 -26.32759) (xy 5.357972 -26.369663) (xy 5.497192 -26.419241) (xy 5.633566 -26.476182)
			(xy 5.766706 -26.540324) (xy 5.775589 -26.545204) (xy 20.872002 -26.545204) (xy 20.872046 -26.453892)
			(xy 20.880963 -26.363017) (xy 20.89867 -26.273438) (xy 20.911312 -26.229564) (xy 21.129752 -26.229564)
			(xy 21.146337 -26.229093) (xy 21.178388 -26.220547) (xy 21.207148 -26.204021) (xy 21.230671 -26.180634)
			(xy 21.23948 -26.166572) (xy 21.257779 -26.13622) (xy 21.299905 -26.07922) (xy 21.347885 -26.027052)
			(xy 21.40117 -25.980315) (xy 21.459146 -25.939544) (xy 21.489924 -25.92197) (xy 21.504479 -25.913258)
			(xy 21.528761 -25.889592) (xy 21.545974 -25.86038) (xy 21.554911 -25.827671) (xy 21.555456 -25.810718)
			(xy 21.555456 -25.59685) (xy 21.596941 -25.585662) (xy 21.681432 -25.570016) (xy 21.767 -25.562161)
			(xy 21.852928 -25.562161) (xy 21.938496 -25.570016) (xy 22.022987 -25.585662) (xy 22.064472 -25.59685)
			(xy 22.064472 -25.810718) (xy 22.064977 -25.827683) (xy 22.073864 -25.860425) (xy 22.091083 -25.889658)
			(xy 22.11541 -25.913306) (xy 22.130004 -25.92197) (xy 22.160776 -25.939556) (xy 22.218768 -25.980308)
			(xy 22.272061 -26.027037) (xy 22.320043 -26.079205) (xy 22.362161 -26.136212) (xy 22.380448 -26.166572)
			(xy 22.389252 -26.18063) (xy 22.412795 -26.203982) (xy 22.441556 -26.220486) (xy 22.473596 -26.229029)
			(xy 22.490176 -26.229564) (xy 22.708616 -26.229564) (xy 22.721236 -26.27353) (xy 22.738894 -26.363286)
			(xy 22.747728 -26.454335) (xy 22.74824 -26.500074) (xy 22.747727 -26.545195) (xy 22.739125 -26.635025)
			(xy 22.72193 -26.723613) (xy 22.709632 -26.767028) (xy 22.492208 -26.767028) (xy 22.475553 -26.767518)
			(xy 22.443378 -26.776138) (xy 22.414531 -26.792795) (xy 22.39098 -26.816351) (xy 22.382226 -26.830528)
			(xy 22.363925 -26.861225) (xy 22.32171 -26.918897) (xy 22.27352 -26.971677) (xy 22.257883 -26.985468)
			(xy 183.6039 -26.985468) (xy 183.6039 -26.659332) (xy 183.834532 -26.4287) (xy 185.430668 -26.4287)
			(xy 185.6613 -26.659332) (xy 185.6613 -26.985468) (xy 404.603712 -26.985468) (xy 404.603712 -26.659332)
			(xy 404.834344 -26.4287) (xy 406.43048 -26.4287) (xy 406.661112 -26.659332) (xy 406.661112 -26.985468)
			(xy 406.43048 -27.2161) (xy 404.834344 -27.2161) (xy 404.603712 -26.985468) (xy 185.6613 -26.985468)
			(xy 185.430668 -27.2161) (xy 183.834532 -27.2161) (xy 183.6039 -26.985468) (xy 22.257883 -26.985468)
			(xy 22.219917 -27.018951) (xy 22.161527 -27.060166) (xy 22.130512 -27.077924) (xy 22.115946 -27.086618)
			(xy 22.091669 -27.110292) (xy 22.07446 -27.13951) (xy 22.065525 -27.172222) (xy 22.06498 -27.189176)
			(xy 22.06498 -27.403044) (xy 22.023416 -27.414277) (xy 21.938758 -27.429988) (xy 21.853016 -27.437877)
			(xy 21.766912 -27.437877) (xy 21.68117 -27.429988) (xy 21.596512 -27.414277) (xy 21.554948 -27.403044)
			(xy 21.554948 -27.189176) (xy 21.554438 -27.172212) (xy 21.545551 -27.139471) (xy 21.528334 -27.110238)
			(xy 21.504009 -27.086589) (xy 21.489416 -27.077924) (xy 21.458587 -27.060291) (xy 21.400517 -27.019395)
			(xy 21.347165 -26.972511) (xy 21.299143 -26.92018) (xy 21.257006 -26.863005) (xy 21.238718 -26.83256)
			(xy 21.229926 -26.818493) (xy 21.206381 -26.79514) (xy 21.177616 -26.778637) (xy 21.145571 -26.770099)
			(xy 21.12899 -26.769568) (xy 20.911058 -26.769568) (xy 20.898452 -26.725683) (xy 20.880832 -26.636088)
			(xy 20.872002 -26.545204) (xy 5.775589 -26.545204) (xy 5.89623 -26.611483) (xy 6.02177 -26.689458)
			(xy 6.142967 -26.774025) (xy 6.259475 -26.864942) (xy 6.370963 -26.961951) (xy 6.477111 -27.064775)
			(xy 6.577618 -27.173121) (xy 6.672195 -27.286678) (xy 6.760575 -27.405124) (xy 6.842503 -27.52812)
			(xy 6.917747 -27.655315) (xy 6.986091 -27.786347) (xy 7.047341 -27.920841) (xy 7.101323 -28.058414)
			(xy 7.147881 -28.198673) (xy 7.186883 -28.341218) (xy 7.218218 -28.485642) (xy 7.241797 -28.631533)
			(xy 7.257552 -28.778476) (xy 7.265437 -28.92605) (xy 7.265924 -28.999942) (xy 7.265924 -29.472128)
			(xy 183.83504 -29.472128) (xy 183.83504 -29.145992) (xy 184.065672 -28.91536) (xy 185.661808 -28.91536)
			(xy 185.89244 -29.145992) (xy 185.89244 -29.472128) (xy 404.834852 -29.472128) (xy 404.834852 -29.145992)
			(xy 405.065484 -28.91536) (xy 406.66162 -28.91536) (xy 406.892252 -29.145992) (xy 406.892252 -29.472128)
			(xy 406.66162 -29.70276) (xy 405.065484 -29.70276) (xy 404.834852 -29.472128) (xy 185.89244 -29.472128)
			(xy 185.661808 -29.70276) (xy 184.065672 -29.70276) (xy 183.83504 -29.472128) (xy 7.265924 -29.472128)
			(xy 7.265924 -30.897068) (xy 167.656256 -30.897068) (xy 167.656256 -30.570932) (xy 167.886888 -30.3403)
			(xy 169.483024 -30.3403) (xy 169.713656 -30.570932) (xy 169.713656 -30.897068) (xy 169.483024 -31.1277)
			(xy 167.886888 -31.1277) (xy 167.656256 -30.897068) (xy 7.265924 -30.897068) (xy 7.265924 -31.158688)
			(xy 174.856394 -31.158688) (xy 174.856394 -30.832552) (xy 175.087026 -30.60192) (xy 176.683162 -30.60192)
			(xy 176.839118 -30.757876) (xy 189.06617 -30.757876) (xy 189.06617 -30.43174) (xy 189.296802 -30.201108)
			(xy 190.892938 -30.201108) (xy 191.12357 -30.43174) (xy 191.12357 -30.726888) (xy 193.866262 -30.726888)
			(xy 193.866262 -30.400752) (xy 194.096894 -30.17012) (xy 195.70192 -30.17012) (xy 195.923662 -30.391862)
			(xy 195.923662 -30.726888) (xy 195.753482 -30.897068) (xy 388.656068 -30.897068) (xy 388.656068 -30.570932)
			(xy 388.8867 -30.3403) (xy 390.482836 -30.3403) (xy 390.713468 -30.570932) (xy 390.713468 -30.897068)
			(xy 390.482836 -31.1277) (xy 388.8867 -31.1277) (xy 388.656068 -30.897068) (xy 195.753482 -30.897068)
			(xy 195.69303 -30.95752) (xy 194.096894 -30.95752) (xy 193.866262 -30.726888) (xy 191.12357 -30.726888)
			(xy 191.12357 -30.757876) (xy 190.892938 -30.988508) (xy 189.296802 -30.988508) (xy 189.06617 -30.757876)
			(xy 176.839118 -30.757876) (xy 176.913794 -30.832552) (xy 176.913794 -31.158688) (xy 395.856206 -31.158688)
			(xy 395.856206 -30.832552) (xy 396.086838 -30.60192) (xy 397.682974 -30.60192) (xy 397.83893 -30.757876)
			(xy 410.065982 -30.757876) (xy 410.065982 -30.43174) (xy 410.296614 -30.201108) (xy 411.89275 -30.201108)
			(xy 412.123382 -30.43174) (xy 412.123382 -30.726888) (xy 414.866074 -30.726888) (xy 414.866074 -30.400752)
			(xy 415.096706 -30.17012) (xy 416.692842 -30.17012) (xy 416.923474 -30.400752) (xy 416.923474 -30.726888)
			(xy 416.692842 -30.95752) (xy 415.096706 -30.95752) (xy 414.866074 -30.726888) (xy 412.123382 -30.726888)
			(xy 412.123382 -30.757876) (xy 411.89275 -30.988508) (xy 410.296614 -30.988508) (xy 410.065982 -30.757876)
			(xy 397.83893 -30.757876) (xy 397.913606 -30.832552) (xy 397.913606 -31.158688) (xy 397.682974 -31.38932)
			(xy 396.086838 -31.38932) (xy 395.856206 -31.158688) (xy 176.913794 -31.158688) (xy 176.683162 -31.38932)
			(xy 175.087026 -31.38932) (xy 174.856394 -31.158688) (xy 7.265924 -31.158688) (xy 7.265924 -32.034226)
			(xy 7.304278 -32.124904) (xy 7.322058 -32.142684) (xy 7.328671 -32.149288) (xy 170.056302 -32.149288)
			(xy 170.056302 -31.823152) (xy 170.286934 -31.59252) (xy 171.88307 -31.59252) (xy 172.113702 -31.823152)
			(xy 172.113702 -31.844488) (xy 191.48044 -31.844488) (xy 191.48044 -31.518352) (xy 191.591184 -31.407608)
			(xy 191.614806 -31.400496) (xy 191.634364 -31.384748) (xy 191.656208 -31.368238) (xy 191.682116 -31.350458)
			(xy 191.710818 -31.29534) (xy 191.710818 -31.287974) (xy 191.711072 -31.28772) (xy 193.307208 -31.28772)
			(xy 193.53784 -31.518352) (xy 193.53784 -31.844488) (xy 193.307208 -32.07512) (xy 191.711072 -32.07512)
			(xy 191.48044 -31.844488) (xy 172.113702 -31.844488) (xy 172.113702 -32.149288) (xy 391.056114 -32.149288)
			(xy 391.056114 -31.823152) (xy 391.286746 -31.59252) (xy 392.882882 -31.59252) (xy 393.113514 -31.823152)
			(xy 393.113514 -31.844488) (xy 412.480252 -31.844488) (xy 412.480252 -31.518352) (xy 412.590996 -31.407608)
			(xy 412.614618 -31.400496) (xy 412.634176 -31.384748) (xy 412.65602 -31.368238) (xy 412.681928 -31.350458)
			(xy 412.71063 -31.29534) (xy 412.71063 -31.287974) (xy 412.710884 -31.28772) (xy 414.30702 -31.28772)
			(xy 414.537652 -31.518352) (xy 414.537652 -31.844488) (xy 414.30702 -32.07512) (xy 412.710884 -32.07512)
			(xy 412.480252 -31.844488) (xy 393.113514 -31.844488) (xy 393.113514 -32.149288) (xy 392.882882 -32.37992)
			(xy 391.286746 -32.37992) (xy 391.056114 -32.149288) (xy 172.113702 -32.149288) (xy 171.88307 -32.37992)
			(xy 170.286934 -32.37992) (xy 170.056302 -32.149288) (xy 7.328671 -32.149288) (xy 7.385608 -32.206151)
			(xy 7.507639 -32.337964) (xy 7.623654 -32.475101) (xy 7.733421 -32.617289) (xy 7.83672 -32.764242)
			(xy 7.933346 -32.915667) (xy 8.023105 -33.071261) (xy 8.105817 -33.230712) (xy 8.181316 -33.393703)
			(xy 8.249453 -33.559906) (xy 8.277861 -33.639119) (xy 165.265595 -33.639119) (xy 165.265595 -33.540833)
			(xy 165.273504 -33.442866) (xy 165.28927 -33.345853) (xy 165.312791 -33.250424) (xy 165.343915 -33.157196)
			(xy 165.38244 -33.066775) (xy 165.428115 -32.979748) (xy 165.480646 -32.896677) (xy 165.53969 -32.818104)
			(xy 165.604865 -32.744536) (xy 165.675749 -32.676451) (xy 165.751882 -32.61429) (xy 165.832769 -32.558458)
			(xy 165.917887 -32.509315) (xy 166.006684 -32.467181) (xy 166.098582 -32.432328) (xy 166.192988 -32.404983)
			(xy 166.289287 -32.385324) (xy 166.386856 -32.373477) (xy 166.485062 -32.369519) (xy 166.583268 -32.373477)
			(xy 166.680837 -32.385324) (xy 166.777136 -32.404983) (xy 166.871542 -32.432328) (xy 166.96344 -32.467181)
			(xy 167.052237 -32.509315) (xy 167.137355 -32.558458) (xy 167.218242 -32.61429) (xy 167.294375 -32.676451)
			(xy 167.365259 -32.744536) (xy 167.430434 -32.818104) (xy 167.489478 -32.896677) (xy 167.542009 -32.979748)
			(xy 167.587684 -33.066775) (xy 167.593944 -33.081468) (xy 172.481748 -33.081468) (xy 172.481748 -32.755332)
			(xy 172.71238 -32.5247) (xy 174.308516 -32.5247) (xy 174.539148 -32.755332) (xy 174.539148 -33.081468)
			(xy 174.308516 -33.3121) (xy 172.71238 -33.3121) (xy 172.481748 -33.081468) (xy 167.593944 -33.081468)
			(xy 167.626209 -33.157196) (xy 167.657333 -33.250424) (xy 167.680854 -33.345853) (xy 167.69662 -33.442866)
			(xy 167.704529 -33.540833) (xy 167.705024 -33.589976) (xy 167.704529 -33.639119) (xy 167.704526 -33.63915)
			(xy 177.264809 -33.63915) (xy 177.264809 -33.540802) (xy 177.272723 -33.442774) (xy 177.288499 -33.345701)
			(xy 177.312035 -33.250211) (xy 177.343178 -33.156926) (xy 177.381727 -33.066448) (xy 177.427431 -32.979366)
			(xy 177.479994 -32.896244) (xy 177.539075 -32.817621) (xy 177.604292 -32.744008) (xy 177.67522 -32.67588)
			(xy 177.7514 -32.613681) (xy 177.832338 -32.557813) (xy 177.917509 -32.50864) (xy 178.006361 -32.466479)
			(xy 178.098317 -32.431605) (xy 178.192781 -32.404243) (xy 178.289141 -32.384571) (xy 178.386771 -32.372717)
			(xy 178.485038 -32.368757) (xy 178.583305 -32.372717) (xy 178.680935 -32.384571) (xy 178.777295 -32.404243)
			(xy 178.871759 -32.431605) (xy 178.963715 -32.466479) (xy 179.052567 -32.50864) (xy 179.137738 -32.557813)
			(xy 179.218676 -32.613681) (xy 179.294856 -32.67588) (xy 179.365784 -32.744008) (xy 179.431001 -32.817621)
			(xy 179.490082 -32.896244) (xy 179.542645 -32.979366) (xy 179.588349 -33.066448) (xy 179.626898 -33.156926)
			(xy 179.658041 -33.250211) (xy 179.681577 -33.345701) (xy 179.697353 -33.442774) (xy 179.705267 -33.540802)
			(xy 179.705762 -33.589976) (xy 179.705267 -33.639119) (xy 184.275463 -33.639119) (xy 184.275463 -33.540833)
			(xy 184.283372 -33.442866) (xy 184.299138 -33.345853) (xy 184.322659 -33.250424) (xy 184.353783 -33.157196)
			(xy 184.392308 -33.066775) (xy 184.437983 -32.979748) (xy 184.490514 -32.896677) (xy 184.549558 -32.818104)
			(xy 184.614733 -32.744536) (xy 184.685617 -32.676451) (xy 184.76175 -32.61429) (xy 184.842637 -32.558458)
			(xy 184.927755 -32.509315) (xy 185.016552 -32.467181) (xy 185.10845 -32.432328) (xy 185.202856 -32.404983)
			(xy 185.299155 -32.385324) (xy 185.396724 -32.373477) (xy 185.49493 -32.369519) (xy 185.593136 -32.373477)
			(xy 185.690705 -32.385324) (xy 185.787004 -32.404983) (xy 185.88141 -32.432328) (xy 185.973308 -32.467181)
			(xy 186.062105 -32.509315) (xy 186.147223 -32.558458) (xy 186.22811 -32.61429) (xy 186.304243 -32.676451)
			(xy 186.375127 -32.744536) (xy 186.440302 -32.818104) (xy 186.499346 -32.896677) (xy 186.551877 -32.979748)
			(xy 186.597552 -33.066775) (xy 186.636077 -33.157196) (xy 186.667201 -33.250424) (xy 186.690722 -33.345853)
			(xy 186.706488 -33.442866) (xy 186.714397 -33.540833) (xy 186.714892 -33.589976) (xy 186.714397 -33.639119)
			(xy 186.714394 -33.63915) (xy 196.274677 -33.63915) (xy 196.274677 -33.540802) (xy 196.282591 -33.442774)
			(xy 196.298367 -33.345701) (xy 196.321903 -33.250211) (xy 196.353046 -33.156926) (xy 196.391595 -33.066448)
			(xy 196.437299 -32.979366) (xy 196.489862 -32.896244) (xy 196.548943 -32.817621) (xy 196.61416 -32.744008)
			(xy 196.685088 -32.67588) (xy 196.761268 -32.613681) (xy 196.842206 -32.557813) (xy 196.927377 -32.50864)
			(xy 197.016229 -32.466479) (xy 197.108185 -32.431605) (xy 197.202649 -32.404243) (xy 197.299009 -32.384571)
			(xy 197.396639 -32.372717) (xy 197.494906 -32.368757) (xy 197.593173 -32.372717) (xy 197.690803 -32.384571)
			(xy 197.787163 -32.404243) (xy 197.881627 -32.431605) (xy 197.973583 -32.466479) (xy 198.062435 -32.50864)
			(xy 198.147606 -32.557813) (xy 198.228544 -32.613681) (xy 198.304724 -32.67588) (xy 198.375652 -32.744008)
			(xy 198.440869 -32.817621) (xy 198.49995 -32.896244) (xy 198.552513 -32.979366) (xy 198.598217 -33.066448)
			(xy 198.636766 -33.156926) (xy 198.667909 -33.250211) (xy 198.691445 -33.345701) (xy 198.707221 -33.442774)
			(xy 198.715135 -33.540802) (xy 198.71563 -33.589976) (xy 198.715135 -33.639119) (xy 386.265407 -33.639119)
			(xy 386.265407 -33.540833) (xy 386.273316 -33.442866) (xy 386.289082 -33.345853) (xy 386.312603 -33.250424)
			(xy 386.343727 -33.157196) (xy 386.382252 -33.066775) (xy 386.427927 -32.979748) (xy 386.480458 -32.896677)
			(xy 386.539502 -32.818104) (xy 386.604677 -32.744536) (xy 386.675561 -32.676451) (xy 386.751694 -32.61429)
			(xy 386.832581 -32.558458) (xy 386.917699 -32.509315) (xy 387.006496 -32.467181) (xy 387.098394 -32.432328)
			(xy 387.1928 -32.404983) (xy 387.289099 -32.385324) (xy 387.386668 -32.373477) (xy 387.484874 -32.369519)
			(xy 387.58308 -32.373477) (xy 387.680649 -32.385324) (xy 387.776948 -32.404983) (xy 387.871354 -32.432328)
			(xy 387.963252 -32.467181) (xy 388.052049 -32.509315) (xy 388.137167 -32.558458) (xy 388.218054 -32.61429)
			(xy 388.294187 -32.676451) (xy 388.365071 -32.744536) (xy 388.430246 -32.818104) (xy 388.48929 -32.896677)
			(xy 388.541821 -32.979748) (xy 388.587496 -33.066775) (xy 388.593756 -33.081468) (xy 393.48156 -33.081468)
			(xy 393.48156 -32.755332) (xy 393.712192 -32.5247) (xy 395.308328 -32.5247) (xy 395.53896 -32.755332)
			(xy 395.53896 -33.081468) (xy 395.308328 -33.3121) (xy 393.712192 -33.3121) (xy 393.48156 -33.081468)
			(xy 388.593756 -33.081468) (xy 388.626021 -33.157196) (xy 388.657145 -33.250424) (xy 388.680666 -33.345853)
			(xy 388.696432 -33.442866) (xy 388.704341 -33.540833) (xy 388.704836 -33.589976) (xy 388.704341 -33.639119)
			(xy 388.704338 -33.63915) (xy 398.264621 -33.63915) (xy 398.264621 -33.540802) (xy 398.272535 -33.442774)
			(xy 398.288311 -33.345701) (xy 398.311847 -33.250211) (xy 398.34299 -33.156926) (xy 398.381539 -33.066448)
			(xy 398.427243 -32.979366) (xy 398.479806 -32.896244) (xy 398.538887 -32.817621) (xy 398.604104 -32.744008)
			(xy 398.675032 -32.67588) (xy 398.751212 -32.613681) (xy 398.83215 -32.557813) (xy 398.917321 -32.50864)
			(xy 399.006173 -32.466479) (xy 399.098129 -32.431605) (xy 399.192593 -32.404243) (xy 399.288953 -32.384571)
			(xy 399.386583 -32.372717) (xy 399.48485 -32.368757) (xy 399.583117 -32.372717) (xy 399.680747 -32.384571)
			(xy 399.777107 -32.404243) (xy 399.871571 -32.431605) (xy 399.963527 -32.466479) (xy 400.052379 -32.50864)
			(xy 400.13755 -32.557813) (xy 400.218488 -32.613681) (xy 400.294668 -32.67588) (xy 400.365596 -32.744008)
			(xy 400.430813 -32.817621) (xy 400.489894 -32.896244) (xy 400.542457 -32.979366) (xy 400.588161 -33.066448)
			(xy 400.62671 -33.156926) (xy 400.657853 -33.250211) (xy 400.681389 -33.345701) (xy 400.697165 -33.442774)
			(xy 400.705079 -33.540802) (xy 400.705574 -33.589976) (xy 400.705079 -33.639119) (xy 405.275529 -33.639119)
			(xy 405.275529 -33.540833) (xy 405.283438 -33.442866) (xy 405.299204 -33.345853) (xy 405.322725 -33.250424)
			(xy 405.353849 -33.157196) (xy 405.392374 -33.066775) (xy 405.438049 -32.979748) (xy 405.49058 -32.896677)
			(xy 405.549624 -32.818104) (xy 405.614799 -32.744536) (xy 405.685683 -32.676451) (xy 405.761816 -32.61429)
			(xy 405.842703 -32.558458) (xy 405.927821 -32.509315) (xy 406.016618 -32.467181) (xy 406.108516 -32.432328)
			(xy 406.202922 -32.404983) (xy 406.299221 -32.385324) (xy 406.39679 -32.373477) (xy 406.494996 -32.369519)
			(xy 406.593202 -32.373477) (xy 406.690771 -32.385324) (xy 406.78707 -32.404983) (xy 406.881476 -32.432328)
			(xy 406.973374 -32.467181) (xy 407.062171 -32.509315) (xy 407.147289 -32.558458) (xy 407.228176 -32.61429)
			(xy 407.304309 -32.676451) (xy 407.375193 -32.744536) (xy 407.440368 -32.818104) (xy 407.499412 -32.896677)
			(xy 407.551943 -32.979748) (xy 407.597618 -33.066775) (xy 407.636143 -33.157196) (xy 407.667267 -33.250424)
			(xy 407.690788 -33.345853) (xy 407.706554 -33.442866) (xy 407.714463 -33.540833) (xy 407.714958 -33.589976)
			(xy 407.714463 -33.639119) (xy 407.71446 -33.63915) (xy 417.274743 -33.63915) (xy 417.274743 -33.540802)
			(xy 417.282657 -33.442774) (xy 417.298433 -33.345701) (xy 417.321969 -33.250211) (xy 417.353112 -33.156926)
			(xy 417.391661 -33.066448) (xy 417.437365 -32.979366) (xy 417.489928 -32.896244) (xy 417.549009 -32.817621)
			(xy 417.614226 -32.744008) (xy 417.685154 -32.67588) (xy 417.761334 -32.613681) (xy 417.842272 -32.557813)
			(xy 417.927443 -32.50864) (xy 418.016295 -32.466479) (xy 418.108251 -32.431605) (xy 418.202715 -32.404243)
			(xy 418.299075 -32.384571) (xy 418.396705 -32.372717) (xy 418.494972 -32.368757) (xy 418.593239 -32.372717)
			(xy 418.690869 -32.384571) (xy 418.787229 -32.404243) (xy 418.881693 -32.431605) (xy 418.973649 -32.466479)
			(xy 419.062501 -32.50864) (xy 419.147672 -32.557813) (xy 419.22861 -32.613681) (xy 419.30479 -32.67588)
			(xy 419.375718 -32.744008) (xy 419.440935 -32.817621) (xy 419.500016 -32.896244) (xy 419.552579 -32.979366)
			(xy 419.598283 -33.066448) (xy 419.636832 -33.156926) (xy 419.667975 -33.250211) (xy 419.691511 -33.345701)
			(xy 419.707287 -33.442774) (xy 419.715201 -33.540802) (xy 419.715696 -33.589976) (xy 419.715201 -33.63915)
			(xy 419.707287 -33.737178) (xy 419.691511 -33.834251) (xy 419.667975 -33.929741) (xy 419.636832 -34.023026)
			(xy 419.598283 -34.113504) (xy 419.552579 -34.200586) (xy 419.500016 -34.283708) (xy 419.440935 -34.362331)
			(xy 419.375718 -34.435944) (xy 419.30479 -34.504072) (xy 419.22861 -34.566271) (xy 419.147672 -34.622139)
			(xy 419.062501 -34.671312) (xy 418.973649 -34.713473) (xy 418.881693 -34.748347) (xy 418.787229 -34.775709)
			(xy 418.690869 -34.795381) (xy 418.593239 -34.807235) (xy 418.494972 -34.811196) (xy 418.396705 -34.807235)
			(xy 418.299075 -34.795381) (xy 418.202715 -34.775709) (xy 418.108251 -34.748347) (xy 418.016295 -34.713473)
			(xy 417.927443 -34.671312) (xy 417.842272 -34.622139) (xy 417.761334 -34.566271) (xy 417.685154 -34.504072)
			(xy 417.614226 -34.435944) (xy 417.549009 -34.362331) (xy 417.489928 -34.283708) (xy 417.437365 -34.200586)
			(xy 417.391661 -34.113504) (xy 417.353112 -34.023026) (xy 417.321969 -33.929741) (xy 417.298433 -33.834251)
			(xy 417.282657 -33.737178) (xy 417.274743 -33.63915) (xy 407.71446 -33.63915) (xy 407.706554 -33.737086)
			(xy 407.690788 -33.834099) (xy 407.667267 -33.929528) (xy 407.636143 -34.022756) (xy 407.597618 -34.113177)
			(xy 407.551943 -34.200205) (xy 407.499412 -34.283275) (xy 407.440368 -34.361848) (xy 407.375193 -34.435416)
			(xy 407.304309 -34.503501) (xy 407.228176 -34.565662) (xy 407.147289 -34.621494) (xy 407.062171 -34.670637)
			(xy 406.973374 -34.712771) (xy 406.881476 -34.747624) (xy 406.78707 -34.774969) (xy 406.690771 -34.794628)
			(xy 406.593202 -34.806475) (xy 406.494996 -34.810433) (xy 406.39679 -34.806475) (xy 406.299221 -34.794628)
			(xy 406.202922 -34.774969) (xy 406.108516 -34.747624) (xy 406.016618 -34.712771) (xy 405.927821 -34.670637)
			(xy 405.842703 -34.621494) (xy 405.761816 -34.565662) (xy 405.685683 -34.503501) (xy 405.614799 -34.435416)
			(xy 405.549624 -34.361848) (xy 405.49058 -34.283275) (xy 405.438049 -34.200205) (xy 405.392374 -34.113177)
			(xy 405.353849 -34.022756) (xy 405.322725 -33.929528) (xy 405.299204 -33.834099) (xy 405.283438 -33.737086)
			(xy 405.275529 -33.639119) (xy 400.705079 -33.639119) (xy 400.705079 -33.63915) (xy 400.697165 -33.737178)
			(xy 400.681389 -33.834251) (xy 400.657853 -33.929741) (xy 400.62671 -34.023026) (xy 400.588161 -34.113504)
			(xy 400.542457 -34.200586) (xy 400.489894 -34.283708) (xy 400.430813 -34.362331) (xy 400.365596 -34.435944)
			(xy 400.294668 -34.504072) (xy 400.218488 -34.566271) (xy 400.13755 -34.622139) (xy 400.052379 -34.671312)
			(xy 399.963527 -34.713473) (xy 399.871571 -34.748347) (xy 399.777107 -34.775709) (xy 399.680747 -34.795381)
			(xy 399.583117 -34.807235) (xy 399.48485 -34.811196) (xy 399.386583 -34.807235) (xy 399.288953 -34.795381)
			(xy 399.192593 -34.775709) (xy 399.098129 -34.748347) (xy 399.006173 -34.713473) (xy 398.917321 -34.671312)
			(xy 398.83215 -34.622139) (xy 398.751212 -34.566271) (xy 398.675032 -34.504072) (xy 398.604104 -34.435944)
			(xy 398.538887 -34.362331) (xy 398.479806 -34.283708) (xy 398.427243 -34.200586) (xy 398.381539 -34.113504)
			(xy 398.34299 -34.023026) (xy 398.311847 -33.929741) (xy 398.288311 -33.834251) (xy 398.272535 -33.737178)
			(xy 398.264621 -33.63915) (xy 388.704338 -33.63915) (xy 388.696432 -33.737086) (xy 388.680666 -33.834099)
			(xy 388.657145 -33.929528) (xy 388.626021 -34.022756) (xy 388.587496 -34.113177) (xy 388.541821 -34.200205)
			(xy 388.48929 -34.283275) (xy 388.430246 -34.361848) (xy 388.365071 -34.435416) (xy 388.294187 -34.503501)
			(xy 388.218054 -34.565662) (xy 388.137167 -34.621494) (xy 388.052049 -34.670637) (xy 387.963252 -34.712771)
			(xy 387.871354 -34.747624) (xy 387.776948 -34.774969) (xy 387.680649 -34.794628) (xy 387.58308 -34.806475)
			(xy 387.484874 -34.810433) (xy 387.386668 -34.806475) (xy 387.289099 -34.794628) (xy 387.1928 -34.774969)
			(xy 387.098394 -34.747624) (xy 387.006496 -34.712771) (xy 386.917699 -34.670637) (xy 386.832581 -34.621494)
			(xy 386.751694 -34.565662) (xy 386.675561 -34.503501) (xy 386.604677 -34.435416) (xy 386.539502 -34.361848)
			(xy 386.480458 -34.283275) (xy 386.427927 -34.200205) (xy 386.382252 -34.113177) (xy 386.343727 -34.022756)
			(xy 386.312603 -33.929528) (xy 386.289082 -33.834099) (xy 386.273316 -33.737086) (xy 386.265407 -33.639119)
			(xy 198.715135 -33.639119) (xy 198.715135 -33.63915) (xy 198.707221 -33.737178) (xy 198.691445 -33.834251)
			(xy 198.667909 -33.929741) (xy 198.636766 -34.023026) (xy 198.598217 -34.113504) (xy 198.552513 -34.200586)
			(xy 198.49995 -34.283708) (xy 198.440869 -34.362331) (xy 198.375652 -34.435944) (xy 198.304724 -34.504072)
			(xy 198.228544 -34.566271) (xy 198.147606 -34.622139) (xy 198.062435 -34.671312) (xy 197.973583 -34.713473)
			(xy 197.881627 -34.748347) (xy 197.787163 -34.775709) (xy 197.690803 -34.795381) (xy 197.593173 -34.807235)
			(xy 197.494906 -34.811196) (xy 197.396639 -34.807235) (xy 197.299009 -34.795381) (xy 197.202649 -34.775709)
			(xy 197.108185 -34.748347) (xy 197.016229 -34.713473) (xy 196.927377 -34.671312) (xy 196.842206 -34.622139)
			(xy 196.761268 -34.566271) (xy 196.685088 -34.504072) (xy 196.61416 -34.435944) (xy 196.548943 -34.362331)
			(xy 196.489862 -34.283708) (xy 196.437299 -34.200586) (xy 196.391595 -34.113504) (xy 196.353046 -34.023026)
			(xy 196.321903 -33.929741) (xy 196.298367 -33.834251) (xy 196.282591 -33.737178) (xy 196.274677 -33.63915)
			(xy 186.714394 -33.63915) (xy 186.706488 -33.737086) (xy 186.690722 -33.834099) (xy 186.667201 -33.929528)
			(xy 186.636077 -34.022756) (xy 186.597552 -34.113177) (xy 186.551877 -34.200205) (xy 186.499346 -34.283275)
			(xy 186.440302 -34.361848) (xy 186.375127 -34.435416) (xy 186.304243 -34.503501) (xy 186.22811 -34.565662)
			(xy 186.147223 -34.621494) (xy 186.062105 -34.670637) (xy 185.973308 -34.712771) (xy 185.88141 -34.747624)
			(xy 185.787004 -34.774969) (xy 185.690705 -34.794628) (xy 185.593136 -34.806475) (xy 185.49493 -34.810433)
			(xy 185.396724 -34.806475) (xy 185.299155 -34.794628) (xy 185.202856 -34.774969) (xy 185.10845 -34.747624)
			(xy 185.016552 -34.712771) (xy 184.927755 -34.670637) (xy 184.842637 -34.621494) (xy 184.76175 -34.565662)
			(xy 184.685617 -34.503501) (xy 184.614733 -34.435416) (xy 184.549558 -34.361848) (xy 184.490514 -34.283275)
			(xy 184.437983 -34.200205) (xy 184.392308 -34.113177) (xy 184.353783 -34.022756) (xy 184.322659 -33.929528)
			(xy 184.299138 -33.834099) (xy 184.283372 -33.737086) (xy 184.275463 -33.639119) (xy 179.705267 -33.639119)
			(xy 179.705267 -33.63915) (xy 179.697353 -33.737178) (xy 179.681577 -33.834251) (xy 179.658041 -33.929741)
			(xy 179.626898 -34.023026) (xy 179.588349 -34.113504) (xy 179.542645 -34.200586) (xy 179.490082 -34.283708)
			(xy 179.431001 -34.362331) (xy 179.365784 -34.435944) (xy 179.294856 -34.504072) (xy 179.218676 -34.566271)
			(xy 179.137738 -34.622139) (xy 179.052567 -34.671312) (xy 178.963715 -34.713473) (xy 178.871759 -34.748347)
			(xy 178.777295 -34.775709) (xy 178.680935 -34.795381) (xy 178.583305 -34.807235) (xy 178.485038 -34.811196)
			(xy 178.386771 -34.807235) (xy 178.289141 -34.795381) (xy 178.192781 -34.775709) (xy 178.098317 -34.748347)
			(xy 178.006361 -34.713473) (xy 177.917509 -34.671312) (xy 177.832338 -34.622139) (xy 177.7514 -34.566271)
			(xy 177.67522 -34.504072) (xy 177.604292 -34.435944) (xy 177.539075 -34.362331) (xy 177.479994 -34.283708)
			(xy 177.427431 -34.200586) (xy 177.381727 -34.113504) (xy 177.343178 -34.023026) (xy 177.312035 -33.929741)
			(xy 177.288499 -33.834251) (xy 177.272723 -33.737178) (xy 177.264809 -33.63915) (xy 167.704526 -33.63915)
			(xy 167.69662 -33.737086) (xy 167.680854 -33.834099) (xy 167.657333 -33.929528) (xy 167.626209 -34.022756)
			(xy 167.587684 -34.113177) (xy 167.542009 -34.200205) (xy 167.489478 -34.283275) (xy 167.430434 -34.361848)
			(xy 167.365259 -34.435416) (xy 167.294375 -34.503501) (xy 167.218242 -34.565662) (xy 167.137355 -34.621494)
			(xy 167.052237 -34.670637) (xy 166.96344 -34.712771) (xy 166.871542 -34.747624) (xy 166.777136 -34.774969)
			(xy 166.680837 -34.794628) (xy 166.583268 -34.806475) (xy 166.485062 -34.810433) (xy 166.386856 -34.806475)
			(xy 166.289287 -34.794628) (xy 166.192988 -34.774969) (xy 166.098582 -34.747624) (xy 166.006684 -34.712771)
			(xy 165.917887 -34.670637) (xy 165.832769 -34.621494) (xy 165.751882 -34.565662) (xy 165.675749 -34.503501)
			(xy 165.604865 -34.435416) (xy 165.53969 -34.361848) (xy 165.480646 -34.283275) (xy 165.428115 -34.200205)
			(xy 165.38244 -34.113177) (xy 165.343915 -34.022756) (xy 165.312791 -33.929528) (xy 165.28927 -33.834099)
			(xy 165.273504 -33.737086) (xy 165.265595 -33.639119) (xy 8.277861 -33.639119) (xy 8.31009 -33.728989)
			(xy 8.363106 -33.900614) (xy 8.408396 -34.074439) (xy 8.445868 -34.250114) (xy 8.475448 -34.42729)
			(xy 8.497076 -34.60561) (xy 8.51071 -34.78472) (xy 8.516322 -34.96426) (xy 8.5139 -35.143871) (xy 8.50345 -35.323194)
			(xy 8.484993 -35.501871) (xy 8.458565 -35.679543) (xy 8.424219 -35.855857) (xy 8.382024 -36.030458)
			(xy 8.332065 -36.202998) (xy 8.274441 -36.373132) (xy 8.209267 -36.540519) (xy 8.136675 -36.704825)
			(xy 8.056808 -36.865721) (xy 7.969828 -37.022884) (xy 7.875907 -37.176002) (xy 7.775234 -37.324767)
			(xy 7.66801 -37.468881) (xy 7.642576 -37.500052) (xy 9.403341 -37.500052) (xy 9.407346 -37.412144)
			(xy 9.419329 -37.324964) (xy 9.439189 -37.239235) (xy 9.466764 -37.155667) (xy 9.501823 -37.074953)
			(xy 9.544076 -36.997761) (xy 9.593174 -36.924732) (xy 9.64871 -36.85647) (xy 9.710222 -36.79354)
			(xy 9.777203 -36.736466) (xy 9.849096 -36.685718) (xy 9.925305 -36.641718) (xy 10.0052 -36.604831)
			(xy 10.088119 -36.575362) (xy 10.173374 -36.553555) (xy 10.260258 -36.539591) (xy 10.348052 -36.533585)
			(xy 10.436029 -36.535589) (xy 10.523459 -36.545584) (xy 10.609618 -36.563488) (xy 10.693792 -36.589152)
			(xy 10.775283 -36.622365) (xy 10.853417 -36.662851) (xy 10.927545 -36.710273) (xy 10.997053 -36.76424)
			(xy 11.061367 -36.824305) (xy 11.119951 -36.889969) (xy 11.172322 -36.960688) (xy 11.218045 -37.035876)
			(xy 11.256742 -37.114911) (xy 11.288091 -37.197137) (xy 11.311833 -37.281873) (xy 11.327771 -37.368417)
			(xy 11.335773 -37.456052) (xy 11.336274 -37.500052) (xy 11.335773 -37.544052) (xy 11.327771 -37.631687)
			(xy 11.311833 -37.718231) (xy 11.288091 -37.802967) (xy 11.256742 -37.885193) (xy 11.218045 -37.964228)
			(xy 11.172322 -38.039416) (xy 11.119951 -38.110135) (xy 11.061367 -38.175799) (xy 10.997053 -38.235864)
			(xy 10.927545 -38.289831) (xy 10.853417 -38.337253) (xy 10.775283 -38.377739) (xy 10.693792 -38.410952)
			(xy 10.609618 -38.436616) (xy 10.523459 -38.45452) (xy 10.436029 -38.464515) (xy 10.348052 -38.466519)
			(xy 10.260258 -38.460513) (xy 10.173374 -38.446549) (xy 10.088119 -38.424742) (xy 10.0052 -38.395273)
			(xy 9.925305 -38.358386) (xy 9.849096 -38.314386) (xy 9.777203 -38.263638) (xy 9.710222 -38.206564)
			(xy 9.64871 -38.143634) (xy 9.593174 -38.075372) (xy 9.544076 -38.002343) (xy 9.501823 -37.925151)
			(xy 9.466764 -37.844437) (xy 9.439189 -37.760869) (xy 9.419329 -37.67514) (xy 9.407346 -37.58796)
			(xy 9.403341 -37.500052) (xy 7.642576 -37.500052) (xy 7.554449 -37.608058) (xy 7.43478 -37.742018)
			(xy 7.30924 -37.870493) (xy 7.178081 -37.993226) (xy 7.041566 -38.109972) (xy 6.899968 -38.220498)
			(xy 6.753569 -38.324582) (xy 6.602663 -38.422016) (xy 6.447551 -38.512605) (xy 6.288544 -38.596168)
			(xy 6.12596 -38.672538) (xy 5.960123 -38.741562) (xy 5.791367 -38.803103) (xy 5.620027 -38.857036)
			(xy 5.446447 -38.903254) (xy 5.270975 -38.941665) (xy 5.09396 -38.972192) (xy 4.915758 -38.994773)
			(xy 4.736724 -39.009364) (xy 4.557216 -39.015936) (xy 4.377595 -39.014474) (xy 4.198218 -39.004983)
			(xy 4.019445 -38.987481) (xy 3.841634 -38.962004) (xy 3.665139 -38.928601) (xy 3.490315 -38.88734)
			(xy 3.31751 -38.838304) (xy 3.147071 -38.78159) (xy 2.979337 -38.717313) (xy 2.814646 -38.6456) (xy 2.653326 -38.566594)
			(xy 2.495699 -38.480455) (xy 2.342082 -38.387355) (xy 2.192781 -38.287478) (xy 2.048095 -38.181026)
			(xy 1.908313 -38.068212) (xy 1.773716 -37.94926) (xy 1.644571 -37.824409) (xy 1.521138 -37.693908)
			(xy 1.462024 -37.62629) (xy 1.447247 -37.609935) (xy 1.413088 -37.582086) (xy 1.374636 -37.560548)
			(xy 1.333044 -37.545968) (xy 1.28956 -37.538784) (xy 1.245489 -37.539211) (xy 1.202153 -37.547236)
			(xy 1.160851 -37.562619) (xy 1.122823 -37.584897) (xy 1.08921 -37.613403) (xy 1.06102 -37.647282)
			(xy 1.039098 -37.685516) (xy 1.024102 -37.72696) (xy 1.016483 -37.77037) (xy 1.016 -37.792406) (xy 1.016 -46.4058)
			(xy 1.016543 -46.422448) (xy 1.025161 -46.454611) (xy 1.041809 -46.483446) (xy 1.065354 -46.506991)
			(xy 1.094189 -46.523639) (xy 1.126352 -46.532257) (xy 1.143 -46.5328) (xy 9.307068 -46.5328) (xy 9.323726 -46.532309)
			(xy 9.355907 -46.523693) (xy 9.384761 -46.507041) (xy 9.408321 -46.483487) (xy 9.424981 -46.454637)
			(xy 9.433605 -46.422457) (xy 9.434068 -46.4058) (xy 9.434068 -42.650664) (xy 9.434569 -42.598323)
			(xy 9.442583 -42.493948) (xy 9.458562 -42.390492) (xy 9.482415 -42.288563) (xy 9.513999 -42.188759)
			(xy 9.553131 -42.091666) (xy 9.599581 -41.997853) (xy 9.653076 -41.907872) (xy 9.713302 -41.822249)
			(xy 9.779905 -41.741487) (xy 9.852495 -41.666062) (xy 9.930646 -41.596414) (xy 10.013899 -41.532952)
			(xy 10.101766 -41.476051) (xy 10.193731 -41.426042) (xy 10.289254 -41.383219) (xy 10.387775 -41.347835)
			(xy 10.488715 -41.320096) (xy 10.591483 -41.300165) (xy 10.695474 -41.28816) (xy 10.80008 -41.284151)
			(xy 10.904686 -41.28816) (xy 11.008677 -41.300165) (xy 11.111445 -41.320096) (xy 11.212385 -41.347835)
			(xy 11.310906 -41.383219) (xy 11.406429 -41.426042) (xy 11.498394 -41.476051) (xy 11.586261 -41.532952)
			(xy 11.669514 -41.596414) (xy 11.747665 -41.666062) (xy 11.820255 -41.741487) (xy 11.886858 -41.822249)
			(xy 11.947084 -41.907872) (xy 12.000579 -41.997853) (xy 12.047029 -42.091666) (xy 12.086161 -42.188759)
			(xy 12.117745 -42.288563) (xy 12.141598 -42.390492) (xy 12.157577 -42.493948) (xy 12.165591 -42.598323)
			(xy 12.166092 -42.650664) (xy 12.166092 -45.1104) (xy 12.166635 -45.127049) (xy 12.175253 -45.159212)
			(xy 12.191901 -45.188049) (xy 12.215445 -45.211594) (xy 12.244281 -45.228244) (xy 12.276443 -45.236864)
			(xy 12.293092 -45.2374) (xy 50.936906 -45.2374) (xy 50.953554 -45.236856) (xy 50.985715 -45.228237)
			(xy 51.014549 -45.211588) (xy 51.038092 -45.188044) (xy 51.05474 -45.159209) (xy 51.063357 -45.127048)
			(xy 51.063906 -45.1104) (xy 51.063906 -43.319954) (xy 51.064393 -43.256614) (xy 51.072347 -43.130184)
			(xy 51.088224 -43.004503) (xy 51.111962 -42.880067) (xy 51.143466 -42.757366) (xy 51.182612 -42.636887)
			(xy 51.229246 -42.519102) (xy 51.283183 -42.404479) (xy 51.344212 -42.293468) (xy 51.41209 -42.186509)
			(xy 51.486551 -42.084023) (xy 51.5673 -41.986414) (xy 51.654018 -41.894068) (xy 51.746364 -41.80735)
			(xy 51.843973 -41.726601) (xy 51.946459 -41.65214) (xy 52.053418 -41.584262) (xy 52.164429 -41.523233)
			(xy 52.279052 -41.469296) (xy 52.396837 -41.422662) (xy 52.517316 -41.383516) (xy 52.640017 -41.352012)
			(xy 52.764453 -41.328274) (xy 52.890134 -41.312397) (xy 53.016564 -41.304443) (xy 53.079904 -41.303956)
			(xy 55.0799 -41.303956) (xy 55.14324 -41.304454) (xy 55.269671 -41.312408) (xy 55.395352 -41.328285)
			(xy 55.519789 -41.352022) (xy 55.642489 -41.383526) (xy 55.76297 -41.422671) (xy 55.880754 -41.469305)
			(xy 55.995378 -41.523242) (xy 56.10639 -41.58427) (xy 56.21335 -41.652148) (xy 56.315837 -41.726608)
			(xy 56.413447 -41.807356) (xy 56.505794 -41.894074) (xy 56.592514 -41.986419) (xy 56.673264 -42.084026)
			(xy 56.747726 -42.186512) (xy 56.815607 -42.293471) (xy 56.876637 -42.404481) (xy 56.930577 -42.519104)
			(xy 56.977213 -42.636887) (xy 57.016362 -42.757367) (xy 57.047868 -42.880066) (xy 57.071608 -43.004503)
			(xy 57.087488 -43.130184) (xy 57.095445 -43.256614) (xy 57.095898 -43.319954) (xy 57.095898 -50.31994)
			(xy 57.096425 -50.365408) (xy 57.104819 -50.455954) (xy 57.121531 -50.54534) (xy 57.146419 -50.632803)
			(xy 57.179272 -50.717597) (xy 57.219807 -50.798997) (xy 57.26768 -50.876311) (xy 57.322482 -50.948877)
			(xy 57.383746 -51.016078) (xy 57.450949 -51.07734) (xy 57.523517 -51.132139) (xy 57.600832 -51.18001)
			(xy 57.682234 -51.220542) (xy 57.767029 -51.253391) (xy 57.854493 -51.278277) (xy 57.943879 -51.294986)
			(xy 58.034426 -51.303377) (xy 58.079894 -51.303936)
		)
		(stroke
			(width 0)
			(type solid)
		)
		(fill yes)
		(layer "In3.Cu")
		(net "P12V")
	)
	(gr_line
		(start 0.1778 -46.8376)
		(end 10.541 -46.8376)
		(stroke
			(width 0.508)
			(type default)
		)
		(layer "In3.Cu")
	)
	(gr_line
		(start 0.7366 -49.1744)
		(end 9.271 -49.1744)
		(stroke
			(width 2.54)
			(type default)
		)
		(layer "In3.Cu")
	)
	(gr_line
		(start 0.762 -51.3334)
		(end 9.2964 -51.3334)
		(stroke
			(width 2.54)
			(type default)
		)
		(layer "In3.Cu")
	)
	(gr_line
		(start 0.762 -50.3174)
		(end 9.2964 -50.3174)
		(stroke
			(width 2.54)
			(type default)
		)
		(layer "In3.Cu")
	)
	(gr_line
		(start 0.762 -49.911)
		(end 9.2964 -49.911)
		(stroke
			(width 2.54)
			(type default)
		)
		(layer "In3.Cu")
	)
	(gr_line
		(start 0.7874 -50.8508)
		(end 9.3218 -50.8508)
		(stroke
			(width 2.54)
			(type default)
		)
		(layer "In3.Cu")
	)
	(gr_line
		(start 0.7874 -50.3682)
		(end 9.3218 -50.3682)
		(stroke
			(width 2.54)
			(type default)
		)
		(layer "In3.Cu")
	)
	(gr_line
		(start 0.7874 -49.5046)
		(end 9.3218 -49.5046)
		(stroke
			(width 2.54)
			(type default)
		)
		(layer "In3.Cu")
	)
	(gr_line
		(start 0.7874 -48.6156)
		(end 9.3218 -48.6156)
		(stroke
			(width 2.54)
			(type default)
		)
		(layer "In3.Cu")
	)
	(gr_line
		(start 0.7874 -48.0822)
		(end 9.3218 -48.0822)
		(stroke
			(width 2.54)
			(type default)
		)
		(layer "In3.Cu")
	)
	(gr_line
		(start 0.8128 -48.3108)
		(end 9.3472 -48.3108)
		(stroke
			(width 2.54)
			(type default)
		)
		(layer "In3.Cu")
	)
	(gr_line
		(start 0.8128 -48.26)
		(end 9.3472 -48.26)
		(stroke
			(width 2.54)
			(type default)
		)
		(layer "In3.Cu")
	)
	(gr_line
		(start 0.8128 -47.9044)
		(end 9.3472 -47.9044)
		(stroke
			(width 2.54)
			(type default)
		)
		(layer "In3.Cu")
	)
	(gr_line
		(start 0.8382 -48.8442)
		(end 9.3726 -48.8442)
		(stroke
			(width 2.54)
			(type default)
		)
		(layer "In3.Cu")
	)
	(gr_line
		(start 0.8382 -48.5394)
		(end 9.3726 -48.5394)
		(stroke
			(width 2.54)
			(type default)
		)
		(layer "In3.Cu")
	)
	(gr_line
		(start 0.8382 -48.4378)
		(end 9.3726 -48.4378)
		(stroke
			(width 2.54)
			(type default)
		)
		(layer "In3.Cu")
	)
	(gr_line
		(start 0.8382 -48.0822)
		(end 9.3726 -48.0822)
		(stroke
			(width 2.54)
			(type default)
		)
		(layer "In3.Cu")
	)
	(gr_line
		(start 0.8636 -49.0982)
		(end 9.398 -49.0982)
		(stroke
			(width 2.54)
			(type default)
		)
		(layer "In3.Cu")
	)
	(gr_line
		(start 0.8636 -48.9204)
		(end 9.398 -48.9204)
		(stroke
			(width 2.54)
			(type default)
		)
		(layer "In3.Cu")
	)
	(gr_line
		(start 0.8636 -48.7172)
		(end 9.398 -48.7172)
		(stroke
			(width 2.54)
			(type default)
		)
		(layer "In3.Cu")
	)
	(gr_line
		(start 0.8636 -48.641)
		(end 9.398 -48.641)
		(stroke
			(width 2.54)
			(type default)
		)
		(layer "In3.Cu")
	)
	(gr_line
		(start 0.889 -51.5366)
		(end 9.4234 -51.5366)
		(stroke
			(width 2.54)
			(type default)
		)
		(layer "In3.Cu")
	)
	(gr_line
		(start 0.9144 -49.8856)
		(end 9.4488 -49.8856)
		(stroke
			(width 2.54)
			(type default)
		)
		(layer "In3.Cu")
	)
	(gr_line
		(start 0.9144 -49.2506)
		(end 9.4488 -49.2506)
		(stroke
			(width 2.54)
			(type default)
		)
		(layer "In3.Cu")
	)
	(gr_line
		(start 0.9398 -51.2572)
		(end 9.4742 -51.2572)
		(stroke
			(width 2.54)
			(type default)
		)
		(layer "In3.Cu")
	)
	(gr_line
		(start 0.9398 -49.7332)
		(end 9.4742 -49.7332)
		(stroke
			(width 2.54)
			(type default)
		)
		(layer "In3.Cu")
	)
	(gr_line
		(start 0.9398 -49.5808)
		(end 9.4742 -49.5808)
		(stroke
			(width 2.54)
			(type default)
		)
		(layer "In3.Cu")
	)
	(gr_line
		(start 0.9398 -49.3522)
		(end 9.4742 -49.3522)
		(stroke
			(width 2.54)
			(type default)
		)
		(layer "In3.Cu")
	)
	(gr_line
		(start 0.9652 -51.3588)
		(end 9.4996 -51.3588)
		(stroke
			(width 2.54)
			(type default)
		)
		(layer "In3.Cu")
	)
	(gr_line
		(start 0.9652 -50.4698)
		(end 9.4996 -50.4698)
		(stroke
			(width 2.54)
			(type default)
		)
		(layer "In3.Cu")
	)
	(gr_line
		(start 0.9652 -50.3682)
		(end 9.4996 -50.3682)
		(stroke
			(width 2.54)
			(type default)
		)
		(layer "In3.Cu")
	)
	(gr_line
		(start 0.9652 -50.1142)
		(end 9.4996 -50.1142)
		(stroke
			(width 2.54)
			(type default)
		)
		(layer "In3.Cu")
	)
	(gr_line
		(start 0.9906 -51.435)
		(end 5.8674 -51.435)
		(stroke
			(width 2.54)
			(type default)
		)
		(layer "In3.Cu")
	)
	(gr_line
		(start 0.9906 -51.1048)
		(end 9.525 -51.1048)
		(stroke
			(width 2.54)
			(type default)
		)
		(layer "In3.Cu")
	)
	(gr_line
		(start 0.9906 -50.8)
		(end 9.525 -50.8)
		(stroke
			(width 2.54)
			(type default)
		)
		(layer "In3.Cu")
	)
	(gr_line
		(start 0.9906 -50.6476)
		(end 9.525 -50.6476)
		(stroke
			(width 2.54)
			(type default)
		)
		(layer "In3.Cu")
	)
	(gr_line
		(start 1.016 -50.9524)
		(end 9.5504 -50.9524)
		(stroke
			(width 2.54)
			(type default)
		)
		(layer "In3.Cu")
	)
	(gr_line
		(start 1.0414 -51.1556)
		(end 9.5758 -51.1556)
		(stroke
			(width 2.54)
			(type default)
		)
		(layer "In3.Cu")
	)
	(gr_line
		(start 1.0414 -50.9016)
		(end 9.5758 -50.9016)
		(stroke
			(width 2.54)
			(type default)
		)
		(layer "In3.Cu")
	)
	(gr_line
		(start 1.0414 -50.0888)
		(end 9.5758 -50.0888)
		(stroke
			(width 2.54)
			(type default)
		)
		(layer "In3.Cu")
	)
	(gr_line
		(start 1.0668 -50.6984)
		(end 9.6012 -50.6984)
		(stroke
			(width 2.54)
			(type default)
		)
		(layer "In3.Cu")
	)
	(gr_line
		(start 1.0668 -50.4952)
		(end 9.6012 -50.4952)
		(stroke
			(width 2.54)
			(type default)
		)
		(layer "In3.Cu")
	)
	(gr_line
		(start 1.0668 -50.2412)
		(end 9.6012 -50.2412)
		(stroke
			(width 2.54)
			(type default)
		)
		(layer "In3.Cu")
	)
	(gr_line
		(start 1.1938 -50.3682)
		(end 9.7282 -50.3682)
		(stroke
			(width 2.54)
			(type default)
		)
		(layer "In3.Cu")
	)
	(gr_line
		(start 1.2192 -50.3428)
		(end 9.7536 -50.3428)
		(stroke
			(width 2.54)
			(type default)
		)
		(layer "In3.Cu")
	)
	(gr_line
		(start 1.2192 -49.8602)
		(end 9.7536 -49.8602)
		(stroke
			(width 2.54)
			(type default)
		)
		(layer "In3.Cu")
	)
	(gr_line
		(start 1.2446 -48.7934)
		(end 9.779 -48.7934)
		(stroke
			(width 2.54)
			(type default)
		)
		(layer "In3.Cu")
	)
	(gr_line
		(start 1.4732 -52.1462)
		(end 6.35 -52.1462)
		(stroke
			(width 2.54)
			(type default)
		)
		(layer "In3.Cu")
	)
	(gr_line
		(start 1.49987 -53.299868)
		(end 0 -51.799998)
		(stroke
			(width 2.032)
			(type default)
		)
		(layer "In3.Cu")
	)
	(gr_line
		(start 1.8542 -52.5272)
		(end 6.731 -52.5272)
		(stroke
			(width 2.54)
			(type default)
		)
		(layer "In3.Cu")
	)
	(gr_arc
		(start 1.999996 0)
		(mid 0.585785 -0.585785)
		(end 0 -1.999996)
		(stroke
			(width 2.032)
			(type default)
		)
		(layer "In3.Cu")
	)
	(gr_line
		(start 1.999996 0)
		(end 426.809916 0)
		(stroke
			(width 2.032)
			(type default)
		)
		(layer "In3.Cu")
	)
	(gr_line
		(start 2.2098 -2.0574)
		(end 2.2098 -2.057654)
		(stroke
			(width 5.588)
			(type default)
		)
		(layer "In3.Cu")
	)
	(gr_line
		(start 2.5654 -52.2478)
		(end 7.4422 -52.2478)
		(stroke
			(width 2.54)
			(type default)
		)
		(layer "In3.Cu")
	)
	(gr_arc
		(start 2.750058 -32.563308)
		(mid 4.372855 -37.997202)
		(end 6.45033 -32.720534)
		(stroke
			(width 2.032)
			(type default)
		)
		(layer "In3.Cu")
	)
	(gr_line
		(start 2.750058 -29.207714)
		(end 2.750058 -32.563308)
		(stroke
			(width 2.032)
			(type default)
		)
		(layer "In3.Cu")
	)
	(gr_line
		(start 2.760726 -29.197046)
		(end 2.750058 -29.207714)
		(stroke
			(width 2.032)
			(type default)
		)
		(layer "In3.Cu")
	)
	(gr_line
		(start 3.6576 -52.5018)
		(end 8.5344 -52.5018)
		(stroke
			(width 2.54)
			(type default)
		)
		(layer "In3.Cu")
	)
	(gr_line
		(start 4.2418 -49.5554)
		(end 12.7762 -49.5554)
		(stroke
			(width 2.54)
			(type default)
		)
		(layer "In3.Cu")
	)
	(gr_line
		(start 4.2672 -49.7586)
		(end 12.8016 -49.7586)
		(stroke
			(width 2.54)
			(type default)
		)
		(layer "In3.Cu")
	)
	(gr_line
		(start 4.2926 -49.2506)
		(end 12.827 -49.2506)
		(stroke
			(width 2.54)
			(type default)
		)
		(layer "In3.Cu")
	)
	(gr_line
		(start 4.318 -48.8188)
		(end 12.8524 -48.8188)
		(stroke
			(width 2.54)
			(type default)
		)
		(layer "In3.Cu")
	)
	(gr_line
		(start 4.3434 -50.8254)
		(end 12.8778 -50.8254)
		(stroke
			(width 2.54)
			(type default)
		)
		(layer "In3.Cu")
	)
	(gr_line
		(start 4.3434 -48.895)
		(end 12.8778 -48.895)
		(stroke
			(width 2.54)
			(type default)
		)
		(layer "In3.Cu")
	)
	(gr_line
		(start 4.3688 -50.6222)
		(end 12.9032 -50.6222)
		(stroke
			(width 2.54)
			(type default)
		)
		(layer "In3.Cu")
	)
	(gr_line
		(start 4.3688 -50.4444)
		(end 12.9032 -50.4444)
		(stroke
			(width 2.54)
			(type default)
		)
		(layer "In3.Cu")
	)
	(gr_line
		(start 4.3688 -50.1142)
		(end 12.9032 -50.1142)
		(stroke
			(width 2.54)
			(type default)
		)
		(layer "In3.Cu")
	)
	(gr_line
		(start 4.3942 -51.8668)
		(end 9.271 -51.8668)
		(stroke
			(width 2.54)
			(type default)
		)
		(layer "In3.Cu")
	)
	(gr_line
		(start 4.3942 -49.9364)
		(end 12.9286 -49.9364)
		(stroke
			(width 2.54)
			(type default)
		)
		(layer "In3.Cu")
	)
	(gr_line
		(start 4.3942 -48.4632)
		(end 12.9286 -48.4632)
		(stroke
			(width 2.54)
			(type default)
		)
		(layer "In3.Cu")
	)
	(gr_line
		(start 4.4196 -48.2092)
		(end 12.954 -48.2092)
		(stroke
			(width 2.54)
			(type default)
		)
		(layer "In3.Cu")
	)
	(gr_line
		(start 4.445 -48.5394)
		(end 12.9794 -48.5394)
		(stroke
			(width 2.54)
			(type default)
		)
		(layer "In3.Cu")
	)
	(gr_line
		(start 4.445 -48.4378)
		(end 12.9794 -48.4378)
		(stroke
			(width 2.54)
			(type default)
		)
		(layer "In3.Cu")
	)
	(gr_line
		(start 4.445 -48.0314)
		(end 12.9794 -48.0314)
		(stroke
			(width 2.54)
			(type default)
		)
		(layer "In3.Cu")
	)
	(gr_line
		(start 4.445 -47.9044)
		(end 12.9794 -47.9044)
		(stroke
			(width 2.54)
			(type default)
		)
		(layer "In3.Cu")
	)
	(gr_line
		(start 4.4704 -48.8442)
		(end 13.0048 -48.8442)
		(stroke
			(width 2.54)
			(type default)
		)
		(layer "In3.Cu")
	)
	(gr_line
		(start 4.49961 -34.99993)
		(end 4.499864 -35.000184)
		(stroke
			(width 4.064)
			(type default)
		)
		(layer "In3.Cu")
	)
	(gr_line
		(start 4.49961 -28.999688)
		(end 4.49961 -34.99993)
		(stroke
			(width 4.064)
			(type default)
		)
		(layer "In3.Cu")
	)
	(gr_line
		(start 4.499864 -35.000184)
		(end 4.499864 -34.99993)
		(stroke
			(width 6.604)
			(type default)
		)
		(layer "In3.Cu")
	)
	(gr_line
		(start 4.500118 -4.700016)
		(end 4.500118 -4.699762)
		(stroke
			(width 8.128)
			(type default)
		)
		(layer "In3.Cu")
	)
	(gr_circle
		(center 4.500118 -4.700016)
		(end 8.559038 -4.700016)
		(stroke
			(width 0.254)
			(type default)
		)
		(fill no)
		(layer "In3.Cu")
	)
	(gr_line
		(start 4.6736 -49.0728)
		(end 13.208 -49.0728)
		(stroke
			(width 2.54)
			(type default)
		)
		(layer "In3.Cu")
	)
	(gr_line
		(start 4.826 -49.4284)
		(end 13.3604 -49.4284)
		(stroke
			(width 2.54)
			(type default)
		)
		(layer "In3.Cu")
	)
	(gr_line
		(start 4.8514 -49.5808)
		(end 13.3858 -49.5808)
		(stroke
			(width 2.54)
			(type default)
		)
		(layer "In3.Cu")
	)
	(gr_line
		(start 4.8514 -48.7934)
		(end 13.3858 -48.7934)
		(stroke
			(width 2.54)
			(type default)
		)
		(layer "In3.Cu")
	)
	(gr_line
		(start 4.9022 -49.8856)
		(end 13.4366 -49.8856)
		(stroke
			(width 2.54)
			(type default)
		)
		(layer "In3.Cu")
	)
	(gr_line
		(start 4.9276 -50.2666)
		(end 13.462 -50.2666)
		(stroke
			(width 2.54)
			(type default)
		)
		(layer "In3.Cu")
	)
	(gr_line
		(start 4.953 -50.419)
		(end 13.4874 -50.419)
		(stroke
			(width 2.54)
			(type default)
		)
		(layer "In3.Cu")
	)
	(gr_line
		(start 4.953 -50.0634)
		(end 13.4874 -50.0634)
		(stroke
			(width 2.54)
			(type default)
		)
		(layer "In3.Cu")
	)
	(gr_line
		(start 5.0038 -50.7238)
		(end 13.5382 -50.7238)
		(stroke
			(width 2.54)
			(type default)
		)
		(layer "In3.Cu")
	)
	(gr_line
		(start 5.0546 -51.181)
		(end 9.9314 -51.181)
		(stroke
			(width 2.54)
			(type default)
		)
		(layer "In3.Cu")
	)
	(gr_line
		(start 6.249924 -32.520128)
		(end 6.249924 -28.999942)
		(stroke
			(width 2.032)
			(type default)
		)
		(layer "In3.Cu")
	)
	(gr_arc
		(start 6.249924 -28.999942)
		(mid 4.401168 -27.252413)
		(end 2.760726 -29.197046)
		(stroke
			(width 2.032)
			(type default)
		)
		(layer "In3.Cu")
	)
	(gr_line
		(start 6.45033 -32.720534)
		(end 6.249924 -32.520128)
		(stroke
			(width 2.032)
			(type default)
		)
		(layer "In3.Cu")
	)
	(gr_line
		(start 8.950198 -53.299868)
		(end 1.49987 -53.299868)
		(stroke
			(width 2.032)
			(type default)
		)
		(layer "In3.Cu")
	)
	(gr_line
		(start 10.450068 -51.799998)
		(end 8.950198 -53.299868)
		(stroke
			(width 2.032)
			(type default)
		)
		(layer "In3.Cu")
	)
	(gr_line
		(start 10.450068 -42.650664)
		(end 10.450068 -51.799998)
		(stroke
			(width 2.032)
			(type default)
		)
		(layer "In3.Cu")
	)
	(gr_arc
		(start 10.450068 -42.650664)
		(mid 11.047577 -42.898154)
		(end 10.80008 -42.300652)
		(stroke
			(width 2.032)
			(type default)
		)
		(layer "In3.Cu")
	)
	(gr_line
		(start 10.541 -46.8376)
		(end 10.9982 -46.3804)
		(stroke
			(width 0.508)
			(type default)
		)
		(layer "In3.Cu")
	)
	(gr_line
		(start 10.7188 -45.6692)
		(end 10.7696 -45.6184)
		(stroke
			(width 0.762)
			(type default)
		)
		(layer "In3.Cu")
	)
	(gr_line
		(start 10.7696 -45.72)
		(end 10.7188 -45.6692)
		(stroke
			(width 0.762)
			(type default)
		)
		(layer "In3.Cu")
	)
	(gr_line
		(start 10.7696 -45.6184)
		(end 51.9176 -45.6184)
		(stroke
			(width 0.762)
			(type default)
		)
		(layer "In3.Cu")
	)
	(gr_line
		(start 10.9982 -46.3804)
		(end 11.4554 -45.9232)
		(stroke
			(width 1.27)
			(type default)
		)
		(layer "In3.Cu")
	)
	(gr_line
		(start 11.150092 -51.799998)
		(end 12.649962 -53.299868)
		(stroke
			(width 2.032)
			(type default)
		)
		(layer "In3.Cu")
	)
	(gr_arc
		(start 11.150092 -42.650664)
		(mid 11.047562 -42.403198)
		(end 10.80008 -42.300652)
		(stroke
			(width 2.032)
			(type default)
		)
		(layer "In3.Cu")
	)
	(gr_line
		(start 11.150092 -42.650664)
		(end 11.150092 -51.799998)
		(stroke
			(width 2.032)
			(type default)
		)
		(layer "In3.Cu")
	)
	(gr_line
		(start 11.1506 -45.7962)
		(end 11.3284 -45.6184)
		(stroke
			(width 0.762)
			(type default)
		)
		(layer "In3.Cu")
	)
	(gr_line
		(start 11.303 -45.9486)
		(end 11.1506 -45.7962)
		(stroke
			(width 1.27)
			(type default)
		)
		(layer "In3.Cu")
	)
	(gr_line
		(start 11.3284 -45.6184)
		(end 51.9176 -45.6184)
		(stroke
			(width 0.762)
			(type default)
		)
		(layer "In3.Cu")
	)
	(gr_line
		(start 11.4554 -45.9232)
		(end 51.943 -45.9232)
		(stroke
			(width 1.27)
			(type default)
		)
		(layer "In3.Cu")
	)
	(gr_line
		(start 11.5062 -50.7238)
		(end 11.5062 -46.5836)
		(stroke
			(width 2.54)
			(type default)
		)
		(layer "In3.Cu")
	)
	(gr_line
		(start 11.5062 -50.6222)
		(end 11.5062 -46.482)
		(stroke
			(width 2.54)
			(type default)
		)
		(layer "In3.Cu")
	)
	(gr_line
		(start 12.192 -51.6382)
		(end 12.192 -47.498)
		(stroke
			(width 2.54)
			(type default)
		)
		(layer "In3.Cu")
	)
	(gr_line
		(start 12.3444 -51.5874)
		(end 12.3444 -47.4472)
		(stroke
			(width 2.54)
			(type default)
		)
		(layer "In3.Cu")
	)
	(gr_line
		(start 12.649962 -53.299868)
		(end 50.580036 -53.299868)
		(stroke
			(width 2.032)
			(type default)
		)
		(layer "In3.Cu")
	)
	(gr_line
		(start 13.0302 -52.578)
		(end 13.0302 -48.4378)
		(stroke
			(width 2.54)
			(type default)
		)
		(layer "In3.Cu")
	)
	(gr_line
		(start 13.6906 -49.3268)
		(end 42.545 -49.3268)
		(stroke
			(width 7.62)
			(type default)
		)
		(layer "In3.Cu")
	)
	(gr_line
		(start 13.716 -52.197)
		(end 13.716 -48.0568)
		(stroke
			(width 2.54)
			(type default)
		)
		(layer "In3.Cu")
	)
	(gr_line
		(start 13.843 -49.276)
		(end 42.6974 -49.276)
		(stroke
			(width 7.62)
			(type default)
		)
		(layer "In3.Cu")
	)
	(gr_line
		(start 14.1986 -49.9872)
		(end 43.053 -49.9872)
		(stroke
			(width 7.62)
			(type default)
		)
		(layer "In3.Cu")
	)
	(gr_line
		(start 14.6304 -52.4002)
		(end 14.6304 -48.26)
		(stroke
			(width 2.54)
			(type default)
		)
		(layer "In3.Cu")
	)
	(gr_line
		(start 15.5448 -49.276)
		(end 44.3992 -49.276)
		(stroke
			(width 7.62)
			(type default)
		)
		(layer "In3.Cu")
	)
	(gr_line
		(start 15.9258 -52.5272)
		(end 15.9258 -48.387)
		(stroke
			(width 2.54)
			(type default)
		)
		(layer "In3.Cu")
	)
	(gr_line
		(start 18.4912 -49.5808)
		(end 47.3456 -49.5808)
		(stroke
			(width 7.62)
			(type default)
		)
		(layer "In3.Cu")
	)
	(gr_line
		(start 18.6436 -49.4792)
		(end 47.498 -49.4792)
		(stroke
			(width 7.62)
			(type default)
		)
		(layer "In3.Cu")
	)
	(gr_line
		(start 18.9738 -49.3776)
		(end 47.8282 -49.3776)
		(stroke
			(width 7.62)
			(type default)
		)
		(layer "In3.Cu")
	)
	(gr_line
		(start 19.3294 -49.9872)
		(end 48.1838 -49.9872)
		(stroke
			(width 7.62)
			(type default)
		)
		(layer "In3.Cu")
	)
	(gr_line
		(start 19.7866 -49.8348)
		(end 48.641 -49.8348)
		(stroke
			(width 7.62)
			(type default)
		)
		(layer "In3.Cu")
	)
	(gr_line
		(start 19.7866 -49.276)
		(end 48.641 -49.276)
		(stroke
			(width 7.62)
			(type default)
		)
		(layer "In3.Cu")
	)
	(gr_line
		(start 19.8882 -49.022)
		(end 48.7426 -49.022)
		(stroke
			(width 7.62)
			(type default)
		)
		(layer "In3.Cu")
	)
	(gr_line
		(start 49.9872 -52.5272)
		(end 49.9872 -48.387)
		(stroke
			(width 2.54)
			(type default)
		)
		(layer "In3.Cu")
	)
	(gr_line
		(start 50.038 -51.1556)
		(end 50.038 -47.0154)
		(stroke
			(width 2.54)
			(type default)
		)
		(layer "In3.Cu")
	)
	(gr_line
		(start 50.3174 -52.451)
		(end 50.3174 -48.3108)
		(stroke
			(width 2.54)
			(type default)
		)
		(layer "In3.Cu")
	)
	(gr_line
		(start 50.546 -52.2224)
		(end 50.546 -48.0822)
		(stroke
			(width 2.54)
			(type default)
		)
		(layer "In3.Cu")
	)
	(gr_line
		(start 50.580036 -53.299868)
		(end 52.079906 -51.799998)
		(stroke
			(width 2.032)
			(type default)
		)
		(layer "In3.Cu")
	)
	(gr_line
		(start 50.8254 -51.8922)
		(end 50.8254 -47.752)
		(stroke
			(width 2.54)
			(type default)
		)
		(layer "In3.Cu")
	)
	(gr_line
		(start 50.927 -50.7746)
		(end 50.927 -46.6344)
		(stroke
			(width 2.54)
			(type default)
		)
		(layer "In3.Cu")
	)
	(gr_line
		(start 51.0286 -50.6984)
		(end 51.0286 -46.5582)
		(stroke
			(width 2.54)
			(type default)
		)
		(layer "In3.Cu")
	)
	(gr_line
		(start 51.2318 -51.4858)
		(end 51.2318 -47.3456)
		(stroke
			(width 2.54)
			(type default)
		)
		(layer "In3.Cu")
	)
	(gr_line
		(start 51.2826 -50.7238)
		(end 51.2826 -46.5836)
		(stroke
			(width 2.54)
			(type default)
		)
		(layer "In3.Cu")
	)
	(gr_line
		(start 51.816 -45.72)
		(end 10.7696 -45.72)
		(stroke
			(width 0.762)
			(type default)
		)
		(layer "In3.Cu")
	)
	(gr_line
		(start 51.9176 -45.9486)
		(end 11.303 -45.9486)
		(stroke
			(width 1.27)
			(type default)
		)
		(layer "In3.Cu")
	)
	(gr_line
		(start 51.9176 -45.6184)
		(end 51.816 -45.72)
		(stroke
			(width 0.762)
			(type default)
		)
		(layer "In3.Cu")
	)
	(gr_line
		(start 51.943 -45.9232)
		(end 51.9176 -45.9486)
		(stroke
			(width 1.27)
			(type default)
		)
		(layer "In3.Cu")
	)
	(gr_line
		(start 52.079906 -51.799998)
		(end 52.079906 -43.319954)
		(stroke
			(width 2.032)
			(type default)
		)
		(layer "In3.Cu")
	)
	(gr_arc
		(start 53.079904 -42.319956)
		(mid 52.37278 -42.612844)
		(end 52.079906 -43.319954)
		(stroke
			(width 2.032)
			(type default)
		)
		(layer "In3.Cu")
	)
	(gr_line
		(start 53.079904 -42.319956)
		(end 55.0799 -42.319956)
		(stroke
			(width 2.032)
			(type default)
		)
		(layer "In3.Cu")
	)
	(gr_arc
		(start 56.079898 -50.31994)
		(mid 56.665683 -51.734151)
		(end 58.079894 -52.319936)
		(stroke
			(width 2.032)
			(type default)
		)
		(layer "In3.Cu")
	)
	(gr_arc
		(start 56.079898 -43.319954)
		(mid 55.786989 -42.612878)
		(end 55.0799 -42.319956)
		(stroke
			(width 2.032)
			(type default)
		)
		(layer "In3.Cu")
	)
	(gr_line
		(start 56.079898 -43.319954)
		(end 56.079898 -50.31994)
		(stroke
			(width 2.032)
			(type default)
		)
		(layer "In3.Cu")
	)
	(gr_line
		(start 58.079894 -52.319936)
		(end 94.681802 -52.319936)
		(stroke
			(width 2.032)
			(type default)
		)
		(layer "In3.Cu")
	)
	(gr_arc
		(start 78.060042 -45.063664)
		(mid 79.682839 -50.497558)
		(end 81.760314 -45.22089)
		(stroke
			(width 2.032)
			(type default)
		)
		(layer "In3.Cu")
	)
	(gr_line
		(start 78.060042 -41.70807)
		(end 78.060042 -45.063664)
		(stroke
			(width 2.032)
			(type default)
		)
		(layer "In3.Cu")
	)
	(gr_line
		(start 78.07071 -41.697402)
		(end 78.060042 -41.70807)
		(stroke
			(width 2.032)
			(type default)
		)
		(layer "In3.Cu")
	)
	(gr_line
		(start 79.809594 -47.500286)
		(end 79.809848 -47.50054)
		(stroke
			(width 4.064)
			(type default)
		)
		(layer "In3.Cu")
	)
	(gr_line
		(start 79.809594 -41.500044)
		(end 79.809594 -47.500286)
		(stroke
			(width 4.064)
			(type default)
		)
		(layer "In3.Cu")
	)
	(gr_line
		(start 79.809848 -47.50054)
		(end 79.809848 -47.500286)
		(stroke
			(width 6.604)
			(type default)
		)
		(layer "In3.Cu")
	)
	(gr_line
		(start 81.559908 -45.020484)
		(end 81.559908 -41.500298)
		(stroke
			(width 2.032)
			(type default)
		)
		(layer "In3.Cu")
	)
	(gr_arc
		(start 81.559908 -41.500298)
		(mid 79.711152 -39.752769)
		(end 78.07071 -41.697402)
		(stroke
			(width 2.032)
			(type default)
		)
		(layer "In3.Cu")
	)
	(gr_line
		(start 81.760314 -45.22089)
		(end 81.559908 -45.020484)
		(stroke
			(width 2.032)
			(type default)
		)
		(layer "In3.Cu")
	)
	(gr_arc
		(start 94.681802 -52.319936)
		(mid 95.388907 -52.027043)
		(end 95.6818 -51.319938)
		(stroke
			(width 2.032)
			(type default)
		)
		(layer "In3.Cu")
	)
	(gr_line
		(start 95.6818 -51.319938)
		(end 95.6818 -50.8)
		(stroke
			(width 2.032)
			(type default)
		)
		(layer "In3.Cu")
	)
	(gr_arc
		(start 96.681798 -49.800002)
		(mid 95.974694 -50.092895)
		(end 95.6818 -50.8)
		(stroke
			(width 2.032)
			(type default)
		)
		(layer "In3.Cu")
	)
	(gr_line
		(start 96.681798 -49.800002)
		(end 112.06988 -49.800002)
		(stroke
			(width 2.032)
			(type default)
		)
		(layer "In3.Cu")
	)
	(gr_line
		(start 101.576632 -11.378946)
		(end 101.576632 -9.194546)
		(stroke
			(width 0.254)
			(type default)
		)
		(layer "In3.Cu")
	)
	(gr_line
		(start 101.576632 -9.194546)
		(end 103.151432 -9.194546)
		(stroke
			(width 0.254)
			(type default)
		)
		(layer "In3.Cu")
	)
	(gr_line
		(start 101.602032 -11.378946)
		(end 101.602032 -9.245346)
		(stroke
			(width 0.254)
			(type default)
		)
		(layer "In3.Cu")
	)
	(gr_line
		(start 101.602032 -9.245346)
		(end 103.126032 -9.245346)
		(stroke
			(width 0.254)
			(type default)
		)
		(layer "In3.Cu")
	)
	(gr_line
		(start 101.652832 -11.353546)
		(end 101.652832 -9.372346)
		(stroke
			(width 0.254)
			(type default)
		)
		(layer "In3.Cu")
	)
	(gr_line
		(start 101.652832 -9.372346)
		(end 103.100632 -9.372346)
		(stroke
			(width 0.254)
			(type default)
		)
		(layer "In3.Cu")
	)
	(gr_line
		(start 101.706934 -11.302746)
		(end 102.011734 -11.302746)
		(stroke
			(width 0.1016)
			(type default)
		)
		(layer "In3.Cu")
	)
	(gr_line
		(start 101.706934 -9.296146)
		(end 101.706934 -11.302746)
		(stroke
			(width 0.1016)
			(type default)
		)
		(layer "In3.Cu")
	)
	(gr_line
		(start 101.734874 -5.57784)
		(end 103.004874 -5.57784)
		(stroke
			(width 1.016)
			(type default)
		)
		(layer "In3.Cu")
	)
	(gr_line
		(start 101.757734 -11.226546)
		(end 102.849934 -11.226546)
		(stroke
			(width 0.2032)
			(type default)
		)
		(layer "In3.Cu")
	)
	(gr_line
		(start 101.757734 -9.372346)
		(end 101.757734 -11.226546)
		(stroke
			(width 0.2032)
			(type default)
		)
		(layer "In3.Cu")
	)
	(gr_line
		(start 101.783134 -11.226546)
		(end 102.951534 -11.226546)
		(stroke
			(width 0.2032)
			(type default)
		)
		(layer "In3.Cu")
	)
	(gr_line
		(start 101.783134 -9.423146)
		(end 101.783134 -11.226546)
		(stroke
			(width 0.2032)
			(type default)
		)
		(layer "In3.Cu")
	)
	(gr_line
		(start 101.830632 -11.124946)
		(end 101.830632 -9.575546)
		(stroke
			(width 0.762)
			(type default)
		)
		(layer "In3.Cu")
	)
	(gr_line
		(start 101.830632 -11.124946)
		(end 102.745032 -11.124946)
		(stroke
			(width 0.762)
			(type default)
		)
		(layer "In3.Cu")
	)
	(gr_line
		(start 101.830632 -11.099546)
		(end 101.830632 -9.550146)
		(stroke
			(width 0.762)
			(type default)
		)
		(layer "In3.Cu")
	)
	(gr_line
		(start 101.830632 -10.997946)
		(end 101.830632 -9.448546)
		(stroke
			(width 0.762)
			(type default)
		)
		(layer "In3.Cu")
	)
	(gr_line
		(start 101.830632 -9.448546)
		(end 102.745032 -9.448546)
		(stroke
			(width 0.762)
			(type default)
		)
		(layer "In3.Cu")
	)
	(gr_line
		(start 101.833934 -11.175746)
		(end 102.926134 -11.175746)
		(stroke
			(width 0.2032)
			(type default)
		)
		(layer "In3.Cu")
	)
	(gr_line
		(start 101.833934 -9.473946)
		(end 101.833934 -11.175746)
		(stroke
			(width 0.2032)
			(type default)
		)
		(layer "In3.Cu")
	)
	(gr_line
		(start 101.856032 -10.997946)
		(end 102.770432 -10.997946)
		(stroke
			(width 0.762)
			(type default)
		)
		(layer "In3.Cu")
	)
	(gr_line
		(start 101.856032 -9.575546)
		(end 102.770432 -9.575546)
		(stroke
			(width 0.762)
			(type default)
		)
		(layer "In3.Cu")
	)
	(gr_line
		(start 101.935534 -11.074146)
		(end 102.722934 -11.074146)
		(stroke
			(width 0.508)
			(type default)
		)
		(layer "In3.Cu")
	)
	(gr_line
		(start 101.935534 -11.048746)
		(end 101.935534 -9.524746)
		(stroke
			(width 0.508)
			(type default)
		)
		(layer "In3.Cu")
	)
	(gr_line
		(start 101.960934 -11.074146)
		(end 101.960934 -9.550146)
		(stroke
			(width 0.508)
			(type default)
		)
		(layer "In3.Cu")
	)
	(gr_line
		(start 101.983032 -11.124946)
		(end 102.897432 -11.124946)
		(stroke
			(width 0.762)
			(type default)
		)
		(layer "In3.Cu")
	)
	(gr_line
		(start 101.983032 -9.448546)
		(end 102.897432 -9.448546)
		(stroke
			(width 0.762)
			(type default)
		)
		(layer "In3.Cu")
	)
	(gr_line
		(start 101.986334 -9.524746)
		(end 102.722934 -9.524746)
		(stroke
			(width 0.508)
			(type default)
		)
		(layer "In3.Cu")
	)
	(gr_line
		(start 102.011734 -11.302746)
		(end 103.002334 -11.302746)
		(stroke
			(width 0.1016)
			(type default)
		)
		(layer "In3.Cu")
	)
	(gr_line
		(start 102.011734 -11.074146)
		(end 102.011734 -9.550146)
		(stroke
			(width 0.508)
			(type default)
		)
		(layer "In3.Cu")
	)
	(gr_line
		(start 102.037134 -11.074146)
		(end 102.037134 -9.550146)
		(stroke
			(width 0.508)
			(type default)
		)
		(layer "In3.Cu")
	)
	(gr_line
		(start 102.062534 -11.074146)
		(end 102.062534 -9.550146)
		(stroke
			(width 0.508)
			(type default)
		)
		(layer "In3.Cu")
	)
	(gr_line
		(start 102.087934 -11.074146)
		(end 102.087934 -9.550146)
		(stroke
			(width 0.508)
			(type default)
		)
		(layer "In3.Cu")
	)
	(gr_line
		(start 102.087934 -11.048746)
		(end 102.087934 -9.524746)
		(stroke
			(width 0.508)
			(type default)
		)
		(layer "In3.Cu")
	)
	(gr_line
		(start 102.113334 -11.074146)
		(end 102.113334 -9.550146)
		(stroke
			(width 0.508)
			(type default)
		)
		(layer "In3.Cu")
	)
	(gr_line
		(start 102.138734 -11.074146)
		(end 102.138734 -9.550146)
		(stroke
			(width 0.508)
			(type default)
		)
		(layer "In3.Cu")
	)
	(gr_line
		(start 102.189534 -11.074146)
		(end 102.189534 -9.550146)
		(stroke
			(width 0.508)
			(type default)
		)
		(layer "In3.Cu")
	)
	(gr_line
		(start 102.189534 -11.048746)
		(end 102.189534 -9.524746)
		(stroke
			(width 0.508)
			(type default)
		)
		(layer "In3.Cu")
	)
	(gr_line
		(start 102.214934 -11.074146)
		(end 102.214934 -9.550146)
		(stroke
			(width 0.508)
			(type default)
		)
		(layer "In3.Cu")
	)
	(gr_line
		(start 102.240334 -11.074146)
		(end 102.240334 -9.550146)
		(stroke
			(width 0.508)
			(type default)
		)
		(layer "In3.Cu")
	)
	(gr_line
		(start 102.265734 -11.074146)
		(end 102.265734 -9.550146)
		(stroke
			(width 0.508)
			(type default)
		)
		(layer "In3.Cu")
	)
	(gr_line
		(start 102.316534 -11.074146)
		(end 102.316534 -9.550146)
		(stroke
			(width 0.508)
			(type default)
		)
		(layer "In3.Cu")
	)
	(gr_line
		(start 102.341934 -11.074146)
		(end 102.341934 -9.550146)
		(stroke
			(width 0.508)
			(type default)
		)
		(layer "In3.Cu")
	)
	(gr_line
		(start 102.341934 -11.048746)
		(end 102.341934 -9.524746)
		(stroke
			(width 0.508)
			(type default)
		)
		(layer "In3.Cu")
	)
	(gr_line
		(start 102.367334 -11.074146)
		(end 102.367334 -9.550146)
		(stroke
			(width 0.508)
			(type default)
		)
		(layer "In3.Cu")
	)
	(gr_line
		(start 102.392734 -11.074146)
		(end 102.392734 -9.550146)
		(stroke
			(width 0.508)
			(type default)
		)
		(layer "In3.Cu")
	)
	(gr_line
		(start 102.418134 -11.074146)
		(end 102.418134 -9.550146)
		(stroke
			(width 0.508)
			(type default)
		)
		(layer "In3.Cu")
	)
	(gr_line
		(start 102.418134 -11.048746)
		(end 102.418134 -9.524746)
		(stroke
			(width 0.508)
			(type default)
		)
		(layer "In3.Cu")
	)
	(gr_line
		(start 102.443534 -11.074146)
		(end 102.443534 -9.550146)
		(stroke
			(width 0.508)
			(type default)
		)
		(layer "In3.Cu")
	)
	(gr_line
		(start 102.468934 -11.074146)
		(end 102.468934 -9.550146)
		(stroke
			(width 0.508)
			(type default)
		)
		(layer "In3.Cu")
	)
	(gr_line
		(start 102.468934 -11.048746)
		(end 102.468934 -9.524746)
		(stroke
			(width 0.508)
			(type default)
		)
		(layer "In3.Cu")
	)
	(gr_line
		(start 102.494334 -11.074146)
		(end 102.494334 -9.550146)
		(stroke
			(width 0.508)
			(type default)
		)
		(layer "In3.Cu")
	)
	(gr_line
		(start 102.494334 -11.048746)
		(end 102.494334 -9.524746)
		(stroke
			(width 0.508)
			(type default)
		)
		(layer "In3.Cu")
	)
	(gr_line
		(start 102.519734 -11.048746)
		(end 102.519734 -9.524746)
		(stroke
			(width 0.508)
			(type default)
		)
		(layer "In3.Cu")
	)
	(gr_line
		(start 102.545134 -11.074146)
		(end 102.545134 -9.550146)
		(stroke
			(width 0.508)
			(type default)
		)
		(layer "In3.Cu")
	)
	(gr_line
		(start 102.567232 -11.378946)
		(end 101.576632 -11.378946)
		(stroke
			(width 0.254)
			(type default)
		)
		(layer "In3.Cu")
	)
	(gr_line
		(start 102.570534 -11.048746)
		(end 102.570534 -9.524746)
		(stroke
			(width 0.508)
			(type default)
		)
		(layer "In3.Cu")
	)
	(gr_line
		(start 102.595934 -11.048746)
		(end 102.595934 -9.524746)
		(stroke
			(width 0.508)
			(type default)
		)
		(layer "In3.Cu")
	)
	(gr_line
		(start 102.621334 -11.074146)
		(end 102.621334 -9.550146)
		(stroke
			(width 0.508)
			(type default)
		)
		(layer "In3.Cu")
	)
	(gr_line
		(start 102.646734 -11.074146)
		(end 102.646734 -9.550146)
		(stroke
			(width 0.508)
			(type default)
		)
		(layer "In3.Cu")
	)
	(gr_line
		(start 102.646734 -11.048746)
		(end 102.646734 -9.524746)
		(stroke
			(width 0.508)
			(type default)
		)
		(layer "In3.Cu")
	)
	(gr_line
		(start 102.697534 -11.074146)
		(end 102.697534 -9.550146)
		(stroke
			(width 0.508)
			(type default)
		)
		(layer "In3.Cu")
	)
	(gr_line
		(start 102.697534 -11.048746)
		(end 102.697534 -9.524746)
		(stroke
			(width 0.508)
			(type default)
		)
		(layer "In3.Cu")
	)
	(gr_line
		(start 102.748334 -11.074146)
		(end 102.748334 -9.550146)
		(stroke
			(width 0.508)
			(type default)
		)
		(layer "In3.Cu")
	)
	(gr_line
		(start 102.748334 -11.048746)
		(end 102.748334 -9.524746)
		(stroke
			(width 0.508)
			(type default)
		)
		(layer "In3.Cu")
	)
	(gr_line
		(start 102.770432 -11.099546)
		(end 102.770432 -9.550146)
		(stroke
			(width 0.762)
			(type default)
		)
		(layer "In3.Cu")
	)
	(gr_line
		(start 102.773734 -11.074146)
		(end 102.773734 -9.550146)
		(stroke
			(width 0.508)
			(type default)
		)
		(layer "In3.Cu")
	)
	(gr_line
		(start 102.799134 -11.074146)
		(end 102.799134 -9.550146)
		(stroke
			(width 0.508)
			(type default)
		)
		(layer "In3.Cu")
	)
	(gr_line
		(start 102.849934 -11.226546)
		(end 102.875334 -11.226546)
		(stroke
			(width 0.2032)
			(type default)
		)
		(layer "In3.Cu")
	)
	(gr_line
		(start 102.875334 -11.226546)
		(end 102.875334 -9.473946)
		(stroke
			(width 0.2032)
			(type default)
		)
		(layer "In3.Cu")
	)
	(gr_line
		(start 102.875334 -9.473946)
		(end 101.833934 -9.473946)
		(stroke
			(width 0.2032)
			(type default)
		)
		(layer "In3.Cu")
	)
	(gr_line
		(start 102.897432 -11.124946)
		(end 102.897432 -9.575546)
		(stroke
			(width 0.762)
			(type default)
		)
		(layer "In3.Cu")
	)
	(gr_line
		(start 102.897432 -11.099546)
		(end 102.897432 -9.600946)
		(stroke
			(width 0.762)
			(type default)
		)
		(layer "In3.Cu")
	)
	(gr_line
		(start 102.897432 -10.997946)
		(end 102.897432 -9.448546)
		(stroke
			(width 0.762)
			(type default)
		)
		(layer "In3.Cu")
	)
	(gr_line
		(start 102.926134 -11.175746)
		(end 102.926134 -9.423146)
		(stroke
			(width 0.2032)
			(type default)
		)
		(layer "In3.Cu")
	)
	(gr_line
		(start 102.926134 -9.423146)
		(end 101.783134 -9.423146)
		(stroke
			(width 0.2032)
			(type default)
		)
		(layer "In3.Cu")
	)
	(gr_line
		(start 102.951534 -11.226546)
		(end 102.951534 -9.372346)
		(stroke
			(width 0.2032)
			(type default)
		)
		(layer "In3.Cu")
	)
	(gr_line
		(start 102.951534 -9.372346)
		(end 101.757734 -9.372346)
		(stroke
			(width 0.2032)
			(type default)
		)
		(layer "In3.Cu")
	)
	(gr_line
		(start 103.002334 -11.302746)
		(end 103.002334 -9.296146)
		(stroke
			(width 0.1016)
			(type default)
		)
		(layer "In3.Cu")
	)
	(gr_line
		(start 103.002334 -9.296146)
		(end 101.706934 -9.296146)
		(stroke
			(width 0.1016)
			(type default)
		)
		(layer "In3.Cu")
	)
	(gr_line
		(start 103.100632 -11.226546)
		(end 102.849934 -11.226546)
		(stroke
			(width 0.254)
			(type default)
		)
		(layer "In3.Cu")
	)
	(gr_line
		(start 103.100632 -9.372346)
		(end 103.100632 -11.226546)
		(stroke
			(width 0.254)
			(type default)
		)
		(layer "In3.Cu")
	)
	(gr_line
		(start 103.126032 -11.353546)
		(end 101.652832 -11.353546)
		(stroke
			(width 0.254)
			(type default)
		)
		(layer "In3.Cu")
	)
	(gr_line
		(start 103.126032 -9.245346)
		(end 103.126032 -11.353546)
		(stroke
			(width 0.254)
			(type default)
		)
		(layer "In3.Cu")
	)
	(gr_line
		(start 103.151432 -11.378946)
		(end 101.602032 -11.378946)
		(stroke
			(width 0.254)
			(type default)
		)
		(layer "In3.Cu")
	)
	(gr_line
		(start 103.151432 -9.194546)
		(end 103.151432 -11.378946)
		(stroke
			(width 0.254)
			(type default)
		)
		(layer "In3.Cu")
	)
	(gr_line
		(start 106.376724 -11.378946)
		(end 106.376724 -9.194546)
		(stroke
			(width 0.254)
			(type default)
		)
		(layer "In3.Cu")
	)
	(gr_line
		(start 106.376724 -9.194546)
		(end 107.951524 -9.194546)
		(stroke
			(width 0.254)
			(type default)
		)
		(layer "In3.Cu")
	)
	(gr_line
		(start 106.402124 -11.378946)
		(end 106.402124 -9.245346)
		(stroke
			(width 0.254)
			(type default)
		)
		(layer "In3.Cu")
	)
	(gr_line
		(start 106.402124 -9.245346)
		(end 107.926124 -9.245346)
		(stroke
			(width 0.254)
			(type default)
		)
		(layer "In3.Cu")
	)
	(gr_line
		(start 106.452924 -11.353546)
		(end 106.452924 -9.372346)
		(stroke
			(width 0.254)
			(type default)
		)
		(layer "In3.Cu")
	)
	(gr_line
		(start 106.452924 -9.372346)
		(end 107.900724 -9.372346)
		(stroke
			(width 0.254)
			(type default)
		)
		(layer "In3.Cu")
	)
	(gr_line
		(start 106.507026 -11.302746)
		(end 106.811826 -11.302746)
		(stroke
			(width 0.1016)
			(type default)
		)
		(layer "In3.Cu")
	)
	(gr_line
		(start 106.507026 -9.296146)
		(end 106.507026 -11.302746)
		(stroke
			(width 0.1016)
			(type default)
		)
		(layer "In3.Cu")
	)
	(gr_line
		(start 106.557826 -11.226546)
		(end 107.650026 -11.226546)
		(stroke
			(width 0.2032)
			(type default)
		)
		(layer "In3.Cu")
	)
	(gr_line
		(start 106.557826 -9.372346)
		(end 106.557826 -11.226546)
		(stroke
			(width 0.2032)
			(type default)
		)
		(layer "In3.Cu")
	)
	(gr_line
		(start 106.583226 -11.226546)
		(end 107.751626 -11.226546)
		(stroke
			(width 0.2032)
			(type default)
		)
		(layer "In3.Cu")
	)
	(gr_line
		(start 106.583226 -9.423146)
		(end 106.583226 -11.226546)
		(stroke
			(width 0.2032)
			(type default)
		)
		(layer "In3.Cu")
	)
	(gr_line
		(start 106.630724 -11.124946)
		(end 106.630724 -9.575546)
		(stroke
			(width 0.762)
			(type default)
		)
		(layer "In3.Cu")
	)
	(gr_line
		(start 106.630724 -11.124946)
		(end 107.545124 -11.124946)
		(stroke
			(width 0.762)
			(type default)
		)
		(layer "In3.Cu")
	)
	(gr_line
		(start 106.630724 -11.099546)
		(end 106.630724 -9.550146)
		(stroke
			(width 0.762)
			(type default)
		)
		(layer "In3.Cu")
	)
	(gr_line
		(start 106.630724 -10.997946)
		(end 106.630724 -9.448546)
		(stroke
			(width 0.762)
			(type default)
		)
		(layer "In3.Cu")
	)
	(gr_line
		(start 106.630724 -9.448546)
		(end 107.545124 -9.448546)
		(stroke
			(width 0.762)
			(type default)
		)
		(layer "In3.Cu")
	)
	(gr_line
		(start 106.634026 -11.175746)
		(end 107.726226 -11.175746)
		(stroke
			(width 0.2032)
			(type default)
		)
		(layer "In3.Cu")
	)
	(gr_line
		(start 106.634026 -9.473946)
		(end 106.634026 -11.175746)
		(stroke
			(width 0.2032)
			(type default)
		)
		(layer "In3.Cu")
	)
	(gr_line
		(start 106.656124 -10.997946)
		(end 107.570524 -10.997946)
		(stroke
			(width 0.762)
			(type default)
		)
		(layer "In3.Cu")
	)
	(gr_line
		(start 106.656124 -9.575546)
		(end 107.570524 -9.575546)
		(stroke
			(width 0.762)
			(type default)
		)
		(layer "In3.Cu")
	)
	(gr_line
		(start 106.735626 -11.074146)
		(end 107.523026 -11.074146)
		(stroke
			(width 0.508)
			(type default)
		)
		(layer "In3.Cu")
	)
	(gr_line
		(start 106.735626 -11.048746)
		(end 106.735626 -9.524746)
		(stroke
			(width 0.508)
			(type default)
		)
		(layer "In3.Cu")
	)
	(gr_line
		(start 106.761026 -11.074146)
		(end 106.761026 -9.550146)
		(stroke
			(width 0.508)
			(type default)
		)
		(layer "In3.Cu")
	)
	(gr_line
		(start 106.783124 -11.124946)
		(end 107.697524 -11.124946)
		(stroke
			(width 0.762)
			(type default)
		)
		(layer "In3.Cu")
	)
	(gr_line
		(start 106.783124 -9.448546)
		(end 107.697524 -9.448546)
		(stroke
			(width 0.762)
			(type default)
		)
		(layer "In3.Cu")
	)
	(gr_line
		(start 106.786426 -9.524746)
		(end 107.523026 -9.524746)
		(stroke
			(width 0.508)
			(type default)
		)
		(layer "In3.Cu")
	)
	(gr_line
		(start 106.811826 -11.302746)
		(end 107.802426 -11.302746)
		(stroke
			(width 0.1016)
			(type default)
		)
		(layer "In3.Cu")
	)
	(gr_line
		(start 106.811826 -11.074146)
		(end 106.811826 -9.550146)
		(stroke
			(width 0.508)
			(type default)
		)
		(layer "In3.Cu")
	)
	(gr_line
		(start 106.837226 -11.074146)
		(end 106.837226 -9.550146)
		(stroke
			(width 0.508)
			(type default)
		)
		(layer "In3.Cu")
	)
	(gr_line
		(start 106.862626 -11.074146)
		(end 106.862626 -9.550146)
		(stroke
			(width 0.508)
			(type default)
		)
		(layer "In3.Cu")
	)
	(gr_line
		(start 106.888026 -11.074146)
		(end 106.888026 -9.550146)
		(stroke
			(width 0.508)
			(type default)
		)
		(layer "In3.Cu")
	)
	(gr_line
		(start 106.888026 -11.048746)
		(end 106.888026 -9.524746)
		(stroke
			(width 0.508)
			(type default)
		)
		(layer "In3.Cu")
	)
	(gr_line
		(start 106.913426 -11.074146)
		(end 106.913426 -9.550146)
		(stroke
			(width 0.508)
			(type default)
		)
		(layer "In3.Cu")
	)
	(gr_line
		(start 106.938826 -11.074146)
		(end 106.938826 -9.550146)
		(stroke
			(width 0.508)
			(type default)
		)
		(layer "In3.Cu")
	)
	(gr_line
		(start 106.989626 -11.074146)
		(end 106.989626 -9.550146)
		(stroke
			(width 0.508)
			(type default)
		)
		(layer "In3.Cu")
	)
	(gr_line
		(start 106.989626 -11.048746)
		(end 106.989626 -9.524746)
		(stroke
			(width 0.508)
			(type default)
		)
		(layer "In3.Cu")
	)
	(gr_line
		(start 107.015026 -11.074146)
		(end 107.015026 -9.550146)
		(stroke
			(width 0.508)
			(type default)
		)
		(layer "In3.Cu")
	)
	(gr_line
		(start 107.040426 -11.074146)
		(end 107.040426 -9.550146)
		(stroke
			(width 0.508)
			(type default)
		)
		(layer "In3.Cu")
	)
	(gr_line
		(start 107.065826 -11.074146)
		(end 107.065826 -9.550146)
		(stroke
			(width 0.508)
			(type default)
		)
		(layer "In3.Cu")
	)
	(gr_line
		(start 107.116626 -11.074146)
		(end 107.116626 -9.550146)
		(stroke
			(width 0.508)
			(type default)
		)
		(layer "In3.Cu")
	)
	(gr_line
		(start 107.142026 -11.074146)
		(end 107.142026 -9.550146)
		(stroke
			(width 0.508)
			(type default)
		)
		(layer "In3.Cu")
	)
	(gr_line
		(start 107.142026 -11.048746)
		(end 107.142026 -9.524746)
		(stroke
			(width 0.508)
			(type default)
		)
		(layer "In3.Cu")
	)
	(gr_line
		(start 107.167426 -11.074146)
		(end 107.167426 -9.550146)
		(stroke
			(width 0.508)
			(type default)
		)
		(layer "In3.Cu")
	)
	(gr_line
		(start 107.192826 -11.074146)
		(end 107.192826 -9.550146)
		(stroke
			(width 0.508)
			(type default)
		)
		(layer "In3.Cu")
	)
	(gr_line
		(start 107.218226 -11.074146)
		(end 107.218226 -9.550146)
		(stroke
			(width 0.508)
			(type default)
		)
		(layer "In3.Cu")
	)
	(gr_line
		(start 107.218226 -11.048746)
		(end 107.218226 -9.524746)
		(stroke
			(width 0.508)
			(type default)
		)
		(layer "In3.Cu")
	)
	(gr_line
		(start 107.243626 -11.074146)
		(end 107.243626 -9.550146)
		(stroke
			(width 0.508)
			(type default)
		)
		(layer "In3.Cu")
	)
	(gr_line
		(start 107.269026 -11.074146)
		(end 107.269026 -9.550146)
		(stroke
			(width 0.508)
			(type default)
		)
		(layer "In3.Cu")
	)
	(gr_line
		(start 107.269026 -11.048746)
		(end 107.269026 -9.524746)
		(stroke
			(width 0.508)
			(type default)
		)
		(layer "In3.Cu")
	)
	(gr_line
		(start 107.294426 -11.074146)
		(end 107.294426 -9.550146)
		(stroke
			(width 0.508)
			(type default)
		)
		(layer "In3.Cu")
	)
	(gr_line
		(start 107.294426 -11.048746)
		(end 107.294426 -9.524746)
		(stroke
			(width 0.508)
			(type default)
		)
		(layer "In3.Cu")
	)
	(gr_line
		(start 107.319826 -11.048746)
		(end 107.319826 -9.524746)
		(stroke
			(width 0.508)
			(type default)
		)
		(layer "In3.Cu")
	)
	(gr_line
		(start 107.345226 -11.074146)
		(end 107.345226 -9.550146)
		(stroke
			(width 0.508)
			(type default)
		)
		(layer "In3.Cu")
	)
	(gr_line
		(start 107.367324 -11.378946)
		(end 106.376724 -11.378946)
		(stroke
			(width 0.254)
			(type default)
		)
		(layer "In3.Cu")
	)
	(gr_line
		(start 107.370626 -11.048746)
		(end 107.370626 -9.524746)
		(stroke
			(width 0.508)
			(type default)
		)
		(layer "In3.Cu")
	)
	(gr_line
		(start 107.396026 -11.048746)
		(end 107.396026 -9.524746)
		(stroke
			(width 0.508)
			(type default)
		)
		(layer "In3.Cu")
	)
	(gr_line
		(start 107.421426 -11.074146)
		(end 107.421426 -9.550146)
		(stroke
			(width 0.508)
			(type default)
		)
		(layer "In3.Cu")
	)
	(gr_line
		(start 107.446826 -11.074146)
		(end 107.446826 -9.550146)
		(stroke
			(width 0.508)
			(type default)
		)
		(layer "In3.Cu")
	)
	(gr_line
		(start 107.446826 -11.048746)
		(end 107.446826 -9.524746)
		(stroke
			(width 0.508)
			(type default)
		)
		(layer "In3.Cu")
	)
	(gr_line
		(start 107.497626 -11.074146)
		(end 107.497626 -9.550146)
		(stroke
			(width 0.508)
			(type default)
		)
		(layer "In3.Cu")
	)
	(gr_line
		(start 107.497626 -11.048746)
		(end 107.497626 -9.524746)
		(stroke
			(width 0.508)
			(type default)
		)
		(layer "In3.Cu")
	)
	(gr_line
		(start 107.548426 -11.074146)
		(end 107.548426 -9.550146)
		(stroke
			(width 0.508)
			(type default)
		)
		(layer "In3.Cu")
	)
	(gr_line
		(start 107.548426 -11.048746)
		(end 107.548426 -9.524746)
		(stroke
			(width 0.508)
			(type default)
		)
		(layer "In3.Cu")
	)
	(gr_line
		(start 107.570524 -11.099546)
		(end 107.570524 -9.550146)
		(stroke
			(width 0.762)
			(type default)
		)
		(layer "In3.Cu")
	)
	(gr_line
		(start 107.573826 -11.074146)
		(end 107.573826 -9.550146)
		(stroke
			(width 0.508)
			(type default)
		)
		(layer "In3.Cu")
	)
	(gr_line
		(start 107.599226 -11.074146)
		(end 107.599226 -9.550146)
		(stroke
			(width 0.508)
			(type default)
		)
		(layer "In3.Cu")
	)
	(gr_line
		(start 107.650026 -11.226546)
		(end 107.675426 -11.226546)
		(stroke
			(width 0.2032)
			(type default)
		)
		(layer "In3.Cu")
	)
	(gr_line
		(start 107.675426 -11.226546)
		(end 107.675426 -9.473946)
		(stroke
			(width 0.2032)
			(type default)
		)
		(layer "In3.Cu")
	)
	(gr_line
		(start 107.675426 -9.473946)
		(end 106.634026 -9.473946)
		(stroke
			(width 0.2032)
			(type default)
		)
		(layer "In3.Cu")
	)
	(gr_line
		(start 107.697524 -11.124946)
		(end 107.697524 -9.575546)
		(stroke
			(width 0.762)
			(type default)
		)
		(layer "In3.Cu")
	)
	(gr_line
		(start 107.697524 -11.099546)
		(end 107.697524 -9.600946)
		(stroke
			(width 0.762)
			(type default)
		)
		(layer "In3.Cu")
	)
	(gr_line
		(start 107.697524 -10.997946)
		(end 107.697524 -9.448546)
		(stroke
			(width 0.762)
			(type default)
		)
		(layer "In3.Cu")
	)
	(gr_line
		(start 107.726226 -11.175746)
		(end 107.726226 -9.423146)
		(stroke
			(width 0.2032)
			(type default)
		)
		(layer "In3.Cu")
	)
	(gr_line
		(start 107.726226 -9.423146)
		(end 106.583226 -9.423146)
		(stroke
			(width 0.2032)
			(type default)
		)
		(layer "In3.Cu")
	)
	(gr_line
		(start 107.751626 -11.226546)
		(end 107.751626 -9.372346)
		(stroke
			(width 0.2032)
			(type default)
		)
		(layer "In3.Cu")
	)
	(gr_line
		(start 107.751626 -9.372346)
		(end 106.557826 -9.372346)
		(stroke
			(width 0.2032)
			(type default)
		)
		(layer "In3.Cu")
	)
	(gr_line
		(start 107.802426 -11.302746)
		(end 107.802426 -9.296146)
		(stroke
			(width 0.1016)
			(type default)
		)
		(layer "In3.Cu")
	)
	(gr_line
		(start 107.802426 -9.296146)
		(end 106.507026 -9.296146)
		(stroke
			(width 0.1016)
			(type default)
		)
		(layer "In3.Cu")
	)
	(gr_line
		(start 107.900724 -11.226546)
		(end 107.650026 -11.226546)
		(stroke
			(width 0.254)
			(type default)
		)
		(layer "In3.Cu")
	)
	(gr_line
		(start 107.900724 -9.372346)
		(end 107.900724 -11.226546)
		(stroke
			(width 0.254)
			(type default)
		)
		(layer "In3.Cu")
	)
	(gr_line
		(start 107.926124 -11.353546)
		(end 106.452924 -11.353546)
		(stroke
			(width 0.254)
			(type default)
		)
		(layer "In3.Cu")
	)
	(gr_line
		(start 107.926124 -9.245346)
		(end 107.926124 -11.353546)
		(stroke
			(width 0.254)
			(type default)
		)
		(layer "In3.Cu")
	)
	(gr_line
		(start 107.951524 -11.378946)
		(end 106.402124 -11.378946)
		(stroke
			(width 0.254)
			(type default)
		)
		(layer "In3.Cu")
	)
	(gr_line
		(start 107.951524 -9.194546)
		(end 107.951524 -11.378946)
		(stroke
			(width 0.254)
			(type default)
		)
		(layer "In3.Cu")
	)
	(gr_arc
		(start 113.069878 -51.319938)
		(mid 113.362771 -52.027043)
		(end 114.069876 -52.319936)
		(stroke
			(width 2.032)
			(type default)
		)
		(layer "In3.Cu")
	)
	(gr_arc
		(start 113.069878 -50.8)
		(mid 112.776984 -50.092902)
		(end 112.06988 -49.800002)
		(stroke
			(width 2.032)
			(type default)
		)
		(layer "In3.Cu")
	)
	(gr_line
		(start 113.069878 -50.8)
		(end 113.069878 -51.319938)
		(stroke
			(width 2.032)
			(type default)
		)
		(layer "In3.Cu")
	)
	(gr_line
		(start 113.76152 -9.1948)
		(end 115.18392 -9.1948)
		(stroke
			(width 1.016)
			(type default)
		)
		(layer "In3.Cu")
	)
	(gr_line
		(start 114.069876 -52.319936)
		(end 132.990082 -52.319936)
		(stroke
			(width 2.032)
			(type default)
		)
		(layer "In3.Cu")
	)
	(gr_line
		(start 117.856 -13.843)
		(end 118.6942 -13.843)
		(stroke
			(width 0.1016)
			(type default)
		)
		(layer "In3.Cu")
	)
	(gr_line
		(start 117.856 -11.1252)
		(end 117.856 -13.843)
		(stroke
			(width 0.1016)
			(type default)
		)
		(layer "In3.Cu")
	)
	(gr_line
		(start 117.856 -9.64311)
		(end 118.6942 -9.64311)
		(stroke
			(width 0.1016)
			(type default)
		)
		(layer "In3.Cu")
	)
	(gr_line
		(start 117.856 -6.92531)
		(end 117.856 -9.64311)
		(stroke
			(width 0.1016)
			(type default)
		)
		(layer "In3.Cu")
	)
	(gr_line
		(start 117.8814 -13.8176)
		(end 117.8814 -11.1506)
		(stroke
			(width 0.127)
			(type default)
		)
		(layer "In3.Cu")
	)
	(gr_line
		(start 117.8814 -11.1506)
		(end 119.1768 -11.1506)
		(stroke
			(width 0.127)
			(type default)
		)
		(layer "In3.Cu")
	)
	(gr_line
		(start 117.8814 -9.61771)
		(end 117.8814 -6.95071)
		(stroke
			(width 0.127)
			(type default)
		)
		(layer "In3.Cu")
	)
	(gr_line
		(start 117.8814 -6.95071)
		(end 119.1768 -6.95071)
		(stroke
			(width 0.127)
			(type default)
		)
		(layer "In3.Cu")
	)
	(gr_line
		(start 117.9068 -13.8176)
		(end 117.9068 -11.176)
		(stroke
			(width 0.127)
			(type default)
		)
		(layer "In3.Cu")
	)
	(gr_line
		(start 117.9068 -13.7922)
		(end 117.9068 -11.176)
		(stroke
			(width 0.1778)
			(type default)
		)
		(layer "In3.Cu")
	)
	(gr_line
		(start 117.9068 -11.176)
		(end 119.1514 -11.176)
		(stroke
			(width 0.127)
			(type default)
		)
		(layer "In3.Cu")
	)
	(gr_line
		(start 117.9068 -11.176)
		(end 119.1514 -11.176)
		(stroke
			(width 0.1778)
			(type default)
		)
		(layer "In3.Cu")
	)
	(gr_line
		(start 117.9068 -9.61771)
		(end 117.9068 -6.97611)
		(stroke
			(width 0.127)
			(type default)
		)
		(layer "In3.Cu")
	)
	(gr_line
		(start 117.9068 -9.59231)
		(end 117.9068 -6.97611)
		(stroke
			(width 0.1778)
			(type default)
		)
		(layer "In3.Cu")
	)
	(gr_line
		(start 117.9068 -6.97611)
		(end 119.1514 -6.97611)
		(stroke
			(width 0.127)
			(type default)
		)
		(layer "In3.Cu")
	)
	(gr_line
		(start 117.9068 -6.97611)
		(end 119.1514 -6.97611)
		(stroke
			(width 0.1778)
			(type default)
		)
		(layer "In3.Cu")
	)
	(gr_line
		(start 117.9322 -13.7922)
		(end 117.9322 -11.2014)
		(stroke
			(width 0.1778)
			(type default)
		)
		(layer "In3.Cu")
	)
	(gr_line
		(start 117.9322 -11.2014)
		(end 119.126 -11.2014)
		(stroke
			(width 0.1778)
			(type default)
		)
		(layer "In3.Cu")
	)
	(gr_line
		(start 117.9322 -9.59231)
		(end 117.9322 -7.00151)
		(stroke
			(width 0.1778)
			(type default)
		)
		(layer "In3.Cu")
	)
	(gr_line
		(start 117.9322 -7.00151)
		(end 119.126 -7.00151)
		(stroke
			(width 0.1778)
			(type default)
		)
		(layer "In3.Cu")
	)
	(gr_line
		(start 117.9576 -13.7668)
		(end 117.9576 -11.2268)
		(stroke
			(width 0.254)
			(type default)
		)
		(layer "In3.Cu")
	)
	(gr_line
		(start 117.9576 -11.2268)
		(end 119.126 -11.2268)
		(stroke
			(width 0.254)
			(type default)
		)
		(layer "In3.Cu")
	)
	(gr_line
		(start 117.9576 -9.56691)
		(end 117.9576 -7.02691)
		(stroke
			(width 0.254)
			(type default)
		)
		(layer "In3.Cu")
	)
	(gr_line
		(start 117.9576 -7.02691)
		(end 119.126 -7.02691)
		(stroke
			(width 0.254)
			(type default)
		)
		(layer "In3.Cu")
	)
	(gr_line
		(start 117.983 -13.7668)
		(end 117.983 -11.2522)
		(stroke
			(width 0.254)
			(type default)
		)
		(layer "In3.Cu")
	)
	(gr_line
		(start 117.983 -11.2522)
		(end 119.1006 -11.2522)
		(stroke
			(width 0.254)
			(type default)
		)
		(layer "In3.Cu")
	)
	(gr_line
		(start 117.983 -9.56691)
		(end 117.983 -7.05231)
		(stroke
			(width 0.254)
			(type default)
		)
		(layer "In3.Cu")
	)
	(gr_line
		(start 117.983 -7.05231)
		(end 119.1006 -7.05231)
		(stroke
			(width 0.254)
			(type default)
		)
		(layer "In3.Cu")
	)
	(gr_line
		(start 118.0084 -13.716)
		(end 118.0084 -11.2776)
		(stroke
			(width 0.3556)
			(type default)
		)
		(layer "In3.Cu")
	)
	(gr_line
		(start 118.0084 -11.2776)
		(end 119.0498 -11.2776)
		(stroke
			(width 0.3556)
			(type default)
		)
		(layer "In3.Cu")
	)
	(gr_line
		(start 118.0084 -9.51611)
		(end 118.0084 -7.07771)
		(stroke
			(width 0.3556)
			(type default)
		)
		(layer "In3.Cu")
	)
	(gr_line
		(start 118.0084 -7.07771)
		(end 119.0498 -7.07771)
		(stroke
			(width 0.3556)
			(type default)
		)
		(layer "In3.Cu")
	)
	(gr_line
		(start 118.0592 -13.6906)
		(end 118.0592 -11.3284)
		(stroke
			(width 0.381)
			(type default)
		)
		(layer "In3.Cu")
	)
	(gr_line
		(start 118.0592 -11.3284)
		(end 118.999 -11.3284)
		(stroke
			(width 0.381)
			(type default)
		)
		(layer "In3.Cu")
	)
	(gr_line
		(start 118.0592 -9.49071)
		(end 118.0592 -7.12851)
		(stroke
			(width 0.381)
			(type default)
		)
		(layer "In3.Cu")
	)
	(gr_line
		(start 118.0592 -7.12851)
		(end 118.999 -7.12851)
		(stroke
			(width 0.381)
			(type default)
		)
		(layer "In3.Cu")
	)
	(gr_line
		(start 118.1354 -13.6398)
		(end 118.1354 -11.3792)
		(stroke
			(width 0.381)
			(type default)
		)
		(layer "In3.Cu")
	)
	(gr_line
		(start 118.1354 -11.3792)
		(end 118.9482 -11.3792)
		(stroke
			(width 0.381)
			(type default)
		)
		(layer "In3.Cu")
	)
	(gr_line
		(start 118.1354 -9.43991)
		(end 118.1354 -7.17931)
		(stroke
			(width 0.381)
			(type default)
		)
		(layer "In3.Cu")
	)
	(gr_line
		(start 118.1354 -7.17931)
		(end 118.9482 -7.17931)
		(stroke
			(width 0.381)
			(type default)
		)
		(layer "In3.Cu")
	)
	(gr_line
		(start 118.1608 -13.5636)
		(end 118.1608 -11.3792)
		(stroke
			(width 0.508)
			(type default)
		)
		(layer "In3.Cu")
	)
	(gr_line
		(start 118.1608 -11.3792)
		(end 118.9228 -11.3792)
		(stroke
			(width 0.508)
			(type default)
		)
		(layer "In3.Cu")
	)
	(gr_line
		(start 118.1608 -9.36371)
		(end 118.1608 -7.17931)
		(stroke
			(width 0.508)
			(type default)
		)
		(layer "In3.Cu")
	)
	(gr_line
		(start 118.1608 -7.17931)
		(end 118.9228 -7.17931)
		(stroke
			(width 0.508)
			(type default)
		)
		(layer "In3.Cu")
	)
	(gr_line
		(start 118.1862 -13.4112)
		(end 118.7704 -13.4112)
		(stroke
			(width 0.762)
			(type default)
		)
		(layer "In3.Cu")
	)
	(gr_line
		(start 118.1862 -11.5824)
		(end 118.7704 -11.5824)
		(stroke
			(width 0.762)
			(type default)
		)
		(layer "In3.Cu")
	)
	(gr_line
		(start 118.1862 -9.21131)
		(end 118.7704 -9.21131)
		(stroke
			(width 0.762)
			(type default)
		)
		(layer "In3.Cu")
	)
	(gr_line
		(start 118.1862 -7.38251)
		(end 118.7704 -7.38251)
		(stroke
			(width 0.762)
			(type default)
		)
		(layer "In3.Cu")
	)
	(gr_line
		(start 118.2116 -13.5636)
		(end 118.2116 -11.43)
		(stroke
			(width 0.635)
			(type default)
		)
		(layer "In3.Cu")
	)
	(gr_line
		(start 118.2116 -13.5128)
		(end 118.2116 -11.4808)
		(stroke
			(width 0.762)
			(type default)
		)
		(layer "In3.Cu")
	)
	(gr_line
		(start 118.2116 -11.43)
		(end 118.8974 -11.43)
		(stroke
			(width 0.635)
			(type default)
		)
		(layer "In3.Cu")
	)
	(gr_line
		(start 118.2116 -9.36371)
		(end 118.2116 -7.23011)
		(stroke
			(width 0.635)
			(type default)
		)
		(layer "In3.Cu")
	)
	(gr_line
		(start 118.2116 -9.31291)
		(end 118.2116 -7.28091)
		(stroke
			(width 0.762)
			(type default)
		)
		(layer "In3.Cu")
	)
	(gr_line
		(start 118.2116 -7.23011)
		(end 118.8974 -7.23011)
		(stroke
			(width 0.635)
			(type default)
		)
		(layer "In3.Cu")
	)
	(gr_line
		(start 118.237 -13.5128)
		(end 118.237 -11.4808)
		(stroke
			(width 0.762)
			(type default)
		)
		(layer "In3.Cu")
	)
	(gr_line
		(start 118.237 -11.4808)
		(end 118.8212 -11.4808)
		(stroke
			(width 0.762)
			(type default)
		)
		(layer "In3.Cu")
	)
	(gr_line
		(start 118.237 -9.31291)
		(end 118.237 -7.28091)
		(stroke
			(width 0.762)
			(type default)
		)
		(layer "In3.Cu")
	)
	(gr_line
		(start 118.237 -7.28091)
		(end 118.8212 -7.28091)
		(stroke
			(width 0.762)
			(type default)
		)
		(layer "In3.Cu")
	)
	(gr_line
		(start 118.2624 -13.5128)
		(end 118.2624 -11.4808)
		(stroke
			(width 0.762)
			(type default)
		)
		(layer "In3.Cu")
	)
	(gr_line
		(start 118.2624 -13.5128)
		(end 118.8466 -13.5128)
		(stroke
			(width 0.762)
			(type default)
		)
		(layer "In3.Cu")
	)
	(gr_line
		(start 118.2624 -13.4874)
		(end 118.2624 -11.4554)
		(stroke
			(width 0.762)
			(type default)
		)
		(layer "In3.Cu")
	)
	(gr_line
		(start 118.2624 -9.31291)
		(end 118.2624 -7.28091)
		(stroke
			(width 0.762)
			(type default)
		)
		(layer "In3.Cu")
	)
	(gr_line
		(start 118.2624 -9.31291)
		(end 118.8466 -9.31291)
		(stroke
			(width 0.762)
			(type default)
		)
		(layer "In3.Cu")
	)
	(gr_line
		(start 118.2624 -9.28751)
		(end 118.2624 -7.25551)
		(stroke
			(width 0.762)
			(type default)
		)
		(layer "In3.Cu")
	)
	(gr_line
		(start 118.2878 -13.5128)
		(end 118.2878 -11.4808)
		(stroke
			(width 0.762)
			(type default)
		)
		(layer "In3.Cu")
	)
	(gr_line
		(start 118.2878 -9.31291)
		(end 118.2878 -7.28091)
		(stroke
			(width 0.762)
			(type default)
		)
		(layer "In3.Cu")
	)
	(gr_line
		(start 118.3132 -13.5128)
		(end 118.3132 -11.4808)
		(stroke
			(width 0.762)
			(type default)
		)
		(layer "In3.Cu")
	)
	(gr_line
		(start 118.3132 -9.31291)
		(end 118.3132 -7.28091)
		(stroke
			(width 0.762)
			(type default)
		)
		(layer "In3.Cu")
	)
	(gr_line
		(start 118.3386 -13.5128)
		(end 118.3386 -11.4808)
		(stroke
			(width 0.762)
			(type default)
		)
		(layer "In3.Cu")
	)
	(gr_line
		(start 118.3386 -9.31291)
		(end 118.3386 -7.28091)
		(stroke
			(width 0.762)
			(type default)
		)
		(layer "In3.Cu")
	)
	(gr_line
		(start 118.3894 -13.5128)
		(end 118.3894 -11.4808)
		(stroke
			(width 0.762)
			(type default)
		)
		(layer "In3.Cu")
	)
	(gr_line
		(start 118.3894 -9.31291)
		(end 118.3894 -7.28091)
		(stroke
			(width 0.762)
			(type default)
		)
		(layer "In3.Cu")
	)
	(gr_line
		(start 118.4148 -13.5128)
		(end 118.4148 -11.4808)
		(stroke
			(width 0.762)
			(type default)
		)
		(layer "In3.Cu")
	)
	(gr_line
		(start 118.4148 -9.31291)
		(end 118.4148 -7.28091)
		(stroke
			(width 0.762)
			(type default)
		)
		(layer "In3.Cu")
	)
	(gr_line
		(start 118.4402 -13.5128)
		(end 118.4402 -11.7094)
		(stroke
			(width 0.635)
			(type default)
		)
		(layer "In3.Cu")
	)
	(gr_line
		(start 118.4402 -11.7094)
		(end 118.5418 -11.7094)
		(stroke
			(width 0.635)
			(type default)
		)
		(layer "In3.Cu")
	)
	(gr_line
		(start 118.4402 -9.31291)
		(end 118.4402 -7.50951)
		(stroke
			(width 0.635)
			(type default)
		)
		(layer "In3.Cu")
	)
	(gr_line
		(start 118.4402 -7.50951)
		(end 118.5418 -7.50951)
		(stroke
			(width 0.635)
			(type default)
		)
		(layer "In3.Cu")
	)
	(gr_line
		(start 118.4656 -13.5128)
		(end 118.4656 -11.4808)
		(stroke
			(width 0.762)
			(type default)
		)
		(layer "In3.Cu")
	)
	(gr_line
		(start 118.4656 -13.4874)
		(end 118.4656 -11.4554)
		(stroke
			(width 0.762)
			(type default)
		)
		(layer "In3.Cu")
	)
	(gr_line
		(start 118.4656 -13.4366)
		(end 118.4656 -11.6586)
		(stroke
			(width 0.635)
			(type default)
		)
		(layer "In3.Cu")
	)
	(gr_line
		(start 118.4656 -9.31291)
		(end 118.4656 -7.28091)
		(stroke
			(width 0.762)
			(type default)
		)
		(layer "In3.Cu")
	)
	(gr_line
		(start 118.4656 -9.28751)
		(end 118.4656 -7.25551)
		(stroke
			(width 0.762)
			(type default)
		)
		(layer "In3.Cu")
	)
	(gr_line
		(start 118.4656 -9.23671)
		(end 118.4656 -7.45871)
		(stroke
			(width 0.635)
			(type default)
		)
		(layer "In3.Cu")
	)
	(gr_line
		(start 118.5164 -13.5128)
		(end 118.5164 -11.4808)
		(stroke
			(width 0.762)
			(type default)
		)
		(layer "In3.Cu")
	)
	(gr_line
		(start 118.5164 -9.31291)
		(end 118.5164 -7.28091)
		(stroke
			(width 0.762)
			(type default)
		)
		(layer "In3.Cu")
	)
	(gr_line
		(start 118.5418 -13.5128)
		(end 118.5418 -11.4808)
		(stroke
			(width 0.762)
			(type default)
		)
		(layer "In3.Cu")
	)
	(gr_line
		(start 118.5418 -13.4874)
		(end 118.5418 -11.4554)
		(stroke
			(width 0.762)
			(type default)
		)
		(layer "In3.Cu")
	)
	(gr_line
		(start 118.5418 -13.4366)
		(end 118.4656 -13.4366)
		(stroke
			(width 0.635)
			(type default)
		)
		(layer "In3.Cu")
	)
	(gr_line
		(start 118.5418 -11.7094)
		(end 118.5418 -13.4366)
		(stroke
			(width 0.635)
			(type default)
		)
		(layer "In3.Cu")
	)
	(gr_line
		(start 118.5418 -9.31291)
		(end 118.5418 -7.28091)
		(stroke
			(width 0.762)
			(type default)
		)
		(layer "In3.Cu")
	)
	(gr_line
		(start 118.5418 -9.28751)
		(end 118.5418 -7.25551)
		(stroke
			(width 0.762)
			(type default)
		)
		(layer "In3.Cu")
	)
	(gr_line
		(start 118.5418 -9.23671)
		(end 118.4656 -9.23671)
		(stroke
			(width 0.635)
			(type default)
		)
		(layer "In3.Cu")
	)
	(gr_line
		(start 118.5418 -7.50951)
		(end 118.5418 -9.23671)
		(stroke
			(width 0.635)
			(type default)
		)
		(layer "In3.Cu")
	)
	(gr_line
		(start 118.5926 -13.4874)
		(end 118.5926 -11.4554)
		(stroke
			(width 0.762)
			(type default)
		)
		(layer "In3.Cu")
	)
	(gr_line
		(start 118.5926 -9.28751)
		(end 118.5926 -7.25551)
		(stroke
			(width 0.762)
			(type default)
		)
		(layer "In3.Cu")
	)
	(gr_line
		(start 118.618 -13.4874)
		(end 118.618 -11.4554)
		(stroke
			(width 0.762)
			(type default)
		)
		(layer "In3.Cu")
	)
	(gr_line
		(start 118.618 -9.28751)
		(end 118.618 -7.25551)
		(stroke
			(width 0.762)
			(type default)
		)
		(layer "In3.Cu")
	)
	(gr_line
		(start 118.6688 -13.5128)
		(end 118.6688 -11.4808)
		(stroke
			(width 0.762)
			(type default)
		)
		(layer "In3.Cu")
	)
	(gr_line
		(start 118.6688 -9.31291)
		(end 118.6688 -7.28091)
		(stroke
			(width 0.762)
			(type default)
		)
		(layer "In3.Cu")
	)
	(gr_line
		(start 118.6942 -13.843)
		(end 119.2022 -13.843)
		(stroke
			(width 0.1016)
			(type default)
		)
		(layer "In3.Cu")
	)
	(gr_line
		(start 118.6942 -13.4874)
		(end 118.6942 -11.4554)
		(stroke
			(width 0.762)
			(type default)
		)
		(layer "In3.Cu")
	)
	(gr_line
		(start 118.6942 -9.64311)
		(end 119.2022 -9.64311)
		(stroke
			(width 0.1016)
			(type default)
		)
		(layer "In3.Cu")
	)
	(gr_line
		(start 118.6942 -9.28751)
		(end 118.6942 -7.25551)
		(stroke
			(width 0.762)
			(type default)
		)
		(layer "In3.Cu")
	)
	(gr_line
		(start 118.745 -13.5128)
		(end 118.745 -11.4808)
		(stroke
			(width 0.762)
			(type default)
		)
		(layer "In3.Cu")
	)
	(gr_line
		(start 118.745 -13.4874)
		(end 118.745 -11.4554)
		(stroke
			(width 0.762)
			(type default)
		)
		(layer "In3.Cu")
	)
	(gr_line
		(start 118.745 -9.31291)
		(end 118.745 -7.28091)
		(stroke
			(width 0.762)
			(type default)
		)
		(layer "In3.Cu")
	)
	(gr_line
		(start 118.745 -9.28751)
		(end 118.745 -7.25551)
		(stroke
			(width 0.762)
			(type default)
		)
		(layer "In3.Cu")
	)
	(gr_line
		(start 118.7704 -13.4874)
		(end 118.7704 -11.4554)
		(stroke
			(width 0.762)
			(type default)
		)
		(layer "In3.Cu")
	)
	(gr_line
		(start 118.7704 -9.28751)
		(end 118.7704 -7.25551)
		(stroke
			(width 0.762)
			(type default)
		)
		(layer "In3.Cu")
	)
	(gr_line
		(start 118.7958 -13.5636)
		(end 118.1608 -13.5636)
		(stroke
			(width 0.508)
			(type default)
		)
		(layer "In3.Cu")
	)
	(gr_line
		(start 118.7958 -13.5636)
		(end 118.2116 -13.5636)
		(stroke
			(width 0.635)
			(type default)
		)
		(layer "In3.Cu")
	)
	(gr_line
		(start 118.7958 -9.36371)
		(end 118.1608 -9.36371)
		(stroke
			(width 0.508)
			(type default)
		)
		(layer "In3.Cu")
	)
	(gr_line
		(start 118.7958 -9.36371)
		(end 118.2116 -9.36371)
		(stroke
			(width 0.635)
			(type default)
		)
		(layer "In3.Cu")
	)
	(gr_line
		(start 118.8212 -13.4874)
		(end 118.8212 -11.4554)
		(stroke
			(width 0.762)
			(type default)
		)
		(layer "In3.Cu")
	)
	(gr_line
		(start 118.8212 -9.28751)
		(end 118.8212 -7.25551)
		(stroke
			(width 0.762)
			(type default)
		)
		(layer "In3.Cu")
	)
	(gr_line
		(start 118.8466 -13.716)
		(end 118.0084 -13.716)
		(stroke
			(width 0.3556)
			(type default)
		)
		(layer "In3.Cu")
	)
	(gr_line
		(start 118.8466 -13.6906)
		(end 118.0592 -13.6906)
		(stroke
			(width 0.381)
			(type default)
		)
		(layer "In3.Cu")
	)
	(gr_line
		(start 118.8466 -9.51611)
		(end 118.0084 -9.51611)
		(stroke
			(width 0.3556)
			(type default)
		)
		(layer "In3.Cu")
	)
	(gr_line
		(start 118.8466 -9.49071)
		(end 118.0592 -9.49071)
		(stroke
			(width 0.381)
			(type default)
		)
		(layer "In3.Cu")
	)
	(gr_line
		(start 118.872 -13.5128)
		(end 118.872 -11.4808)
		(stroke
			(width 0.762)
			(type default)
		)
		(layer "In3.Cu")
	)
	(gr_line
		(start 118.872 -9.31291)
		(end 118.872 -7.28091)
		(stroke
			(width 0.762)
			(type default)
		)
		(layer "In3.Cu")
	)
	(gr_line
		(start 118.8974 -13.7668)
		(end 117.9576 -13.7668)
		(stroke
			(width 0.254)
			(type default)
		)
		(layer "In3.Cu")
	)
	(gr_line
		(start 118.8974 -13.5128)
		(end 118.4402 -13.5128)
		(stroke
			(width 0.635)
			(type default)
		)
		(layer "In3.Cu")
	)
	(gr_line
		(start 118.8974 -11.43)
		(end 118.8974 -13.5128)
		(stroke
			(width 0.635)
			(type default)
		)
		(layer "In3.Cu")
	)
	(gr_line
		(start 118.8974 -9.56691)
		(end 117.9576 -9.56691)
		(stroke
			(width 0.254)
			(type default)
		)
		(layer "In3.Cu")
	)
	(gr_line
		(start 118.8974 -9.31291)
		(end 118.4402 -9.31291)
		(stroke
			(width 0.635)
			(type default)
		)
		(layer "In3.Cu")
	)
	(gr_line
		(start 118.8974 -7.23011)
		(end 118.8974 -9.31291)
		(stroke
			(width 0.635)
			(type default)
		)
		(layer "In3.Cu")
	)
	(gr_line
		(start 118.9228 -13.7922)
		(end 117.9068 -13.7922)
		(stroke
			(width 0.1778)
			(type default)
		)
		(layer "In3.Cu")
	)
	(gr_line
		(start 118.9228 -13.5636)
		(end 118.7958 -13.5636)
		(stroke
			(width 0.508)
			(type default)
		)
		(layer "In3.Cu")
	)
	(gr_line
		(start 118.9228 -11.3792)
		(end 118.9228 -13.5636)
		(stroke
			(width 0.508)
			(type default)
		)
		(layer "In3.Cu")
	)
	(gr_line
		(start 118.9228 -9.59231)
		(end 117.9068 -9.59231)
		(stroke
			(width 0.1778)
			(type default)
		)
		(layer "In3.Cu")
	)
	(gr_line
		(start 118.9228 -9.36371)
		(end 118.7958 -9.36371)
		(stroke
			(width 0.508)
			(type default)
		)
		(layer "In3.Cu")
	)
	(gr_line
		(start 118.9228 -7.17931)
		(end 118.9228 -9.36371)
		(stroke
			(width 0.508)
			(type default)
		)
		(layer "In3.Cu")
	)
	(gr_line
		(start 118.9482 -13.5636)
		(end 118.7958 -13.5636)
		(stroke
			(width 0.381)
			(type default)
		)
		(layer "In3.Cu")
	)
	(gr_line
		(start 118.9482 -11.3792)
		(end 118.9482 -13.5636)
		(stroke
			(width 0.381)
			(type default)
		)
		(layer "In3.Cu")
	)
	(gr_line
		(start 118.9482 -9.36371)
		(end 118.7958 -9.36371)
		(stroke
			(width 0.381)
			(type default)
		)
		(layer "In3.Cu")
	)
	(gr_line
		(start 118.9482 -7.17931)
		(end 118.9482 -9.36371)
		(stroke
			(width 0.381)
			(type default)
		)
		(layer "In3.Cu")
	)
	(gr_line
		(start 118.999 -13.6398)
		(end 118.1354 -13.6398)
		(stroke
			(width 0.381)
			(type default)
		)
		(layer "In3.Cu")
	)
	(gr_line
		(start 118.999 -11.3284)
		(end 118.999 -13.6398)
		(stroke
			(width 0.381)
			(type default)
		)
		(layer "In3.Cu")
	)
	(gr_line
		(start 118.999 -9.43991)
		(end 118.1354 -9.43991)
		(stroke
			(width 0.381)
			(type default)
		)
		(layer "In3.Cu")
	)
	(gr_line
		(start 118.999 -7.12851)
		(end 118.999 -9.43991)
		(stroke
			(width 0.381)
			(type default)
		)
		(layer "In3.Cu")
	)
	(gr_line
		(start 119.0498 -13.6906)
		(end 118.8466 -13.6906)
		(stroke
			(width 0.3556)
			(type default)
		)
		(layer "In3.Cu")
	)
	(gr_line
		(start 119.0498 -11.2776)
		(end 119.0498 -13.6906)
		(stroke
			(width 0.3556)
			(type default)
		)
		(layer "In3.Cu")
	)
	(gr_line
		(start 119.0498 -9.49071)
		(end 118.8466 -9.49071)
		(stroke
			(width 0.3556)
			(type default)
		)
		(layer "In3.Cu")
	)
	(gr_line
		(start 119.0498 -7.07771)
		(end 119.0498 -9.49071)
		(stroke
			(width 0.3556)
			(type default)
		)
		(layer "In3.Cu")
	)
	(gr_line
		(start 119.0752 -13.8176)
		(end 117.8814 -13.8176)
		(stroke
			(width 0.127)
			(type default)
		)
		(layer "In3.Cu")
	)
	(gr_line
		(start 119.0752 -9.61771)
		(end 117.8814 -9.61771)
		(stroke
			(width 0.127)
			(type default)
		)
		(layer "In3.Cu")
	)
	(gr_line
		(start 119.1006 -13.716)
		(end 118.8466 -13.716)
		(stroke
			(width 0.254)
			(type default)
		)
		(layer "In3.Cu")
	)
	(gr_line
		(start 119.1006 -11.2522)
		(end 119.1006 -13.716)
		(stroke
			(width 0.254)
			(type default)
		)
		(layer "In3.Cu")
	)
	(gr_line
		(start 119.1006 -9.51611)
		(end 118.8466 -9.51611)
		(stroke
			(width 0.254)
			(type default)
		)
		(layer "In3.Cu")
	)
	(gr_line
		(start 119.1006 -7.05231)
		(end 119.1006 -9.51611)
		(stroke
			(width 0.254)
			(type default)
		)
		(layer "In3.Cu")
	)
	(gr_line
		(start 119.126 -13.7668)
		(end 117.983 -13.7668)
		(stroke
			(width 0.254)
			(type default)
		)
		(layer "In3.Cu")
	)
	(gr_line
		(start 119.126 -13.7668)
		(end 118.8974 -13.7668)
		(stroke
			(width 0.1778)
			(type default)
		)
		(layer "In3.Cu")
	)
	(gr_line
		(start 119.126 -11.2268)
		(end 119.126 -13.7668)
		(stroke
			(width 0.254)
			(type default)
		)
		(layer "In3.Cu")
	)
	(gr_line
		(start 119.126 -11.2014)
		(end 119.126 -13.7668)
		(stroke
			(width 0.1778)
			(type default)
		)
		(layer "In3.Cu")
	)
	(gr_line
		(start 119.126 -9.56691)
		(end 117.983 -9.56691)
		(stroke
			(width 0.254)
			(type default)
		)
		(layer "In3.Cu")
	)
	(gr_line
		(start 119.126 -9.56691)
		(end 118.8974 -9.56691)
		(stroke
			(width 0.1778)
			(type default)
		)
		(layer "In3.Cu")
	)
	(gr_line
		(start 119.126 -7.02691)
		(end 119.126 -9.56691)
		(stroke
			(width 0.254)
			(type default)
		)
		(layer "In3.Cu")
	)
	(gr_line
		(start 119.126 -7.00151)
		(end 119.126 -9.56691)
		(stroke
			(width 0.1778)
			(type default)
		)
		(layer "In3.Cu")
	)
	(gr_line
		(start 119.1514 -13.7922)
		(end 117.9322 -13.7922)
		(stroke
			(width 0.1778)
			(type default)
		)
		(layer "In3.Cu")
	)
	(gr_line
		(start 119.1514 -13.7922)
		(end 118.9228 -13.7922)
		(stroke
			(width 0.127)
			(type default)
		)
		(layer "In3.Cu")
	)
	(gr_line
		(start 119.1514 -11.176)
		(end 119.1514 -13.7922)
		(stroke
			(width 0.127)
			(type default)
		)
		(layer "In3.Cu")
	)
	(gr_line
		(start 119.1514 -11.176)
		(end 119.1514 -13.7922)
		(stroke
			(width 0.1778)
			(type default)
		)
		(layer "In3.Cu")
	)
	(gr_line
		(start 119.1514 -9.59231)
		(end 117.9322 -9.59231)
		(stroke
			(width 0.1778)
			(type default)
		)
		(layer "In3.Cu")
	)
	(gr_line
		(start 119.1514 -9.59231)
		(end 118.9228 -9.59231)
		(stroke
			(width 0.127)
			(type default)
		)
		(layer "In3.Cu")
	)
	(gr_line
		(start 119.1514 -6.97611)
		(end 119.1514 -9.59231)
		(stroke
			(width 0.127)
			(type default)
		)
		(layer "In3.Cu")
	)
	(gr_line
		(start 119.1514 -6.97611)
		(end 119.1514 -9.59231)
		(stroke
			(width 0.1778)
			(type default)
		)
		(layer "In3.Cu")
	)
	(gr_line
		(start 119.1768 -13.8176)
		(end 117.9068 -13.8176)
		(stroke
			(width 0.127)
			(type default)
		)
		(layer "In3.Cu")
	)
	(gr_line
		(start 119.1768 -11.1506)
		(end 119.1768 -13.8176)
		(stroke
			(width 0.127)
			(type default)
		)
		(layer "In3.Cu")
	)
	(gr_line
		(start 119.1768 -9.61771)
		(end 117.9068 -9.61771)
		(stroke
			(width 0.127)
			(type default)
		)
		(layer "In3.Cu")
	)
	(gr_line
		(start 119.1768 -6.95071)
		(end 119.1768 -9.61771)
		(stroke
			(width 0.127)
			(type default)
		)
		(layer "In3.Cu")
	)
	(gr_line
		(start 119.2022 -13.843)
		(end 119.2022 -11.1252)
		(stroke
			(width 0.1016)
			(type default)
		)
		(layer "In3.Cu")
	)
	(gr_line
		(start 119.2022 -11.1252)
		(end 117.856 -11.1252)
		(stroke
			(width 0.1016)
			(type default)
		)
		(layer "In3.Cu")
	)
	(gr_line
		(start 119.2022 -9.64311)
		(end 119.2022 -6.92531)
		(stroke
			(width 0.1016)
			(type default)
		)
		(layer "In3.Cu")
	)
	(gr_line
		(start 119.2022 -6.92531)
		(end 117.856 -6.92531)
		(stroke
			(width 0.1016)
			(type default)
		)
		(layer "In3.Cu")
	)
	(gr_line
		(start 127.85598 -12.543028)
		(end 128.69418 -12.543028)
		(stroke
			(width 0.1016)
			(type default)
		)
		(layer "In3.Cu")
	)
	(gr_line
		(start 127.85598 -9.825228)
		(end 127.85598 -12.543028)
		(stroke
			(width 0.1016)
			(type default)
		)
		(layer "In3.Cu")
	)
	(gr_line
		(start 127.85598 -8.343138)
		(end 128.69418 -8.343138)
		(stroke
			(width 0.1016)
			(type default)
		)
		(layer "In3.Cu")
	)
	(gr_line
		(start 127.85598 -5.625338)
		(end 127.85598 -8.343138)
		(stroke
			(width 0.1016)
			(type default)
		)
		(layer "In3.Cu")
	)
	(gr_line
		(start 127.88138 -12.517628)
		(end 127.88138 -9.850628)
		(stroke
			(width 0.127)
			(type default)
		)
		(layer "In3.Cu")
	)
	(gr_line
		(start 127.88138 -9.850628)
		(end 129.17678 -9.850628)
		(stroke
			(width 0.127)
			(type default)
		)
		(layer "In3.Cu")
	)
	(gr_line
		(start 127.88138 -8.317738)
		(end 127.88138 -5.650738)
		(stroke
			(width 0.127)
			(type default)
		)
		(layer "In3.Cu")
	)
	(gr_line
		(start 127.88138 -5.650738)
		(end 129.17678 -5.650738)
		(stroke
			(width 0.127)
			(type default)
		)
		(layer "In3.Cu")
	)
	(gr_line
		(start 127.90678 -12.517628)
		(end 127.90678 -9.876028)
		(stroke
			(width 0.127)
			(type default)
		)
		(layer "In3.Cu")
	)
	(gr_line
		(start 127.90678 -12.492228)
		(end 127.90678 -9.876028)
		(stroke
			(width 0.1778)
			(type default)
		)
		(layer "In3.Cu")
	)
	(gr_line
		(start 127.90678 -9.876028)
		(end 129.15138 -9.876028)
		(stroke
			(width 0.127)
			(type default)
		)
		(layer "In3.Cu")
	)
	(gr_line
		(start 127.90678 -9.876028)
		(end 129.15138 -9.876028)
		(stroke
			(width 0.1778)
			(type default)
		)
		(layer "In3.Cu")
	)
	(gr_line
		(start 127.90678 -8.317738)
		(end 127.90678 -5.676138)
		(stroke
			(width 0.127)
			(type default)
		)
		(layer "In3.Cu")
	)
	(gr_line
		(start 127.90678 -8.292338)
		(end 127.90678 -5.676138)
		(stroke
			(width 0.1778)
			(type default)
		)
		(layer "In3.Cu")
	)
	(gr_line
		(start 127.90678 -5.676138)
		(end 129.15138 -5.676138)
		(stroke
			(width 0.127)
			(type default)
		)
		(layer "In3.Cu")
	)
	(gr_line
		(start 127.90678 -5.676138)
		(end 129.15138 -5.676138)
		(stroke
			(width 0.1778)
			(type default)
		)
		(layer "In3.Cu")
	)
	(gr_line
		(start 127.93218 -12.492228)
		(end 127.93218 -9.901428)
		(stroke
			(width 0.1778)
			(type default)
		)
		(layer "In3.Cu")
	)
	(gr_line
		(start 127.93218 -9.901428)
		(end 129.12598 -9.901428)
		(stroke
			(width 0.1778)
			(type default)
		)
		(layer "In3.Cu")
	)
	(gr_line
		(start 127.93218 -8.292338)
		(end 127.93218 -5.701538)
		(stroke
			(width 0.1778)
			(type default)
		)
		(layer "In3.Cu")
	)
	(gr_line
		(start 127.93218 -5.701538)
		(end 129.12598 -5.701538)
		(stroke
			(width 0.1778)
			(type default)
		)
		(layer "In3.Cu")
	)
	(gr_line
		(start 127.95758 -12.466828)
		(end 127.95758 -9.926828)
		(stroke
			(width 0.254)
			(type default)
		)
		(layer "In3.Cu")
	)
	(gr_line
		(start 127.95758 -9.926828)
		(end 129.12598 -9.926828)
		(stroke
			(width 0.254)
			(type default)
		)
		(layer "In3.Cu")
	)
	(gr_line
		(start 127.95758 -8.266938)
		(end 127.95758 -5.726938)
		(stroke
			(width 0.254)
			(type default)
		)
		(layer "In3.Cu")
	)
	(gr_line
		(start 127.95758 -5.726938)
		(end 129.12598 -5.726938)
		(stroke
			(width 0.254)
			(type default)
		)
		(layer "In3.Cu")
	)
	(gr_line
		(start 127.98298 -12.466828)
		(end 127.98298 -9.952228)
		(stroke
			(width 0.254)
			(type default)
		)
		(layer "In3.Cu")
	)
	(gr_line
		(start 127.98298 -9.952228)
		(end 129.10058 -9.952228)
		(stroke
			(width 0.254)
			(type default)
		)
		(layer "In3.Cu")
	)
	(gr_line
		(start 127.98298 -8.266938)
		(end 127.98298 -5.752338)
		(stroke
			(width 0.254)
			(type default)
		)
		(layer "In3.Cu")
	)
	(gr_line
		(start 127.98298 -5.752338)
		(end 129.10058 -5.752338)
		(stroke
			(width 0.254)
			(type default)
		)
		(layer "In3.Cu")
	)
	(gr_line
		(start 128.00838 -12.416028)
		(end 128.00838 -9.977628)
		(stroke
			(width 0.3556)
			(type default)
		)
		(layer "In3.Cu")
	)
	(gr_line
		(start 128.00838 -9.977628)
		(end 129.04978 -9.977628)
		(stroke
			(width 0.3556)
			(type default)
		)
		(layer "In3.Cu")
	)
	(gr_line
		(start 128.00838 -8.216138)
		(end 128.00838 -5.777738)
		(stroke
			(width 0.3556)
			(type default)
		)
		(layer "In3.Cu")
	)
	(gr_line
		(start 128.00838 -5.777738)
		(end 129.04978 -5.777738)
		(stroke
			(width 0.3556)
			(type default)
		)
		(layer "In3.Cu")
	)
	(gr_line
		(start 128.05918 -12.390628)
		(end 128.05918 -10.028428)
		(stroke
			(width 0.381)
			(type default)
		)
		(layer "In3.Cu")
	)
	(gr_line
		(start 128.05918 -10.028428)
		(end 128.99898 -10.028428)
		(stroke
			(width 0.381)
			(type default)
		)
		(layer "In3.Cu")
	)
	(gr_line
		(start 128.05918 -8.190738)
		(end 128.05918 -5.828538)
		(stroke
			(width 0.381)
			(type default)
		)
		(layer "In3.Cu")
	)
	(gr_line
		(start 128.05918 -5.828538)
		(end 128.99898 -5.828538)
		(stroke
			(width 0.381)
			(type default)
		)
		(layer "In3.Cu")
	)
	(gr_line
		(start 128.13538 -12.339828)
		(end 128.13538 -10.079228)
		(stroke
			(width 0.381)
			(type default)
		)
		(layer "In3.Cu")
	)
	(gr_line
		(start 128.13538 -10.079228)
		(end 128.94818 -10.079228)
		(stroke
			(width 0.381)
			(type default)
		)
		(layer "In3.Cu")
	)
	(gr_line
		(start 128.13538 -8.139938)
		(end 128.13538 -5.879338)
		(stroke
			(width 0.381)
			(type default)
		)
		(layer "In3.Cu")
	)
	(gr_line
		(start 128.13538 -5.879338)
		(end 128.94818 -5.879338)
		(stroke
			(width 0.381)
			(type default)
		)
		(layer "In3.Cu")
	)
	(gr_line
		(start 128.16078 -12.263628)
		(end 128.16078 -10.079228)
		(stroke
			(width 0.508)
			(type default)
		)
		(layer "In3.Cu")
	)
	(gr_line
		(start 128.16078 -10.079228)
		(end 128.92278 -10.079228)
		(stroke
			(width 0.508)
			(type default)
		)
		(layer "In3.Cu")
	)
	(gr_line
		(start 128.16078 -8.063738)
		(end 128.16078 -5.879338)
		(stroke
			(width 0.508)
			(type default)
		)
		(layer "In3.Cu")
	)
	(gr_line
		(start 128.16078 -5.879338)
		(end 128.92278 -5.879338)
		(stroke
			(width 0.508)
			(type default)
		)
		(layer "In3.Cu")
	)
	(gr_line
		(start 128.18618 -12.111228)
		(end 128.77038 -12.111228)
		(stroke
			(width 0.762)
			(type default)
		)
		(layer "In3.Cu")
	)
	(gr_line
		(start 128.18618 -10.282428)
		(end 128.77038 -10.282428)
		(stroke
			(width 0.762)
			(type default)
		)
		(layer "In3.Cu")
	)
	(gr_line
		(start 128.18618 -7.911338)
		(end 128.77038 -7.911338)
		(stroke
			(width 0.762)
			(type default)
		)
		(layer "In3.Cu")
	)
	(gr_line
		(start 128.18618 -6.082538)
		(end 128.77038 -6.082538)
		(stroke
			(width 0.762)
			(type default)
		)
		(layer "In3.Cu")
	)
	(gr_line
		(start 128.21158 -12.263628)
		(end 128.21158 -10.130028)
		(stroke
			(width 0.635)
			(type default)
		)
		(layer "In3.Cu")
	)
	(gr_line
		(start 128.21158 -12.212828)
		(end 128.21158 -10.180828)
		(stroke
			(width 0.762)
			(type default)
		)
		(layer "In3.Cu")
	)
	(gr_line
		(start 128.21158 -10.130028)
		(end 128.89738 -10.130028)
		(stroke
			(width 0.635)
			(type default)
		)
		(layer "In3.Cu")
	)
	(gr_line
		(start 128.21158 -8.063738)
		(end 128.21158 -5.930138)
		(stroke
			(width 0.635)
			(type default)
		)
		(layer "In3.Cu")
	)
	(gr_line
		(start 128.21158 -8.012938)
		(end 128.21158 -5.980938)
		(stroke
			(width 0.762)
			(type default)
		)
		(layer "In3.Cu")
	)
	(gr_line
		(start 128.21158 -5.930138)
		(end 128.89738 -5.930138)
		(stroke
			(width 0.635)
			(type default)
		)
		(layer "In3.Cu")
	)
	(gr_line
		(start 128.23698 -12.212828)
		(end 128.23698 -10.180828)
		(stroke
			(width 0.762)
			(type default)
		)
		(layer "In3.Cu")
	)
	(gr_line
		(start 128.23698 -10.180828)
		(end 128.82118 -10.180828)
		(stroke
			(width 0.762)
			(type default)
		)
		(layer "In3.Cu")
	)
	(gr_line
		(start 128.23698 -8.012938)
		(end 128.23698 -5.980938)
		(stroke
			(width 0.762)
			(type default)
		)
		(layer "In3.Cu")
	)
	(gr_line
		(start 128.23698 -5.980938)
		(end 128.82118 -5.980938)
		(stroke
			(width 0.762)
			(type default)
		)
		(layer "In3.Cu")
	)
	(gr_line
		(start 128.26238 -12.212828)
		(end 128.26238 -10.180828)
		(stroke
			(width 0.762)
			(type default)
		)
		(layer "In3.Cu")
	)
	(gr_line
		(start 128.26238 -12.212828)
		(end 128.84658 -12.212828)
		(stroke
			(width 0.762)
			(type default)
		)
		(layer "In3.Cu")
	)
	(gr_line
		(start 128.26238 -12.187428)
		(end 128.26238 -10.155428)
		(stroke
			(width 0.762)
			(type default)
		)
		(layer "In3.Cu")
	)
	(gr_line
		(start 128.26238 -8.012938)
		(end 128.26238 -5.980938)
		(stroke
			(width 0.762)
			(type default)
		)
		(layer "In3.Cu")
	)
	(gr_line
		(start 128.26238 -8.012938)
		(end 128.84658 -8.012938)
		(stroke
			(width 0.762)
			(type default)
		)
		(layer "In3.Cu")
	)
	(gr_line
		(start 128.26238 -7.987538)
		(end 128.26238 -5.955538)
		(stroke
			(width 0.762)
			(type default)
		)
		(layer "In3.Cu")
	)
	(gr_line
		(start 128.28778 -12.212828)
		(end 128.28778 -10.180828)
		(stroke
			(width 0.762)
			(type default)
		)
		(layer "In3.Cu")
	)
	(gr_line
		(start 128.28778 -8.012938)
		(end 128.28778 -5.980938)
		(stroke
			(width 0.762)
			(type default)
		)
		(layer "In3.Cu")
	)
	(gr_line
		(start 128.31318 -12.212828)
		(end 128.31318 -10.180828)
		(stroke
			(width 0.762)
			(type default)
		)
		(layer "In3.Cu")
	)
	(gr_line
		(start 128.31318 -8.012938)
		(end 128.31318 -5.980938)
		(stroke
			(width 0.762)
			(type default)
		)
		(layer "In3.Cu")
	)
	(gr_line
		(start 128.33858 -12.212828)
		(end 128.33858 -10.180828)
		(stroke
			(width 0.762)
			(type default)
		)
		(layer "In3.Cu")
	)
	(gr_line
		(start 128.33858 -8.012938)
		(end 128.33858 -5.980938)
		(stroke
			(width 0.762)
			(type default)
		)
		(layer "In3.Cu")
	)
	(gr_line
		(start 128.38938 -12.212828)
		(end 128.38938 -10.180828)
		(stroke
			(width 0.762)
			(type default)
		)
		(layer "In3.Cu")
	)
	(gr_line
		(start 128.38938 -8.012938)
		(end 128.38938 -5.980938)
		(stroke
			(width 0.762)
			(type default)
		)
		(layer "In3.Cu")
	)
	(gr_line
		(start 128.41478 -12.212828)
		(end 128.41478 -10.180828)
		(stroke
			(width 0.762)
			(type default)
		)
		(layer "In3.Cu")
	)
	(gr_line
		(start 128.41478 -8.012938)
		(end 128.41478 -5.980938)
		(stroke
			(width 0.762)
			(type default)
		)
		(layer "In3.Cu")
	)
	(gr_line
		(start 128.44018 -12.212828)
		(end 128.44018 -10.409428)
		(stroke
			(width 0.635)
			(type default)
		)
		(layer "In3.Cu")
	)
	(gr_line
		(start 128.44018 -10.409428)
		(end 128.54178 -10.409428)
		(stroke
			(width 0.635)
			(type default)
		)
		(layer "In3.Cu")
	)
	(gr_line
		(start 128.44018 -8.012938)
		(end 128.44018 -6.209538)
		(stroke
			(width 0.635)
			(type default)
		)
		(layer "In3.Cu")
	)
	(gr_line
		(start 128.44018 -6.209538)
		(end 128.54178 -6.209538)
		(stroke
			(width 0.635)
			(type default)
		)
		(layer "In3.Cu")
	)
	(gr_line
		(start 128.46558 -12.212828)
		(end 128.46558 -10.180828)
		(stroke
			(width 0.762)
			(type default)
		)
		(layer "In3.Cu")
	)
	(gr_line
		(start 128.46558 -12.187428)
		(end 128.46558 -10.155428)
		(stroke
			(width 0.762)
			(type default)
		)
		(layer "In3.Cu")
	)
	(gr_line
		(start 128.46558 -12.136628)
		(end 128.46558 -10.358628)
		(stroke
			(width 0.635)
			(type default)
		)
		(layer "In3.Cu")
	)
	(gr_line
		(start 128.46558 -8.012938)
		(end 128.46558 -5.980938)
		(stroke
			(width 0.762)
			(type default)
		)
		(layer "In3.Cu")
	)
	(gr_line
		(start 128.46558 -7.987538)
		(end 128.46558 -5.955538)
		(stroke
			(width 0.762)
			(type default)
		)
		(layer "In3.Cu")
	)
	(gr_line
		(start 128.46558 -7.936738)
		(end 128.46558 -6.158738)
		(stroke
			(width 0.635)
			(type default)
		)
		(layer "In3.Cu")
	)
	(gr_line
		(start 128.51638 -12.212828)
		(end 128.51638 -10.180828)
		(stroke
			(width 0.762)
			(type default)
		)
		(layer "In3.Cu")
	)
	(gr_line
		(start 128.51638 -8.012938)
		(end 128.51638 -5.980938)
		(stroke
			(width 0.762)
			(type default)
		)
		(layer "In3.Cu")
	)
	(gr_line
		(start 128.54178 -12.212828)
		(end 128.54178 -10.180828)
		(stroke
			(width 0.762)
			(type default)
		)
		(layer "In3.Cu")
	)
	(gr_line
		(start 128.54178 -12.187428)
		(end 128.54178 -10.155428)
		(stroke
			(width 0.762)
			(type default)
		)
		(layer "In3.Cu")
	)
	(gr_line
		(start 128.54178 -12.136628)
		(end 128.46558 -12.136628)
		(stroke
			(width 0.635)
			(type default)
		)
		(layer "In3.Cu")
	)
	(gr_line
		(start 128.54178 -10.409428)
		(end 128.54178 -12.136628)
		(stroke
			(width 0.635)
			(type default)
		)
		(layer "In3.Cu")
	)
	(gr_line
		(start 128.54178 -8.012938)
		(end 128.54178 -5.980938)
		(stroke
			(width 0.762)
			(type default)
		)
		(layer "In3.Cu")
	)
	(gr_line
		(start 128.54178 -7.987538)
		(end 128.54178 -5.955538)
		(stroke
			(width 0.762)
			(type default)
		)
		(layer "In3.Cu")
	)
	(gr_line
		(start 128.54178 -7.936738)
		(end 128.46558 -7.936738)
		(stroke
			(width 0.635)
			(type default)
		)
		(layer "In3.Cu")
	)
	(gr_line
		(start 128.54178 -6.209538)
		(end 128.54178 -7.936738)
		(stroke
			(width 0.635)
			(type default)
		)
		(layer "In3.Cu")
	)
	(gr_line
		(start 128.59258 -12.187428)
		(end 128.59258 -10.155428)
		(stroke
			(width 0.762)
			(type default)
		)
		(layer "In3.Cu")
	)
	(gr_line
		(start 128.59258 -7.987538)
		(end 128.59258 -5.955538)
		(stroke
			(width 0.762)
			(type default)
		)
		(layer "In3.Cu")
	)
	(gr_line
		(start 128.61798 -12.187428)
		(end 128.61798 -10.155428)
		(stroke
			(width 0.762)
			(type default)
		)
		(layer "In3.Cu")
	)
	(gr_line
		(start 128.61798 -7.987538)
		(end 128.61798 -5.955538)
		(stroke
			(width 0.762)
			(type default)
		)
		(layer "In3.Cu")
	)
	(gr_line
		(start 128.66878 -12.212828)
		(end 128.66878 -10.180828)
		(stroke
			(width 0.762)
			(type default)
		)
		(layer "In3.Cu")
	)
	(gr_line
		(start 128.66878 -8.012938)
		(end 128.66878 -5.980938)
		(stroke
			(width 0.762)
			(type default)
		)
		(layer "In3.Cu")
	)
	(gr_line
		(start 128.69418 -12.543028)
		(end 129.20218 -12.543028)
		(stroke
			(width 0.1016)
			(type default)
		)
		(layer "In3.Cu")
	)
	(gr_line
		(start 128.69418 -12.187428)
		(end 128.69418 -10.155428)
		(stroke
			(width 0.762)
			(type default)
		)
		(layer "In3.Cu")
	)
	(gr_line
		(start 128.69418 -8.343138)
		(end 129.20218 -8.343138)
		(stroke
			(width 0.1016)
			(type default)
		)
		(layer "In3.Cu")
	)
	(gr_line
		(start 128.69418 -7.987538)
		(end 128.69418 -5.955538)
		(stroke
			(width 0.762)
			(type default)
		)
		(layer "In3.Cu")
	)
	(gr_line
		(start 128.74498 -12.212828)
		(end 128.74498 -10.180828)
		(stroke
			(width 0.762)
			(type default)
		)
		(layer "In3.Cu")
	)
	(gr_line
		(start 128.74498 -12.187428)
		(end 128.74498 -10.155428)
		(stroke
			(width 0.762)
			(type default)
		)
		(layer "In3.Cu")
	)
	(gr_line
		(start 128.74498 -8.012938)
		(end 128.74498 -5.980938)
		(stroke
			(width 0.762)
			(type default)
		)
		(layer "In3.Cu")
	)
	(gr_line
		(start 128.74498 -7.987538)
		(end 128.74498 -5.955538)
		(stroke
			(width 0.762)
			(type default)
		)
		(layer "In3.Cu")
	)
	(gr_line
		(start 128.77038 -12.187428)
		(end 128.77038 -10.155428)
		(stroke
			(width 0.762)
			(type default)
		)
		(layer "In3.Cu")
	)
	(gr_line
		(start 128.77038 -7.987538)
		(end 128.77038 -5.955538)
		(stroke
			(width 0.762)
			(type default)
		)
		(layer "In3.Cu")
	)
	(gr_line
		(start 128.79578 -12.263628)
		(end 128.16078 -12.263628)
		(stroke
			(width 0.508)
			(type default)
		)
		(layer "In3.Cu")
	)
	(gr_line
		(start 128.79578 -12.263628)
		(end 128.21158 -12.263628)
		(stroke
			(width 0.635)
			(type default)
		)
		(layer "In3.Cu")
	)
	(gr_line
		(start 128.79578 -8.063738)
		(end 128.16078 -8.063738)
		(stroke
			(width 0.508)
			(type default)
		)
		(layer "In3.Cu")
	)
	(gr_line
		(start 128.79578 -8.063738)
		(end 128.21158 -8.063738)
		(stroke
			(width 0.635)
			(type default)
		)
		(layer "In3.Cu")
	)
	(gr_line
		(start 128.82118 -12.187428)
		(end 128.82118 -10.155428)
		(stroke
			(width 0.762)
			(type default)
		)
		(layer "In3.Cu")
	)
	(gr_line
		(start 128.82118 -7.987538)
		(end 128.82118 -5.955538)
		(stroke
			(width 0.762)
			(type default)
		)
		(layer "In3.Cu")
	)
	(gr_line
		(start 128.84658 -12.416028)
		(end 128.00838 -12.416028)
		(stroke
			(width 0.3556)
			(type default)
		)
		(layer "In3.Cu")
	)
	(gr_line
		(start 128.84658 -12.390628)
		(end 128.05918 -12.390628)
		(stroke
			(width 0.381)
			(type default)
		)
		(layer "In3.Cu")
	)
	(gr_line
		(start 128.84658 -8.216138)
		(end 128.00838 -8.216138)
		(stroke
			(width 0.3556)
			(type default)
		)
		(layer "In3.Cu")
	)
	(gr_line
		(start 128.84658 -8.190738)
		(end 128.05918 -8.190738)
		(stroke
			(width 0.381)
			(type default)
		)
		(layer "In3.Cu")
	)
	(gr_line
		(start 128.87198 -12.212828)
		(end 128.87198 -10.180828)
		(stroke
			(width 0.762)
			(type default)
		)
		(layer "In3.Cu")
	)
	(gr_line
		(start 128.87198 -8.012938)
		(end 128.87198 -5.980938)
		(stroke
			(width 0.762)
			(type default)
		)
		(layer "In3.Cu")
	)
	(gr_line
		(start 128.89738 -12.466828)
		(end 127.95758 -12.466828)
		(stroke
			(width 0.254)
			(type default)
		)
		(layer "In3.Cu")
	)
	(gr_line
		(start 128.89738 -12.212828)
		(end 128.44018 -12.212828)
		(stroke
			(width 0.635)
			(type default)
		)
		(layer "In3.Cu")
	)
	(gr_line
		(start 128.89738 -10.130028)
		(end 128.89738 -12.212828)
		(stroke
			(width 0.635)
			(type default)
		)
		(layer "In3.Cu")
	)
	(gr_line
		(start 128.89738 -8.266938)
		(end 127.95758 -8.266938)
		(stroke
			(width 0.254)
			(type default)
		)
		(layer "In3.Cu")
	)
	(gr_line
		(start 128.89738 -8.012938)
		(end 128.44018 -8.012938)
		(stroke
			(width 0.635)
			(type default)
		)
		(layer "In3.Cu")
	)
	(gr_line
		(start 128.89738 -5.930138)
		(end 128.89738 -8.012938)
		(stroke
			(width 0.635)
			(type default)
		)
		(layer "In3.Cu")
	)
	(gr_line
		(start 128.92278 -12.492228)
		(end 127.90678 -12.492228)
		(stroke
			(width 0.1778)
			(type default)
		)
		(layer "In3.Cu")
	)
	(gr_line
		(start 128.92278 -12.263628)
		(end 128.79578 -12.263628)
		(stroke
			(width 0.508)
			(type default)
		)
		(layer "In3.Cu")
	)
	(gr_line
		(start 128.92278 -10.079228)
		(end 128.92278 -12.263628)
		(stroke
			(width 0.508)
			(type default)
		)
		(layer "In3.Cu")
	)
	(gr_line
		(start 128.92278 -8.292338)
		(end 127.90678 -8.292338)
		(stroke
			(width 0.1778)
			(type default)
		)
		(layer "In3.Cu")
	)
	(gr_line
		(start 128.92278 -8.063738)
		(end 128.79578 -8.063738)
		(stroke
			(width 0.508)
			(type default)
		)
		(layer "In3.Cu")
	)
	(gr_line
		(start 128.92278 -5.879338)
		(end 128.92278 -8.063738)
		(stroke
			(width 0.508)
			(type default)
		)
		(layer "In3.Cu")
	)
	(gr_line
		(start 128.94818 -12.263628)
		(end 128.79578 -12.263628)
		(stroke
			(width 0.381)
			(type default)
		)
		(layer "In3.Cu")
	)
	(gr_line
		(start 128.94818 -10.079228)
		(end 128.94818 -12.263628)
		(stroke
			(width 0.381)
			(type default)
		)
		(layer "In3.Cu")
	)
	(gr_line
		(start 128.94818 -8.063738)
		(end 128.79578 -8.063738)
		(stroke
			(width 0.381)
			(type default)
		)
		(layer "In3.Cu")
	)
	(gr_line
		(start 128.94818 -5.879338)
		(end 128.94818 -8.063738)
		(stroke
			(width 0.381)
			(type default)
		)
		(layer "In3.Cu")
	)
	(gr_line
		(start 128.99898 -12.339828)
		(end 128.13538 -12.339828)
		(stroke
			(width 0.381)
			(type default)
		)
		(layer "In3.Cu")
	)
	(gr_line
		(start 128.99898 -10.028428)
		(end 128.99898 -12.339828)
		(stroke
			(width 0.381)
			(type default)
		)
		(layer "In3.Cu")
	)
	(gr_line
		(start 128.99898 -8.139938)
		(end 128.13538 -8.139938)
		(stroke
			(width 0.381)
			(type default)
		)
		(layer "In3.Cu")
	)
	(gr_line
		(start 128.99898 -5.828538)
		(end 128.99898 -8.139938)
		(stroke
			(width 0.381)
			(type default)
		)
		(layer "In3.Cu")
	)
	(gr_line
		(start 129.04978 -12.390628)
		(end 128.84658 -12.390628)
		(stroke
			(width 0.3556)
			(type default)
		)
		(layer "In3.Cu")
	)
	(gr_line
		(start 129.04978 -9.977628)
		(end 129.04978 -12.390628)
		(stroke
			(width 0.3556)
			(type default)
		)
		(layer "In3.Cu")
	)
	(gr_line
		(start 129.04978 -8.190738)
		(end 128.84658 -8.190738)
		(stroke
			(width 0.3556)
			(type default)
		)
		(layer "In3.Cu")
	)
	(gr_line
		(start 129.04978 -5.777738)
		(end 129.04978 -8.190738)
		(stroke
			(width 0.3556)
			(type default)
		)
		(layer "In3.Cu")
	)
	(gr_line
		(start 129.07518 -12.517628)
		(end 127.88138 -12.517628)
		(stroke
			(width 0.127)
			(type default)
		)
		(layer "In3.Cu")
	)
	(gr_line
		(start 129.07518 -8.317738)
		(end 127.88138 -8.317738)
		(stroke
			(width 0.127)
			(type default)
		)
		(layer "In3.Cu")
	)
	(gr_line
		(start 129.10058 -12.416028)
		(end 128.84658 -12.416028)
		(stroke
			(width 0.254)
			(type default)
		)
		(layer "In3.Cu")
	)
	(gr_line
		(start 129.10058 -9.952228)
		(end 129.10058 -12.416028)
		(stroke
			(width 0.254)
			(type default)
		)
		(layer "In3.Cu")
	)
	(gr_line
		(start 129.10058 -8.216138)
		(end 128.84658 -8.216138)
		(stroke
			(width 0.254)
			(type default)
		)
		(layer "In3.Cu")
	)
	(gr_line
		(start 129.10058 -5.752338)
		(end 129.10058 -8.216138)
		(stroke
			(width 0.254)
			(type default)
		)
		(layer "In3.Cu")
	)
	(gr_line
		(start 129.12598 -12.466828)
		(end 127.98298 -12.466828)
		(stroke
			(width 0.254)
			(type default)
		)
		(layer "In3.Cu")
	)
	(gr_line
		(start 129.12598 -12.466828)
		(end 128.89738 -12.466828)
		(stroke
			(width 0.1778)
			(type default)
		)
		(layer "In3.Cu")
	)
	(gr_line
		(start 129.12598 -9.926828)
		(end 129.12598 -12.466828)
		(stroke
			(width 0.254)
			(type default)
		)
		(layer "In3.Cu")
	)
	(gr_line
		(start 129.12598 -9.901428)
		(end 129.12598 -12.466828)
		(stroke
			(width 0.1778)
			(type default)
		)
		(layer "In3.Cu")
	)
	(gr_line
		(start 129.12598 -8.266938)
		(end 127.98298 -8.266938)
		(stroke
			(width 0.254)
			(type default)
		)
		(layer "In3.Cu")
	)
	(gr_line
		(start 129.12598 -8.266938)
		(end 128.89738 -8.266938)
		(stroke
			(width 0.1778)
			(type default)
		)
		(layer "In3.Cu")
	)
	(gr_line
		(start 129.12598 -5.726938)
		(end 129.12598 -8.266938)
		(stroke
			(width 0.254)
			(type default)
		)
		(layer "In3.Cu")
	)
	(gr_line
		(start 129.12598 -5.701538)
		(end 129.12598 -8.266938)
		(stroke
			(width 0.1778)
			(type default)
		)
		(layer "In3.Cu")
	)
	(gr_line
		(start 129.15138 -12.492228)
		(end 127.93218 -12.492228)
		(stroke
			(width 0.1778)
			(type default)
		)
		(layer "In3.Cu")
	)
	(gr_line
		(start 129.15138 -12.492228)
		(end 128.92278 -12.492228)
		(stroke
			(width 0.127)
			(type default)
		)
		(layer "In3.Cu")
	)
	(gr_line
		(start 129.15138 -9.876028)
		(end 129.15138 -12.492228)
		(stroke
			(width 0.127)
			(type default)
		)
		(layer "In3.Cu")
	)
	(gr_line
		(start 129.15138 -9.876028)
		(end 129.15138 -12.492228)
		(stroke
			(width 0.1778)
			(type default)
		)
		(layer "In3.Cu")
	)
	(gr_line
		(start 129.15138 -8.292338)
		(end 127.93218 -8.292338)
		(stroke
			(width 0.1778)
			(type default)
		)
		(layer "In3.Cu")
	)
	(gr_line
		(start 129.15138 -8.292338)
		(end 128.92278 -8.292338)
		(stroke
			(width 0.127)
			(type default)
		)
		(layer "In3.Cu")
	)
	(gr_line
		(start 129.15138 -5.676138)
		(end 129.15138 -8.292338)
		(stroke
			(width 0.127)
			(type default)
		)
		(layer "In3.Cu")
	)
	(gr_line
		(start 129.15138 -5.676138)
		(end 129.15138 -8.292338)
		(stroke
			(width 0.1778)
			(type default)
		)
		(layer "In3.Cu")
	)
	(gr_line
		(start 129.17678 -12.517628)
		(end 127.90678 -12.517628)
		(stroke
			(width 0.127)
			(type default)
		)
		(layer "In3.Cu")
	)
	(gr_line
		(start 129.17678 -9.850628)
		(end 129.17678 -12.517628)
		(stroke
			(width 0.127)
			(type default)
		)
		(layer "In3.Cu")
	)
	(gr_line
		(start 129.17678 -8.317738)
		(end 127.90678 -8.317738)
		(stroke
			(width 0.127)
			(type default)
		)
		(layer "In3.Cu")
	)
	(gr_line
		(start 129.17678 -5.650738)
		(end 129.17678 -8.317738)
		(stroke
			(width 0.127)
			(type default)
		)
		(layer "In3.Cu")
	)
	(gr_line
		(start 129.20218 -12.543028)
		(end 129.20218 -9.825228)
		(stroke
			(width 0.1016)
			(type default)
		)
		(layer "In3.Cu")
	)
	(gr_line
		(start 129.20218 -9.825228)
		(end 127.85598 -9.825228)
		(stroke
			(width 0.1016)
			(type default)
		)
		(layer "In3.Cu")
	)
	(gr_line
		(start 129.20218 -8.343138)
		(end 129.20218 -5.625338)
		(stroke
			(width 0.1016)
			(type default)
		)
		(layer "In3.Cu")
	)
	(gr_line
		(start 129.20218 -5.625338)
		(end 127.85598 -5.625338)
		(stroke
			(width 0.1016)
			(type default)
		)
		(layer "In3.Cu")
	)
	(gr_line
		(start 132.9182 -3.95732)
		(end 132.9182 -5.22732)
		(stroke
			(width 1.016)
			(type default)
		)
		(layer "In3.Cu")
	)
	(gr_arc
		(start 132.990082 -52.319936)
		(mid 133.697187 -52.027043)
		(end 133.99008 -51.319938)
		(stroke
			(width 2.032)
			(type default)
		)
		(layer "In3.Cu")
	)
	(gr_line
		(start 133.99008 -51.319938)
		(end 133.99008 -50.8)
		(stroke
			(width 2.032)
			(type default)
		)
		(layer "In3.Cu")
	)
	(gr_arc
		(start 134.990078 -49.800002)
		(mid 134.282987 -50.092902)
		(end 133.99008 -50.8)
		(stroke
			(width 2.032)
			(type default)
		)
		(layer "In3.Cu")
	)
	(gr_line
		(start 134.990078 -49.800002)
		(end 149.990048 -49.800002)
		(stroke
			(width 2.032)
			(type default)
		)
		(layer "In3.Cu")
	)
	(gr_line
		(start 139.4968 -11.3792)
		(end 139.4968 -9.1948)
		(stroke
			(width 0.254)
			(type default)
		)
		(layer "In3.Cu")
	)
	(gr_line
		(start 139.4968 -9.1948)
		(end 141.0716 -9.1948)
		(stroke
			(width 0.254)
			(type default)
		)
		(layer "In3.Cu")
	)
	(gr_line
		(start 139.5222 -11.3792)
		(end 139.5222 -9.2456)
		(stroke
			(width 0.254)
			(type default)
		)
		(layer "In3.Cu")
	)
	(gr_line
		(start 139.5222 -9.2456)
		(end 141.0462 -9.2456)
		(stroke
			(width 0.254)
			(type default)
		)
		(layer "In3.Cu")
	)
	(gr_line
		(start 139.573 -11.3538)
		(end 139.573 -9.3726)
		(stroke
			(width 0.254)
			(type default)
		)
		(layer "In3.Cu")
	)
	(gr_line
		(start 139.573 -9.3726)
		(end 141.0208 -9.3726)
		(stroke
			(width 0.254)
			(type default)
		)
		(layer "In3.Cu")
	)
	(gr_line
		(start 139.627102 -11.303)
		(end 139.931902 -11.303)
		(stroke
			(width 0.1016)
			(type default)
		)
		(layer "In3.Cu")
	)
	(gr_line
		(start 139.627102 -9.2964)
		(end 139.627102 -11.303)
		(stroke
			(width 0.1016)
			(type default)
		)
		(layer "In3.Cu")
	)
	(gr_line
		(start 139.677902 -11.2268)
		(end 140.770102 -11.2268)
		(stroke
			(width 0.2032)
			(type default)
		)
		(layer "In3.Cu")
	)
	(gr_line
		(start 139.677902 -9.3726)
		(end 139.677902 -11.2268)
		(stroke
			(width 0.2032)
			(type default)
		)
		(layer "In3.Cu")
	)
	(gr_line
		(start 139.703302 -11.2268)
		(end 140.871702 -11.2268)
		(stroke
			(width 0.2032)
			(type default)
		)
		(layer "In3.Cu")
	)
	(gr_line
		(start 139.703302 -9.4234)
		(end 139.703302 -11.2268)
		(stroke
			(width 0.2032)
			(type default)
		)
		(layer "In3.Cu")
	)
	(gr_line
		(start 139.7508 -11.1252)
		(end 139.7508 -9.5758)
		(stroke
			(width 0.762)
			(type default)
		)
		(layer "In3.Cu")
	)
	(gr_line
		(start 139.7508 -11.1252)
		(end 140.6652 -11.1252)
		(stroke
			(width 0.762)
			(type default)
		)
		(layer "In3.Cu")
	)
	(gr_line
		(start 139.7508 -11.0998)
		(end 139.7508 -9.5504)
		(stroke
			(width 0.762)
			(type default)
		)
		(layer "In3.Cu")
	)
	(gr_line
		(start 139.7508 -10.9982)
		(end 139.7508 -9.4488)
		(stroke
			(width 0.762)
			(type default)
		)
		(layer "In3.Cu")
	)
	(gr_line
		(start 139.7508 -9.4488)
		(end 140.6652 -9.4488)
		(stroke
			(width 0.762)
			(type default)
		)
		(layer "In3.Cu")
	)
	(gr_line
		(start 139.754102 -11.176)
		(end 140.846302 -11.176)
		(stroke
			(width 0.2032)
			(type default)
		)
		(layer "In3.Cu")
	)
	(gr_line
		(start 139.754102 -9.4742)
		(end 139.754102 -11.176)
		(stroke
			(width 0.2032)
			(type default)
		)
		(layer "In3.Cu")
	)
	(gr_line
		(start 139.7762 -10.9982)
		(end 140.6906 -10.9982)
		(stroke
			(width 0.762)
			(type default)
		)
		(layer "In3.Cu")
	)
	(gr_line
		(start 139.7762 -9.5758)
		(end 140.6906 -9.5758)
		(stroke
			(width 0.762)
			(type default)
		)
		(layer "In3.Cu")
	)
	(gr_line
		(start 139.855702 -11.0744)
		(end 140.643102 -11.0744)
		(stroke
			(width 0.508)
			(type default)
		)
		(layer "In3.Cu")
	)
	(gr_line
		(start 139.855702 -11.049)
		(end 139.855702 -9.525)
		(stroke
			(width 0.508)
			(type default)
		)
		(layer "In3.Cu")
	)
	(gr_line
		(start 139.881102 -11.0744)
		(end 139.881102 -9.5504)
		(stroke
			(width 0.508)
			(type default)
		)
		(layer "In3.Cu")
	)
	(gr_line
		(start 139.9032 -11.1252)
		(end 140.8176 -11.1252)
		(stroke
			(width 0.762)
			(type default)
		)
		(layer "In3.Cu")
	)
	(gr_line
		(start 139.9032 -9.4488)
		(end 140.8176 -9.4488)
		(stroke
			(width 0.762)
			(type default)
		)
		(layer "In3.Cu")
	)
	(gr_line
		(start 139.906502 -9.525)
		(end 140.643102 -9.525)
		(stroke
			(width 0.508)
			(type default)
		)
		(layer "In3.Cu")
	)
	(gr_line
		(start 139.931902 -11.303)
		(end 140.922502 -11.303)
		(stroke
			(width 0.1016)
			(type default)
		)
		(layer "In3.Cu")
	)
	(gr_line
		(start 139.931902 -11.0744)
		(end 139.931902 -9.5504)
		(stroke
			(width 0.508)
			(type default)
		)
		(layer "In3.Cu")
	)
	(gr_line
		(start 139.957302 -11.0744)
		(end 139.957302 -9.5504)
		(stroke
			(width 0.508)
			(type default)
		)
		(layer "In3.Cu")
	)
	(gr_line
		(start 139.982702 -11.0744)
		(end 139.982702 -9.5504)
		(stroke
			(width 0.508)
			(type default)
		)
		(layer "In3.Cu")
	)
	(gr_line
		(start 140.008102 -11.0744)
		(end 140.008102 -9.5504)
		(stroke
			(width 0.508)
			(type default)
		)
		(layer "In3.Cu")
	)
	(gr_line
		(start 140.008102 -11.049)
		(end 140.008102 -9.525)
		(stroke
			(width 0.508)
			(type default)
		)
		(layer "In3.Cu")
	)
	(gr_line
		(start 140.033502 -11.0744)
		(end 140.033502 -9.5504)
		(stroke
			(width 0.508)
			(type default)
		)
		(layer "In3.Cu")
	)
	(gr_line
		(start 140.058902 -11.0744)
		(end 140.058902 -9.5504)
		(stroke
			(width 0.508)
			(type default)
		)
		(layer "In3.Cu")
	)
	(gr_line
		(start 140.109702 -11.0744)
		(end 140.109702 -9.5504)
		(stroke
			(width 0.508)
			(type default)
		)
		(layer "In3.Cu")
	)
	(gr_line
		(start 140.109702 -11.049)
		(end 140.109702 -9.525)
		(stroke
			(width 0.508)
			(type default)
		)
		(layer "In3.Cu")
	)
	(gr_line
		(start 140.135102 -11.0744)
		(end 140.135102 -9.5504)
		(stroke
			(width 0.508)
			(type default)
		)
		(layer "In3.Cu")
	)
	(gr_line
		(start 140.160502 -11.0744)
		(end 140.160502 -9.5504)
		(stroke
			(width 0.508)
			(type default)
		)
		(layer "In3.Cu")
	)
	(gr_line
		(start 140.185902 -11.0744)
		(end 140.185902 -9.5504)
		(stroke
			(width 0.508)
			(type default)
		)
		(layer "In3.Cu")
	)
	(gr_line
		(start 140.236702 -11.0744)
		(end 140.236702 -9.5504)
		(stroke
			(width 0.508)
			(type default)
		)
		(layer "In3.Cu")
	)
	(gr_line
		(start 140.262102 -11.0744)
		(end 140.262102 -9.5504)
		(stroke
			(width 0.508)
			(type default)
		)
		(layer "In3.Cu")
	)
	(gr_line
		(start 140.262102 -11.049)
		(end 140.262102 -9.525)
		(stroke
			(width 0.508)
			(type default)
		)
		(layer "In3.Cu")
	)
	(gr_line
		(start 140.287502 -11.0744)
		(end 140.287502 -9.5504)
		(stroke
			(width 0.508)
			(type default)
		)
		(layer "In3.Cu")
	)
	(gr_line
		(start 140.312902 -11.0744)
		(end 140.312902 -9.5504)
		(stroke
			(width 0.508)
			(type default)
		)
		(layer "In3.Cu")
	)
	(gr_line
		(start 140.338302 -11.0744)
		(end 140.338302 -9.5504)
		(stroke
			(width 0.508)
			(type default)
		)
		(layer "In3.Cu")
	)
	(gr_line
		(start 140.338302 -11.049)
		(end 140.338302 -9.525)
		(stroke
			(width 0.508)
			(type default)
		)
		(layer "In3.Cu")
	)
	(gr_line
		(start 140.363702 -11.0744)
		(end 140.363702 -9.5504)
		(stroke
			(width 0.508)
			(type default)
		)
		(layer "In3.Cu")
	)
	(gr_line
		(start 140.389102 -11.0744)
		(end 140.389102 -9.5504)
		(stroke
			(width 0.508)
			(type default)
		)
		(layer "In3.Cu")
	)
	(gr_line
		(start 140.389102 -11.049)
		(end 140.389102 -9.525)
		(stroke
			(width 0.508)
			(type default)
		)
		(layer "In3.Cu")
	)
	(gr_line
		(start 140.414502 -11.0744)
		(end 140.414502 -9.5504)
		(stroke
			(width 0.508)
			(type default)
		)
		(layer "In3.Cu")
	)
	(gr_line
		(start 140.414502 -11.049)
		(end 140.414502 -9.525)
		(stroke
			(width 0.508)
			(type default)
		)
		(layer "In3.Cu")
	)
	(gr_line
		(start 140.439902 -11.049)
		(end 140.439902 -9.525)
		(stroke
			(width 0.508)
			(type default)
		)
		(layer "In3.Cu")
	)
	(gr_line
		(start 140.465302 -11.0744)
		(end 140.465302 -9.5504)
		(stroke
			(width 0.508)
			(type default)
		)
		(layer "In3.Cu")
	)
	(gr_line
		(start 140.4874 -11.3792)
		(end 139.4968 -11.3792)
		(stroke
			(width 0.254)
			(type default)
		)
		(layer "In3.Cu")
	)
	(gr_line
		(start 140.490702 -11.049)
		(end 140.490702 -9.525)
		(stroke
			(width 0.508)
			(type default)
		)
		(layer "In3.Cu")
	)
	(gr_line
		(start 140.516102 -11.049)
		(end 140.516102 -9.525)
		(stroke
			(width 0.508)
			(type default)
		)
		(layer "In3.Cu")
	)
	(gr_line
		(start 140.541502 -11.0744)
		(end 140.541502 -9.5504)
		(stroke
			(width 0.508)
			(type default)
		)
		(layer "In3.Cu")
	)
	(gr_line
		(start 140.566902 -11.0744)
		(end 140.566902 -9.5504)
		(stroke
			(width 0.508)
			(type default)
		)
		(layer "In3.Cu")
	)
	(gr_line
		(start 140.566902 -11.049)
		(end 140.566902 -9.525)
		(stroke
			(width 0.508)
			(type default)
		)
		(layer "In3.Cu")
	)
	(gr_line
		(start 140.617702 -11.0744)
		(end 140.617702 -9.5504)
		(stroke
			(width 0.508)
			(type default)
		)
		(layer "In3.Cu")
	)
	(gr_line
		(start 140.617702 -11.049)
		(end 140.617702 -9.525)
		(stroke
			(width 0.508)
			(type default)
		)
		(layer "In3.Cu")
	)
	(gr_line
		(start 140.668502 -11.0744)
		(end 140.668502 -9.5504)
		(stroke
			(width 0.508)
			(type default)
		)
		(layer "In3.Cu")
	)
	(gr_line
		(start 140.668502 -11.049)
		(end 140.668502 -9.525)
		(stroke
			(width 0.508)
			(type default)
		)
		(layer "In3.Cu")
	)
	(gr_line
		(start 140.6906 -11.0998)
		(end 140.6906 -9.5504)
		(stroke
			(width 0.762)
			(type default)
		)
		(layer "In3.Cu")
	)
	(gr_line
		(start 140.693902 -11.0744)
		(end 140.693902 -9.5504)
		(stroke
			(width 0.508)
			(type default)
		)
		(layer "In3.Cu")
	)
	(gr_line
		(start 140.719302 -11.0744)
		(end 140.719302 -9.5504)
		(stroke
			(width 0.508)
			(type default)
		)
		(layer "In3.Cu")
	)
	(gr_line
		(start 140.770102 -11.2268)
		(end 140.795502 -11.2268)
		(stroke
			(width 0.2032)
			(type default)
		)
		(layer "In3.Cu")
	)
	(gr_line
		(start 140.795502 -11.2268)
		(end 140.795502 -9.4742)
		(stroke
			(width 0.2032)
			(type default)
		)
		(layer "In3.Cu")
	)
	(gr_line
		(start 140.795502 -9.4742)
		(end 139.754102 -9.4742)
		(stroke
			(width 0.2032)
			(type default)
		)
		(layer "In3.Cu")
	)
	(gr_line
		(start 140.8176 -11.1252)
		(end 140.8176 -9.5758)
		(stroke
			(width 0.762)
			(type default)
		)
		(layer "In3.Cu")
	)
	(gr_line
		(start 140.8176 -11.0998)
		(end 140.8176 -9.6012)
		(stroke
			(width 0.762)
			(type default)
		)
		(layer "In3.Cu")
	)
	(gr_line
		(start 140.8176 -10.9982)
		(end 140.8176 -9.4488)
		(stroke
			(width 0.762)
			(type default)
		)
		(layer "In3.Cu")
	)
	(gr_line
		(start 140.846302 -11.176)
		(end 140.846302 -9.4234)
		(stroke
			(width 0.2032)
			(type default)
		)
		(layer "In3.Cu")
	)
	(gr_line
		(start 140.846302 -9.4234)
		(end 139.703302 -9.4234)
		(stroke
			(width 0.2032)
			(type default)
		)
		(layer "In3.Cu")
	)
	(gr_line
		(start 140.871702 -11.2268)
		(end 140.871702 -9.3726)
		(stroke
			(width 0.2032)
			(type default)
		)
		(layer "In3.Cu")
	)
	(gr_line
		(start 140.871702 -9.3726)
		(end 139.677902 -9.3726)
		(stroke
			(width 0.2032)
			(type default)
		)
		(layer "In3.Cu")
	)
	(gr_line
		(start 140.922502 -11.303)
		(end 140.922502 -9.2964)
		(stroke
			(width 0.1016)
			(type default)
		)
		(layer "In3.Cu")
	)
	(gr_line
		(start 140.922502 -9.2964)
		(end 139.627102 -9.2964)
		(stroke
			(width 0.1016)
			(type default)
		)
		(layer "In3.Cu")
	)
	(gr_line
		(start 141.0208 -11.2268)
		(end 140.770102 -11.2268)
		(stroke
			(width 0.254)
			(type default)
		)
		(layer "In3.Cu")
	)
	(gr_line
		(start 141.0208 -9.3726)
		(end 141.0208 -11.2268)
		(stroke
			(width 0.254)
			(type default)
		)
		(layer "In3.Cu")
	)
	(gr_line
		(start 141.0462 -11.3538)
		(end 139.573 -11.3538)
		(stroke
			(width 0.254)
			(type default)
		)
		(layer "In3.Cu")
	)
	(gr_line
		(start 141.0462 -9.2456)
		(end 141.0462 -11.3538)
		(stroke
			(width 0.254)
			(type default)
		)
		(layer "In3.Cu")
	)
	(gr_line
		(start 141.0716 -11.3792)
		(end 139.5222 -11.3792)
		(stroke
			(width 0.254)
			(type default)
		)
		(layer "In3.Cu")
	)
	(gr_line
		(start 141.0716 -9.1948)
		(end 141.0716 -11.3792)
		(stroke
			(width 0.254)
			(type default)
		)
		(layer "In3.Cu")
	)
	(gr_line
		(start 144.296892 -11.3792)
		(end 144.296892 -9.1948)
		(stroke
			(width 0.254)
			(type default)
		)
		(layer "In3.Cu")
	)
	(gr_line
		(start 144.296892 -9.1948)
		(end 145.871692 -9.1948)
		(stroke
			(width 0.254)
			(type default)
		)
		(layer "In3.Cu")
	)
	(gr_line
		(start 144.322292 -11.3792)
		(end 144.322292 -9.2456)
		(stroke
			(width 0.254)
			(type default)
		)
		(layer "In3.Cu")
	)
	(gr_line
		(start 144.322292 -9.2456)
		(end 145.846292 -9.2456)
		(stroke
			(width 0.254)
			(type default)
		)
		(layer "In3.Cu")
	)
	(gr_line
		(start 144.373092 -11.3538)
		(end 144.373092 -9.3726)
		(stroke
			(width 0.254)
			(type default)
		)
		(layer "In3.Cu")
	)
	(gr_line
		(start 144.373092 -9.3726)
		(end 145.820892 -9.3726)
		(stroke
			(width 0.254)
			(type default)
		)
		(layer "In3.Cu")
	)
	(gr_line
		(start 144.427194 -11.303)
		(end 144.731994 -11.303)
		(stroke
			(width 0.1016)
			(type default)
		)
		(layer "In3.Cu")
	)
	(gr_line
		(start 144.427194 -9.2964)
		(end 144.427194 -11.303)
		(stroke
			(width 0.1016)
			(type default)
		)
		(layer "In3.Cu")
	)
	(gr_line
		(start 144.455134 -5.715)
		(end 145.725134 -5.715)
		(stroke
			(width 1.016)
			(type default)
		)
		(layer "In3.Cu")
	)
	(gr_line
		(start 144.477994 -11.2268)
		(end 145.570194 -11.2268)
		(stroke
			(width 0.2032)
			(type default)
		)
		(layer "In3.Cu")
	)
	(gr_line
		(start 144.477994 -9.3726)
		(end 144.477994 -11.2268)
		(stroke
			(width 0.2032)
			(type default)
		)
		(layer "In3.Cu")
	)
	(gr_line
		(start 144.503394 -11.2268)
		(end 145.671794 -11.2268)
		(stroke
			(width 0.2032)
			(type default)
		)
		(layer "In3.Cu")
	)
	(gr_line
		(start 144.503394 -9.4234)
		(end 144.503394 -11.2268)
		(stroke
			(width 0.2032)
			(type default)
		)
		(layer "In3.Cu")
	)
	(gr_line
		(start 144.550892 -11.1252)
		(end 144.550892 -9.5758)
		(stroke
			(width 0.762)
			(type default)
		)
		(layer "In3.Cu")
	)
	(gr_line
		(start 144.550892 -11.1252)
		(end 145.465292 -11.1252)
		(stroke
			(width 0.762)
			(type default)
		)
		(layer "In3.Cu")
	)
	(gr_line
		(start 144.550892 -11.0998)
		(end 144.550892 -9.5504)
		(stroke
			(width 0.762)
			(type default)
		)
		(layer "In3.Cu")
	)
	(gr_line
		(start 144.550892 -10.9982)
		(end 144.550892 -9.4488)
		(stroke
			(width 0.762)
			(type default)
		)
		(layer "In3.Cu")
	)
	(gr_line
		(start 144.550892 -9.4488)
		(end 145.465292 -9.4488)
		(stroke
			(width 0.762)
			(type default)
		)
		(layer "In3.Cu")
	)
	(gr_line
		(start 144.554194 -11.176)
		(end 145.646394 -11.176)
		(stroke
			(width 0.2032)
			(type default)
		)
		(layer "In3.Cu")
	)
	(gr_line
		(start 144.554194 -9.4742)
		(end 144.554194 -11.176)
		(stroke
			(width 0.2032)
			(type default)
		)
		(layer "In3.Cu")
	)
	(gr_line
		(start 144.576292 -10.9982)
		(end 145.490692 -10.9982)
		(stroke
			(width 0.762)
			(type default)
		)
		(layer "In3.Cu")
	)
	(gr_line
		(start 144.576292 -9.5758)
		(end 145.490692 -9.5758)
		(stroke
			(width 0.762)
			(type default)
		)
		(layer "In3.Cu")
	)
	(gr_line
		(start 144.655794 -11.0744)
		(end 145.443194 -11.0744)
		(stroke
			(width 0.508)
			(type default)
		)
		(layer "In3.Cu")
	)
	(gr_line
		(start 144.655794 -11.049)
		(end 144.655794 -9.525)
		(stroke
			(width 0.508)
			(type default)
		)
		(layer "In3.Cu")
	)
	(gr_line
		(start 144.681194 -11.0744)
		(end 144.681194 -9.5504)
		(stroke
			(width 0.508)
			(type default)
		)
		(layer "In3.Cu")
	)
	(gr_line
		(start 144.703292 -11.1252)
		(end 145.617692 -11.1252)
		(stroke
			(width 0.762)
			(type default)
		)
		(layer "In3.Cu")
	)
	(gr_line
		(start 144.703292 -9.4488)
		(end 145.617692 -9.4488)
		(stroke
			(width 0.762)
			(type default)
		)
		(layer "In3.Cu")
	)
	(gr_line
		(start 144.706594 -9.525)
		(end 145.443194 -9.525)
		(stroke
			(width 0.508)
			(type default)
		)
		(layer "In3.Cu")
	)
	(gr_line
		(start 144.731994 -11.303)
		(end 145.722594 -11.303)
		(stroke
			(width 0.1016)
			(type default)
		)
		(layer "In3.Cu")
	)
	(gr_line
		(start 144.731994 -11.0744)
		(end 144.731994 -9.5504)
		(stroke
			(width 0.508)
			(type default)
		)
		(layer "In3.Cu")
	)
	(gr_line
		(start 144.757394 -11.0744)
		(end 144.757394 -9.5504)
		(stroke
			(width 0.508)
			(type default)
		)
		(layer "In3.Cu")
	)
	(gr_line
		(start 144.782794 -11.0744)
		(end 144.782794 -9.5504)
		(stroke
			(width 0.508)
			(type default)
		)
		(layer "In3.Cu")
	)
	(gr_line
		(start 144.808194 -11.0744)
		(end 144.808194 -9.5504)
		(stroke
			(width 0.508)
			(type default)
		)
		(layer "In3.Cu")
	)
	(gr_line
		(start 144.808194 -11.049)
		(end 144.808194 -9.525)
		(stroke
			(width 0.508)
			(type default)
		)
		(layer "In3.Cu")
	)
	(gr_line
		(start 144.833594 -11.0744)
		(end 144.833594 -9.5504)
		(stroke
			(width 0.508)
			(type default)
		)
		(layer "In3.Cu")
	)
	(gr_line
		(start 144.858994 -11.0744)
		(end 144.858994 -9.5504)
		(stroke
			(width 0.508)
			(type default)
		)
		(layer "In3.Cu")
	)
	(gr_line
		(start 144.909794 -11.0744)
		(end 144.909794 -9.5504)
		(stroke
			(width 0.508)
			(type default)
		)
		(layer "In3.Cu")
	)
	(gr_line
		(start 144.909794 -11.049)
		(end 144.909794 -9.525)
		(stroke
			(width 0.508)
			(type default)
		)
		(layer "In3.Cu")
	)
	(gr_line
		(start 144.935194 -11.0744)
		(end 144.935194 -9.5504)
		(stroke
			(width 0.508)
			(type default)
		)
		(layer "In3.Cu")
	)
	(gr_line
		(start 144.960594 -11.0744)
		(end 144.960594 -9.5504)
		(stroke
			(width 0.508)
			(type default)
		)
		(layer "In3.Cu")
	)
	(gr_line
		(start 144.985994 -11.0744)
		(end 144.985994 -9.5504)
		(stroke
			(width 0.508)
			(type default)
		)
		(layer "In3.Cu")
	)
	(gr_line
		(start 145.036794 -11.0744)
		(end 145.036794 -9.5504)
		(stroke
			(width 0.508)
			(type default)
		)
		(layer "In3.Cu")
	)
	(gr_line
		(start 145.062194 -11.0744)
		(end 145.062194 -9.5504)
		(stroke
			(width 0.508)
			(type default)
		)
		(layer "In3.Cu")
	)
	(gr_line
		(start 145.062194 -11.049)
		(end 145.062194 -9.525)
		(stroke
			(width 0.508)
			(type default)
		)
		(layer "In3.Cu")
	)
	(gr_line
		(start 145.087594 -11.0744)
		(end 145.087594 -9.5504)
		(stroke
			(width 0.508)
			(type default)
		)
		(layer "In3.Cu")
	)
	(gr_line
		(start 145.112994 -11.0744)
		(end 145.112994 -9.5504)
		(stroke
			(width 0.508)
			(type default)
		)
		(layer "In3.Cu")
	)
	(gr_line
		(start 145.138394 -11.0744)
		(end 145.138394 -9.5504)
		(stroke
			(width 0.508)
			(type default)
		)
		(layer "In3.Cu")
	)
	(gr_line
		(start 145.138394 -11.049)
		(end 145.138394 -9.525)
		(stroke
			(width 0.508)
			(type default)
		)
		(layer "In3.Cu")
	)
	(gr_line
		(start 145.163794 -11.0744)
		(end 145.163794 -9.5504)
		(stroke
			(width 0.508)
			(type default)
		)
		(layer "In3.Cu")
	)
	(gr_line
		(start 145.189194 -11.0744)
		(end 145.189194 -9.5504)
		(stroke
			(width 0.508)
			(type default)
		)
		(layer "In3.Cu")
	)
	(gr_line
		(start 145.189194 -11.049)
		(end 145.189194 -9.525)
		(stroke
			(width 0.508)
			(type default)
		)
		(layer "In3.Cu")
	)
	(gr_line
		(start 145.214594 -11.0744)
		(end 145.214594 -9.5504)
		(stroke
			(width 0.508)
			(type default)
		)
		(layer "In3.Cu")
	)
	(gr_line
		(start 145.214594 -11.049)
		(end 145.214594 -9.525)
		(stroke
			(width 0.508)
			(type default)
		)
		(layer "In3.Cu")
	)
	(gr_line
		(start 145.239994 -11.049)
		(end 145.239994 -9.525)
		(stroke
			(width 0.508)
			(type default)
		)
		(layer "In3.Cu")
	)
	(gr_line
		(start 145.265394 -11.0744)
		(end 145.265394 -9.5504)
		(stroke
			(width 0.508)
			(type default)
		)
		(layer "In3.Cu")
	)
	(gr_line
		(start 145.287492 -11.3792)
		(end 144.296892 -11.3792)
		(stroke
			(width 0.254)
			(type default)
		)
		(layer "In3.Cu")
	)
	(gr_line
		(start 145.290794 -11.049)
		(end 145.290794 -9.525)
		(stroke
			(width 0.508)
			(type default)
		)
		(layer "In3.Cu")
	)
	(gr_line
		(start 145.316194 -11.049)
		(end 145.316194 -9.525)
		(stroke
			(width 0.508)
			(type default)
		)
		(layer "In3.Cu")
	)
	(gr_line
		(start 145.341594 -11.0744)
		(end 145.341594 -9.5504)
		(stroke
			(width 0.508)
			(type default)
		)
		(layer "In3.Cu")
	)
	(gr_line
		(start 145.366994 -11.0744)
		(end 145.366994 -9.5504)
		(stroke
			(width 0.508)
			(type default)
		)
		(layer "In3.Cu")
	)
	(gr_line
		(start 145.366994 -11.049)
		(end 145.366994 -9.525)
		(stroke
			(width 0.508)
			(type default)
		)
		(layer "In3.Cu")
	)
	(gr_line
		(start 145.417794 -11.0744)
		(end 145.417794 -9.5504)
		(stroke
			(width 0.508)
			(type default)
		)
		(layer "In3.Cu")
	)
	(gr_line
		(start 145.417794 -11.049)
		(end 145.417794 -9.525)
		(stroke
			(width 0.508)
			(type default)
		)
		(layer "In3.Cu")
	)
	(gr_line
		(start 145.468594 -11.0744)
		(end 145.468594 -9.5504)
		(stroke
			(width 0.508)
			(type default)
		)
		(layer "In3.Cu")
	)
	(gr_line
		(start 145.468594 -11.049)
		(end 145.468594 -9.525)
		(stroke
			(width 0.508)
			(type default)
		)
		(layer "In3.Cu")
	)
	(gr_line
		(start 145.490692 -11.0998)
		(end 145.490692 -9.5504)
		(stroke
			(width 0.762)
			(type default)
		)
		(layer "In3.Cu")
	)
	(gr_line
		(start 145.493994 -11.0744)
		(end 145.493994 -9.5504)
		(stroke
			(width 0.508)
			(type default)
		)
		(layer "In3.Cu")
	)
	(gr_line
		(start 145.519394 -11.0744)
		(end 145.519394 -9.5504)
		(stroke
			(width 0.508)
			(type default)
		)
		(layer "In3.Cu")
	)
	(gr_line
		(start 145.570194 -11.2268)
		(end 145.595594 -11.2268)
		(stroke
			(width 0.2032)
			(type default)
		)
		(layer "In3.Cu")
	)
	(gr_line
		(start 145.595594 -11.2268)
		(end 145.595594 -9.4742)
		(stroke
			(width 0.2032)
			(type default)
		)
		(layer "In3.Cu")
	)
	(gr_line
		(start 145.595594 -9.4742)
		(end 144.554194 -9.4742)
		(stroke
			(width 0.2032)
			(type default)
		)
		(layer "In3.Cu")
	)
	(gr_line
		(start 145.617692 -11.1252)
		(end 145.617692 -9.5758)
		(stroke
			(width 0.762)
			(type default)
		)
		(layer "In3.Cu")
	)
	(gr_line
		(start 145.617692 -11.0998)
		(end 145.617692 -9.6012)
		(stroke
			(width 0.762)
			(type default)
		)
		(layer "In3.Cu")
	)
	(gr_line
		(start 145.617692 -10.9982)
		(end 145.617692 -9.4488)
		(stroke
			(width 0.762)
			(type default)
		)
		(layer "In3.Cu")
	)
	(gr_line
		(start 145.646394 -11.176)
		(end 145.646394 -9.4234)
		(stroke
			(width 0.2032)
			(type default)
		)
		(layer "In3.Cu")
	)
	(gr_line
		(start 145.646394 -9.4234)
		(end 144.503394 -9.4234)
		(stroke
			(width 0.2032)
			(type default)
		)
		(layer "In3.Cu")
	)
	(gr_line
		(start 145.671794 -11.2268)
		(end 145.671794 -9.3726)
		(stroke
			(width 0.2032)
			(type default)
		)
		(layer "In3.Cu")
	)
	(gr_line
		(start 145.671794 -9.3726)
		(end 144.477994 -9.3726)
		(stroke
			(width 0.2032)
			(type default)
		)
		(layer "In3.Cu")
	)
	(gr_line
		(start 145.722594 -11.303)
		(end 145.722594 -9.2964)
		(stroke
			(width 0.1016)
			(type default)
		)
		(layer "In3.Cu")
	)
	(gr_line
		(start 145.722594 -9.2964)
		(end 144.427194 -9.2964)
		(stroke
			(width 0.1016)
			(type default)
		)
		(layer "In3.Cu")
	)
	(gr_line
		(start 145.820892 -11.2268)
		(end 145.570194 -11.2268)
		(stroke
			(width 0.254)
			(type default)
		)
		(layer "In3.Cu")
	)
	(gr_line
		(start 145.820892 -9.3726)
		(end 145.820892 -11.2268)
		(stroke
			(width 0.254)
			(type default)
		)
		(layer "In3.Cu")
	)
	(gr_line
		(start 145.846292 -11.3538)
		(end 144.373092 -11.3538)
		(stroke
			(width 0.254)
			(type default)
		)
		(layer "In3.Cu")
	)
	(gr_line
		(start 145.846292 -9.2456)
		(end 145.846292 -11.3538)
		(stroke
			(width 0.254)
			(type default)
		)
		(layer "In3.Cu")
	)
	(gr_line
		(start 145.871692 -11.3792)
		(end 144.322292 -11.3792)
		(stroke
			(width 0.254)
			(type default)
		)
		(layer "In3.Cu")
	)
	(gr_line
		(start 145.871692 -9.1948)
		(end 145.871692 -11.3792)
		(stroke
			(width 0.254)
			(type default)
		)
		(layer "In3.Cu")
	)
	(gr_arc
		(start 150.990046 -51.319938)
		(mid 151.282939 -52.027043)
		(end 151.990044 -52.319936)
		(stroke
			(width 2.032)
			(type default)
		)
		(layer "In3.Cu")
	)
	(gr_arc
		(start 150.990046 -50.8)
		(mid 150.697156 -50.092878)
		(end 149.990048 -49.800002)
		(stroke
			(width 2.032)
			(type default)
		)
		(layer "In3.Cu")
	)
	(gr_line
		(start 150.990046 -50.8)
		(end 150.990046 -51.319938)
		(stroke
			(width 2.032)
			(type default)
		)
		(layer "In3.Cu")
	)
	(gr_line
		(start 151.990044 -52.319936)
		(end 158.99003 -52.319936)
		(stroke
			(width 2.032)
			(type default)
		)
		(layer "In3.Cu")
	)
	(gr_line
		(start 158.99003 -52.319936)
		(end 159.372554 -52.24399)
		(stroke
			(width 2.032)
			(type default)
		)
		(layer "In3.Cu")
	)
	(gr_line
		(start 159.372554 -52.24399)
		(end 159.697166 -52.027074)
		(stroke
			(width 2.032)
			(type default)
		)
		(layer "In3.Cu")
	)
	(gr_line
		(start 159.697166 -52.027074)
		(end 159.913828 -51.702716)
		(stroke
			(width 2.032)
			(type default)
		)
		(layer "In3.Cu")
	)
	(gr_line
		(start 159.913828 -51.702716)
		(end 159.982154 -51.376072)
		(stroke
			(width 2.032)
			(type default)
		)
		(layer "In3.Cu")
	)
	(gr_line
		(start 159.982154 -51.376072)
		(end 160.0708 -50.996088)
		(stroke
			(width 2.032)
			(type default)
		)
		(layer "In3.Cu")
	)
	(gr_line
		(start 160.0708 -50.996088)
		(end 160.288732 -50.677064)
		(stroke
			(width 2.032)
			(type default)
		)
		(layer "In3.Cu")
	)
	(gr_line
		(start 160.288732 -50.677064)
		(end 160.611058 -50.464466)
		(stroke
			(width 2.032)
			(type default)
		)
		(layer "In3.Cu")
	)
	(gr_line
		(start 160.611058 -50.464466)
		(end 160.990026 -50.390044)
		(stroke
			(width 2.032)
			(type default)
		)
		(layer "In3.Cu")
	)
	(gr_line
		(start 160.990026 -50.390044)
		(end 202.989942 -50.390044)
		(stroke
			(width 2.032)
			(type default)
		)
		(layer "In3.Cu")
	)
	(gr_line
		(start 164.2872 -13.8176)
		(end 165.0746 -13.8176)
		(stroke
			(width 0.1016)
			(type default)
		)
		(layer "In3.Cu")
	)
	(gr_line
		(start 164.2872 -13.7668)
		(end 164.2872 -11.1506)
		(stroke
			(width 0.1016)
			(type default)
		)
		(layer "In3.Cu")
	)
	(gr_line
		(start 164.2872 -11.1506)
		(end 164.2872 -13.8176)
		(stroke
			(width 0.1016)
			(type default)
		)
		(layer "In3.Cu")
	)
	(gr_line
		(start 164.2872 -11.1506)
		(end 165.481 -11.1506)
		(stroke
			(width 0.1016)
			(type default)
		)
		(layer "In3.Cu")
	)
	(gr_line
		(start 164.2872 -9.617456)
		(end 165.0746 -9.617456)
		(stroke
			(width 0.1016)
			(type default)
		)
		(layer "In3.Cu")
	)
	(gr_line
		(start 164.2872 -9.566656)
		(end 164.2872 -6.950456)
		(stroke
			(width 0.1016)
			(type default)
		)
		(layer "In3.Cu")
	)
	(gr_line
		(start 164.2872 -6.950456)
		(end 164.2872 -9.617456)
		(stroke
			(width 0.1016)
			(type default)
		)
		(layer "In3.Cu")
	)
	(gr_line
		(start 164.2872 -6.950456)
		(end 165.481 -6.950456)
		(stroke
			(width 0.1016)
			(type default)
		)
		(layer "In3.Cu")
	)
	(gr_line
		(start 164.2872 -5.417312)
		(end 165.0746 -5.417312)
		(stroke
			(width 0.1016)
			(type default)
		)
		(layer "In3.Cu")
	)
	(gr_line
		(start 164.2872 -5.366512)
		(end 164.2872 -2.750312)
		(stroke
			(width 0.1016)
			(type default)
		)
		(layer "In3.Cu")
	)
	(gr_line
		(start 164.2872 -2.750312)
		(end 164.2872 -5.417312)
		(stroke
			(width 0.1016)
			(type default)
		)
		(layer "In3.Cu")
	)
	(gr_line
		(start 164.2872 -2.750312)
		(end 165.481 -2.750312)
		(stroke
			(width 0.1016)
			(type default)
		)
		(layer "In3.Cu")
	)
	(gr_line
		(start 164.3126 -13.7668)
		(end 164.3126 -11.176)
		(stroke
			(width 0.1016)
			(type default)
		)
		(layer "In3.Cu")
	)
	(gr_line
		(start 164.3126 -11.176)
		(end 165.4556 -11.176)
		(stroke
			(width 0.1016)
			(type default)
		)
		(layer "In3.Cu")
	)
	(gr_line
		(start 164.3126 -9.566656)
		(end 164.3126 -6.975856)
		(stroke
			(width 0.1016)
			(type default)
		)
		(layer "In3.Cu")
	)
	(gr_line
		(start 164.3126 -6.975856)
		(end 165.4556 -6.975856)
		(stroke
			(width 0.1016)
			(type default)
		)
		(layer "In3.Cu")
	)
	(gr_line
		(start 164.3126 -5.366512)
		(end 164.3126 -2.775712)
		(stroke
			(width 0.1016)
			(type default)
		)
		(layer "In3.Cu")
	)
	(gr_line
		(start 164.3126 -2.775712)
		(end 165.4556 -2.775712)
		(stroke
			(width 0.1016)
			(type default)
		)
		(layer "In3.Cu")
	)
	(gr_line
		(start 164.338 -13.7668)
		(end 164.338 -11.2014)
		(stroke
			(width 0.1016)
			(type default)
		)
		(layer "In3.Cu")
	)
	(gr_line
		(start 164.338 -11.2014)
		(end 164.592 -11.2014)
		(stroke
			(width 0.1016)
			(type default)
		)
		(layer "In3.Cu")
	)
	(gr_line
		(start 164.338 -9.566656)
		(end 164.338 -7.001256)
		(stroke
			(width 0.1016)
			(type default)
		)
		(layer "In3.Cu")
	)
	(gr_line
		(start 164.338 -7.001256)
		(end 164.592 -7.001256)
		(stroke
			(width 0.1016)
			(type default)
		)
		(layer "In3.Cu")
	)
	(gr_line
		(start 164.338 -5.366512)
		(end 164.338 -2.801112)
		(stroke
			(width 0.1016)
			(type default)
		)
		(layer "In3.Cu")
	)
	(gr_line
		(start 164.338 -2.801112)
		(end 164.592 -2.801112)
		(stroke
			(width 0.1016)
			(type default)
		)
		(layer "In3.Cu")
	)
	(gr_line
		(start 164.3634 -13.7668)
		(end 164.3634 -11.2014)
		(stroke
			(width 0.2032)
			(type default)
		)
		(layer "In3.Cu")
	)
	(gr_line
		(start 164.3634 -11.2014)
		(end 165.3794 -11.2014)
		(stroke
			(width 0.2032)
			(type default)
		)
		(layer "In3.Cu")
	)
	(gr_line
		(start 164.3634 -9.566656)
		(end 164.3634 -7.001256)
		(stroke
			(width 0.2032)
			(type default)
		)
		(layer "In3.Cu")
	)
	(gr_line
		(start 164.3634 -7.001256)
		(end 165.3794 -7.001256)
		(stroke
			(width 0.2032)
			(type default)
		)
		(layer "In3.Cu")
	)
	(gr_line
		(start 164.3634 -5.366512)
		(end 164.3634 -2.801112)
		(stroke
			(width 0.2032)
			(type default)
		)
		(layer "In3.Cu")
	)
	(gr_line
		(start 164.3634 -2.801112)
		(end 165.3794 -2.801112)
		(stroke
			(width 0.2032)
			(type default)
		)
		(layer "In3.Cu")
	)
	(gr_line
		(start 164.4142 -13.7414)
		(end 164.4142 -11.2522)
		(stroke
			(width 0.2032)
			(type default)
		)
		(layer "In3.Cu")
	)
	(gr_line
		(start 164.4142 -13.7414)
		(end 164.4142 -11.2522)
		(stroke
			(width 0.254)
			(type default)
		)
		(layer "In3.Cu")
	)
	(gr_line
		(start 164.4142 -11.2522)
		(end 164.6174 -11.2522)
		(stroke
			(width 0.2032)
			(type default)
		)
		(layer "In3.Cu")
	)
	(gr_line
		(start 164.4142 -11.2522)
		(end 165.3032 -11.2522)
		(stroke
			(width 0.254)
			(type default)
		)
		(layer "In3.Cu")
	)
	(gr_line
		(start 164.4142 -9.541256)
		(end 164.4142 -7.052056)
		(stroke
			(width 0.2032)
			(type default)
		)
		(layer "In3.Cu")
	)
	(gr_line
		(start 164.4142 -9.541256)
		(end 164.4142 -7.052056)
		(stroke
			(width 0.254)
			(type default)
		)
		(layer "In3.Cu")
	)
	(gr_line
		(start 164.4142 -7.052056)
		(end 164.6174 -7.052056)
		(stroke
			(width 0.2032)
			(type default)
		)
		(layer "In3.Cu")
	)
	(gr_line
		(start 164.4142 -7.052056)
		(end 165.3032 -7.052056)
		(stroke
			(width 0.254)
			(type default)
		)
		(layer "In3.Cu")
	)
	(gr_line
		(start 164.4142 -5.341112)
		(end 164.4142 -2.851912)
		(stroke
			(width 0.2032)
			(type default)
		)
		(layer "In3.Cu")
	)
	(gr_line
		(start 164.4142 -5.341112)
		(end 164.4142 -2.851912)
		(stroke
			(width 0.254)
			(type default)
		)
		(layer "In3.Cu")
	)
	(gr_line
		(start 164.4142 -2.851912)
		(end 164.6174 -2.851912)
		(stroke
			(width 0.2032)
			(type default)
		)
		(layer "In3.Cu")
	)
	(gr_line
		(start 164.4142 -2.851912)
		(end 165.3032 -2.851912)
		(stroke
			(width 0.254)
			(type default)
		)
		(layer "In3.Cu")
	)
	(gr_line
		(start 164.4396 -13.716)
		(end 164.4396 -11.2776)
		(stroke
			(width 0.254)
			(type default)
		)
		(layer "In3.Cu")
	)
	(gr_line
		(start 164.4396 -11.2776)
		(end 165.2778 -11.2776)
		(stroke
			(width 0.254)
			(type default)
		)
		(layer "In3.Cu")
	)
	(gr_line
		(start 164.4396 -9.515856)
		(end 164.4396 -7.077456)
		(stroke
			(width 0.254)
			(type default)
		)
		(layer "In3.Cu")
	)
	(gr_line
		(start 164.4396 -7.077456)
		(end 165.2778 -7.077456)
		(stroke
			(width 0.254)
			(type default)
		)
		(layer "In3.Cu")
	)
	(gr_line
		(start 164.4396 -5.315712)
		(end 164.4396 -2.877312)
		(stroke
			(width 0.254)
			(type default)
		)
		(layer "In3.Cu")
	)
	(gr_line
		(start 164.4396 -2.877312)
		(end 165.2778 -2.877312)
		(stroke
			(width 0.254)
			(type default)
		)
		(layer "In3.Cu")
	)
	(gr_line
		(start 164.465 -13.6906)
		(end 164.465 -11.303)
		(stroke
			(width 0.254)
			(type default)
		)
		(layer "In3.Cu")
	)
	(gr_line
		(start 164.465 -11.303)
		(end 165.2524 -11.303)
		(stroke
			(width 0.254)
			(type default)
		)
		(layer "In3.Cu")
	)
	(gr_line
		(start 164.465 -9.490456)
		(end 164.465 -7.102856)
		(stroke
			(width 0.254)
			(type default)
		)
		(layer "In3.Cu")
	)
	(gr_line
		(start 164.465 -7.102856)
		(end 165.2524 -7.102856)
		(stroke
			(width 0.254)
			(type default)
		)
		(layer "In3.Cu")
	)
	(gr_line
		(start 164.465 -5.290312)
		(end 164.465 -2.902712)
		(stroke
			(width 0.254)
			(type default)
		)
		(layer "In3.Cu")
	)
	(gr_line
		(start 164.465 -2.902712)
		(end 165.2524 -2.902712)
		(stroke
			(width 0.254)
			(type default)
		)
		(layer "In3.Cu")
	)
	(gr_line
		(start 164.4904 -13.6144)
		(end 165.1254 -13.6144)
		(stroke
			(width 0.508)
			(type default)
		)
		(layer "In3.Cu")
	)
	(gr_line
		(start 164.4904 -11.43)
		(end 165.1254 -11.43)
		(stroke
			(width 0.508)
			(type default)
		)
		(layer "In3.Cu")
	)
	(gr_line
		(start 164.4904 -11.3792)
		(end 165.1254 -11.3792)
		(stroke
			(width 0.508)
			(type default)
		)
		(layer "In3.Cu")
	)
	(gr_line
		(start 164.4904 -9.414256)
		(end 165.1254 -9.414256)
		(stroke
			(width 0.508)
			(type default)
		)
		(layer "In3.Cu")
	)
	(gr_line
		(start 164.4904 -7.229856)
		(end 165.1254 -7.229856)
		(stroke
			(width 0.508)
			(type default)
		)
		(layer "In3.Cu")
	)
	(gr_line
		(start 164.4904 -7.179056)
		(end 165.1254 -7.179056)
		(stroke
			(width 0.508)
			(type default)
		)
		(layer "In3.Cu")
	)
	(gr_line
		(start 164.4904 -5.214112)
		(end 165.1254 -5.214112)
		(stroke
			(width 0.508)
			(type default)
		)
		(layer "In3.Cu")
	)
	(gr_line
		(start 164.4904 -3.029712)
		(end 165.1254 -3.029712)
		(stroke
			(width 0.508)
			(type default)
		)
		(layer "In3.Cu")
	)
	(gr_line
		(start 164.4904 -2.978912)
		(end 165.1254 -2.978912)
		(stroke
			(width 0.508)
			(type default)
		)
		(layer "In3.Cu")
	)
	(gr_line
		(start 164.5158 -11.684)
		(end 165.1508 -11.684)
		(stroke
			(width 0.508)
			(type default)
		)
		(layer "In3.Cu")
	)
	(gr_line
		(start 164.5158 -7.483856)
		(end 165.1508 -7.483856)
		(stroke
			(width 0.508)
			(type default)
		)
		(layer "In3.Cu")
	)
	(gr_line
		(start 164.5158 -3.283712)
		(end 165.1508 -3.283712)
		(stroke
			(width 0.508)
			(type default)
		)
		(layer "In3.Cu")
	)
	(gr_line
		(start 164.5412 -13.6398)
		(end 164.5412 -11.3792)
		(stroke
			(width 0.254)
			(type default)
		)
		(layer "In3.Cu")
	)
	(gr_line
		(start 164.5412 -13.4874)
		(end 165.1762 -13.4874)
		(stroke
			(width 0.508)
			(type default)
		)
		(layer "In3.Cu")
	)
	(gr_line
		(start 164.5412 -11.3792)
		(end 165.1762 -11.3792)
		(stroke
			(width 0.254)
			(type default)
		)
		(layer "In3.Cu")
	)
	(gr_line
		(start 164.5412 -9.439656)
		(end 164.5412 -7.179056)
		(stroke
			(width 0.254)
			(type default)
		)
		(layer "In3.Cu")
	)
	(gr_line
		(start 164.5412 -9.287256)
		(end 165.1762 -9.287256)
		(stroke
			(width 0.508)
			(type default)
		)
		(layer "In3.Cu")
	)
	(gr_line
		(start 164.5412 -7.179056)
		(end 165.1762 -7.179056)
		(stroke
			(width 0.254)
			(type default)
		)
		(layer "In3.Cu")
	)
	(gr_line
		(start 164.5412 -5.239512)
		(end 164.5412 -2.978912)
		(stroke
			(width 0.254)
			(type default)
		)
		(layer "In3.Cu")
	)
	(gr_line
		(start 164.5412 -5.087112)
		(end 165.1762 -5.087112)
		(stroke
			(width 0.508)
			(type default)
		)
		(layer "In3.Cu")
	)
	(gr_line
		(start 164.5412 -2.978912)
		(end 165.1762 -2.978912)
		(stroke
			(width 0.254)
			(type default)
		)
		(layer "In3.Cu")
	)
	(gr_line
		(start 164.5666 -13.335)
		(end 165.2016 -13.335)
		(stroke
			(width 0.508)
			(type default)
		)
		(layer "In3.Cu")
	)
	(gr_line
		(start 164.5666 -9.134856)
		(end 165.2016 -9.134856)
		(stroke
			(width 0.508)
			(type default)
		)
		(layer "In3.Cu")
	)
	(gr_line
		(start 164.5666 -4.934712)
		(end 165.2016 -4.934712)
		(stroke
			(width 0.508)
			(type default)
		)
		(layer "In3.Cu")
	)
	(gr_line
		(start 164.592 -13.6144)
		(end 165.227 -13.6144)
		(stroke
			(width 0.508)
			(type default)
		)
		(layer "In3.Cu")
	)
	(gr_line
		(start 164.592 -11.2014)
		(end 165.4302 -11.2014)
		(stroke
			(width 0.2032)
			(type default)
		)
		(layer "In3.Cu")
	)
	(gr_line
		(start 164.592 -9.414256)
		(end 165.227 -9.414256)
		(stroke
			(width 0.508)
			(type default)
		)
		(layer "In3.Cu")
	)
	(gr_line
		(start 164.592 -7.001256)
		(end 165.4302 -7.001256)
		(stroke
			(width 0.2032)
			(type default)
		)
		(layer "In3.Cu")
	)
	(gr_line
		(start 164.592 -5.214112)
		(end 165.227 -5.214112)
		(stroke
			(width 0.508)
			(type default)
		)
		(layer "In3.Cu")
	)
	(gr_line
		(start 164.592 -2.801112)
		(end 165.4302 -2.801112)
		(stroke
			(width 0.2032)
			(type default)
		)
		(layer "In3.Cu")
	)
	(gr_line
		(start 164.6174 -13.6144)
		(end 164.6174 -11.43)
		(stroke
			(width 0.254)
			(type default)
		)
		(layer "In3.Cu")
	)
	(gr_line
		(start 164.6174 -11.43)
		(end 165.1 -11.43)
		(stroke
			(width 0.254)
			(type default)
		)
		(layer "In3.Cu")
	)
	(gr_line
		(start 164.6174 -11.2522)
		(end 165.354 -11.2522)
		(stroke
			(width 0.254)
			(type default)
		)
		(layer "In3.Cu")
	)
	(gr_line
		(start 164.6174 -9.414256)
		(end 164.6174 -7.229856)
		(stroke
			(width 0.254)
			(type default)
		)
		(layer "In3.Cu")
	)
	(gr_line
		(start 164.6174 -7.229856)
		(end 165.1 -7.229856)
		(stroke
			(width 0.254)
			(type default)
		)
		(layer "In3.Cu")
	)
	(gr_line
		(start 164.6174 -7.052056)
		(end 165.354 -7.052056)
		(stroke
			(width 0.254)
			(type default)
		)
		(layer "In3.Cu")
	)
	(gr_line
		(start 164.6174 -5.214112)
		(end 164.6174 -3.029712)
		(stroke
			(width 0.254)
			(type default)
		)
		(layer "In3.Cu")
	)
	(gr_line
		(start 164.6174 -3.029712)
		(end 165.1 -3.029712)
		(stroke
			(width 0.254)
			(type default)
		)
		(layer "In3.Cu")
	)
	(gr_line
		(start 164.6174 -2.851912)
		(end 165.354 -2.851912)
		(stroke
			(width 0.254)
			(type default)
		)
		(layer "In3.Cu")
	)
	(gr_line
		(start 164.635942 -11.36523)
		(end 165.270942 -11.36523)
		(stroke
			(width 0.508)
			(type default)
		)
		(layer "In3.Cu")
	)
	(gr_line
		(start 164.635942 -7.165086)
		(end 165.270942 -7.165086)
		(stroke
			(width 0.508)
			(type default)
		)
		(layer "In3.Cu")
	)
	(gr_line
		(start 164.635942 -2.964942)
		(end 165.270942 -2.964942)
		(stroke
			(width 0.508)
			(type default)
		)
		(layer "In3.Cu")
	)
	(gr_line
		(start 164.6428 -13.6144)
		(end 165.2778 -13.6144)
		(stroke
			(width 0.508)
			(type default)
		)
		(layer "In3.Cu")
	)
	(gr_line
		(start 164.6428 -13.4874)
		(end 164.6428 -11.5062)
		(stroke
			(width 0.762)
			(type default)
		)
		(layer "In3.Cu")
	)
	(gr_line
		(start 164.6428 -11.5062)
		(end 165.2778 -11.5062)
		(stroke
			(width 0.508)
			(type default)
		)
		(layer "In3.Cu")
	)
	(gr_line
		(start 164.6428 -9.414256)
		(end 165.2778 -9.414256)
		(stroke
			(width 0.508)
			(type default)
		)
		(layer "In3.Cu")
	)
	(gr_line
		(start 164.6428 -9.287256)
		(end 164.6428 -7.306056)
		(stroke
			(width 0.762)
			(type default)
		)
		(layer "In3.Cu")
	)
	(gr_line
		(start 164.6428 -7.306056)
		(end 165.2778 -7.306056)
		(stroke
			(width 0.508)
			(type default)
		)
		(layer "In3.Cu")
	)
	(gr_line
		(start 164.6428 -5.214112)
		(end 165.2778 -5.214112)
		(stroke
			(width 0.508)
			(type default)
		)
		(layer "In3.Cu")
	)
	(gr_line
		(start 164.6428 -5.087112)
		(end 164.6428 -3.105912)
		(stroke
			(width 0.762)
			(type default)
		)
		(layer "In3.Cu")
	)
	(gr_line
		(start 164.6428 -3.105912)
		(end 165.2778 -3.105912)
		(stroke
			(width 0.508)
			(type default)
		)
		(layer "In3.Cu")
	)
	(gr_line
		(start 164.6936 -13.5382)
		(end 164.6936 -11.5062)
		(stroke
			(width 0.254)
			(type default)
		)
		(layer "In3.Cu")
	)
	(gr_line
		(start 164.6936 -11.5062)
		(end 165.0238 -11.5062)
		(stroke
			(width 0.254)
			(type default)
		)
		(layer "In3.Cu")
	)
	(gr_line
		(start 164.6936 -9.338056)
		(end 164.6936 -7.306056)
		(stroke
			(width 0.254)
			(type default)
		)
		(layer "In3.Cu")
	)
	(gr_line
		(start 164.6936 -7.306056)
		(end 165.0238 -7.306056)
		(stroke
			(width 0.254)
			(type default)
		)
		(layer "In3.Cu")
	)
	(gr_line
		(start 164.6936 -5.137912)
		(end 164.6936 -3.105912)
		(stroke
			(width 0.254)
			(type default)
		)
		(layer "In3.Cu")
	)
	(gr_line
		(start 164.6936 -3.105912)
		(end 165.0238 -3.105912)
		(stroke
			(width 0.254)
			(type default)
		)
		(layer "In3.Cu")
	)
	(gr_line
		(start 164.7952 -13.462)
		(end 164.7952 -11.6586)
		(stroke
			(width 0.254)
			(type default)
		)
		(layer "In3.Cu")
	)
	(gr_line
		(start 164.7952 -13.462)
		(end 164.7952 -11.4808)
		(stroke
			(width 0.762)
			(type default)
		)
		(layer "In3.Cu")
	)
	(gr_line
		(start 164.7952 -11.6586)
		(end 164.8968 -11.6586)
		(stroke
			(width 0.254)
			(type default)
		)
		(layer "In3.Cu")
	)
	(gr_line
		(start 164.7952 -9.261856)
		(end 164.7952 -7.458456)
		(stroke
			(width 0.254)
			(type default)
		)
		(layer "In3.Cu")
	)
	(gr_line
		(start 164.7952 -9.261856)
		(end 164.7952 -7.280656)
		(stroke
			(width 0.762)
			(type default)
		)
		(layer "In3.Cu")
	)
	(gr_line
		(start 164.7952 -7.458456)
		(end 164.8968 -7.458456)
		(stroke
			(width 0.254)
			(type default)
		)
		(layer "In3.Cu")
	)
	(gr_line
		(start 164.7952 -5.061712)
		(end 164.7952 -3.258312)
		(stroke
			(width 0.254)
			(type default)
		)
		(layer "In3.Cu")
	)
	(gr_line
		(start 164.7952 -5.061712)
		(end 164.7952 -3.080512)
		(stroke
			(width 0.762)
			(type default)
		)
		(layer "In3.Cu")
	)
	(gr_line
		(start 164.7952 -3.258312)
		(end 164.8968 -3.258312)
		(stroke
			(width 0.254)
			(type default)
		)
		(layer "In3.Cu")
	)
	(gr_line
		(start 164.8968 -13.5636)
		(end 164.846 -13.5636)
		(stroke
			(width 0.254)
			(type default)
		)
		(layer "In3.Cu")
	)
	(gr_line
		(start 164.8968 -11.6586)
		(end 164.8968 -13.5636)
		(stroke
			(width 0.254)
			(type default)
		)
		(layer "In3.Cu")
	)
	(gr_line
		(start 164.8968 -9.363456)
		(end 164.846 -9.363456)
		(stroke
			(width 0.254)
			(type default)
		)
		(layer "In3.Cu")
	)
	(gr_line
		(start 164.8968 -7.458456)
		(end 164.8968 -9.363456)
		(stroke
			(width 0.254)
			(type default)
		)
		(layer "In3.Cu")
	)
	(gr_line
		(start 164.8968 -5.163312)
		(end 164.846 -5.163312)
		(stroke
			(width 0.254)
			(type default)
		)
		(layer "In3.Cu")
	)
	(gr_line
		(start 164.8968 -3.258312)
		(end 164.8968 -5.163312)
		(stroke
			(width 0.254)
			(type default)
		)
		(layer "In3.Cu")
	)
	(gr_line
		(start 164.9476 -13.4874)
		(end 164.9476 -11.5062)
		(stroke
			(width 0.762)
			(type default)
		)
		(layer "In3.Cu")
	)
	(gr_line
		(start 164.9476 -9.287256)
		(end 164.9476 -7.306056)
		(stroke
			(width 0.762)
			(type default)
		)
		(layer "In3.Cu")
	)
	(gr_line
		(start 164.9476 -5.087112)
		(end 164.9476 -3.105912)
		(stroke
			(width 0.762)
			(type default)
		)
		(layer "In3.Cu")
	)
	(gr_line
		(start 165.0238 -13.462)
		(end 164.7952 -13.462)
		(stroke
			(width 0.254)
			(type default)
		)
		(layer "In3.Cu")
	)
	(gr_line
		(start 165.0238 -11.5062)
		(end 165.0238 -13.462)
		(stroke
			(width 0.254)
			(type default)
		)
		(layer "In3.Cu")
	)
	(gr_line
		(start 165.0238 -9.261856)
		(end 164.7952 -9.261856)
		(stroke
			(width 0.254)
			(type default)
		)
		(layer "In3.Cu")
	)
	(gr_line
		(start 165.0238 -7.306056)
		(end 165.0238 -9.261856)
		(stroke
			(width 0.254)
			(type default)
		)
		(layer "In3.Cu")
	)
	(gr_line
		(start 165.0238 -5.061712)
		(end 164.7952 -5.061712)
		(stroke
			(width 0.254)
			(type default)
		)
		(layer "In3.Cu")
	)
	(gr_line
		(start 165.0238 -3.105912)
		(end 165.0238 -5.061712)
		(stroke
			(width 0.254)
			(type default)
		)
		(layer "In3.Cu")
	)
	(gr_line
		(start 165.0746 -13.8176)
		(end 165.0746 -13.7668)
		(stroke
			(width 0.1016)
			(type default)
		)
		(layer "In3.Cu")
	)
	(gr_line
		(start 165.0746 -13.8176)
		(end 165.481 -13.8176)
		(stroke
			(width 0.1016)
			(type default)
		)
		(layer "In3.Cu")
	)
	(gr_line
		(start 165.0746 -13.7668)
		(end 164.3126 -13.7668)
		(stroke
			(width 0.1016)
			(type default)
		)
		(layer "In3.Cu")
	)
	(gr_line
		(start 165.0746 -13.4874)
		(end 165.0746 -11.5062)
		(stroke
			(width 0.762)
			(type default)
		)
		(layer "In3.Cu")
	)
	(gr_line
		(start 165.0746 -9.617456)
		(end 165.0746 -9.566656)
		(stroke
			(width 0.1016)
			(type default)
		)
		(layer "In3.Cu")
	)
	(gr_line
		(start 165.0746 -9.617456)
		(end 165.481 -9.617456)
		(stroke
			(width 0.1016)
			(type default)
		)
		(layer "In3.Cu")
	)
	(gr_line
		(start 165.0746 -9.566656)
		(end 164.3126 -9.566656)
		(stroke
			(width 0.1016)
			(type default)
		)
		(layer "In3.Cu")
	)
	(gr_line
		(start 165.0746 -9.287256)
		(end 165.0746 -7.306056)
		(stroke
			(width 0.762)
			(type default)
		)
		(layer "In3.Cu")
	)
	(gr_line
		(start 165.0746 -5.417312)
		(end 165.0746 -5.366512)
		(stroke
			(width 0.1016)
			(type default)
		)
		(layer "In3.Cu")
	)
	(gr_line
		(start 165.0746 -5.417312)
		(end 165.481 -5.417312)
		(stroke
			(width 0.1016)
			(type default)
		)
		(layer "In3.Cu")
	)
	(gr_line
		(start 165.0746 -5.366512)
		(end 164.3126 -5.366512)
		(stroke
			(width 0.1016)
			(type default)
		)
		(layer "In3.Cu")
	)
	(gr_line
		(start 165.0746 -5.087112)
		(end 165.0746 -3.105912)
		(stroke
			(width 0.762)
			(type default)
		)
		(layer "In3.Cu")
	)
	(gr_line
		(start 165.1 -13.5382)
		(end 164.6936 -13.5382)
		(stroke
			(width 0.254)
			(type default)
		)
		(layer "In3.Cu")
	)
	(gr_line
		(start 165.1 -11.43)
		(end 165.1 -13.5382)
		(stroke
			(width 0.254)
			(type default)
		)
		(layer "In3.Cu")
	)
	(gr_line
		(start 165.1 -9.338056)
		(end 164.6936 -9.338056)
		(stroke
			(width 0.254)
			(type default)
		)
		(layer "In3.Cu")
	)
	(gr_line
		(start 165.1 -7.229856)
		(end 165.1 -9.338056)
		(stroke
			(width 0.254)
			(type default)
		)
		(layer "In3.Cu")
	)
	(gr_line
		(start 165.1 -5.137912)
		(end 164.6936 -5.137912)
		(stroke
			(width 0.254)
			(type default)
		)
		(layer "In3.Cu")
	)
	(gr_line
		(start 165.1 -3.029712)
		(end 165.1 -5.137912)
		(stroke
			(width 0.254)
			(type default)
		)
		(layer "In3.Cu")
	)
	(gr_line
		(start 165.1508 -13.4874)
		(end 165.1508 -11.5062)
		(stroke
			(width 0.762)
			(type default)
		)
		(layer "In3.Cu")
	)
	(gr_line
		(start 165.1508 -9.287256)
		(end 165.1508 -7.306056)
		(stroke
			(width 0.762)
			(type default)
		)
		(layer "In3.Cu")
	)
	(gr_line
		(start 165.1508 -5.087112)
		(end 165.1508 -3.105912)
		(stroke
			(width 0.762)
			(type default)
		)
		(layer "In3.Cu")
	)
	(gr_line
		(start 165.1762 -13.6144)
		(end 164.6174 -13.6144)
		(stroke
			(width 0.254)
			(type default)
		)
		(layer "In3.Cu")
	)
	(gr_line
		(start 165.1762 -11.3792)
		(end 165.1762 -13.6144)
		(stroke
			(width 0.254)
			(type default)
		)
		(layer "In3.Cu")
	)
	(gr_line
		(start 165.1762 -9.414256)
		(end 164.6174 -9.414256)
		(stroke
			(width 0.254)
			(type default)
		)
		(layer "In3.Cu")
	)
	(gr_line
		(start 165.1762 -7.179056)
		(end 165.1762 -9.414256)
		(stroke
			(width 0.254)
			(type default)
		)
		(layer "In3.Cu")
	)
	(gr_line
		(start 165.1762 -5.214112)
		(end 164.6174 -5.214112)
		(stroke
			(width 0.254)
			(type default)
		)
		(layer "In3.Cu")
	)
	(gr_line
		(start 165.1762 -2.978912)
		(end 165.1762 -5.214112)
		(stroke
			(width 0.254)
			(type default)
		)
		(layer "In3.Cu")
	)
	(gr_line
		(start 165.2524 -13.6398)
		(end 164.5412 -13.6398)
		(stroke
			(width 0.254)
			(type default)
		)
		(layer "In3.Cu")
	)
	(gr_line
		(start 165.2524 -11.303)
		(end 165.2524 -13.6398)
		(stroke
			(width 0.254)
			(type default)
		)
		(layer "In3.Cu")
	)
	(gr_line
		(start 165.2524 -9.439656)
		(end 164.5412 -9.439656)
		(stroke
			(width 0.254)
			(type default)
		)
		(layer "In3.Cu")
	)
	(gr_line
		(start 165.2524 -7.102856)
		(end 165.2524 -9.439656)
		(stroke
			(width 0.254)
			(type default)
		)
		(layer "In3.Cu")
	)
	(gr_line
		(start 165.2524 -5.239512)
		(end 164.5412 -5.239512)
		(stroke
			(width 0.254)
			(type default)
		)
		(layer "In3.Cu")
	)
	(gr_line
		(start 165.2524 -2.902712)
		(end 165.2524 -5.239512)
		(stroke
			(width 0.254)
			(type default)
		)
		(layer "In3.Cu")
	)
	(gr_line
		(start 165.2778 -13.7668)
		(end 164.2872 -13.7668)
		(stroke
			(width 0.1016)
			(type default)
		)
		(layer "In3.Cu")
	)
	(gr_line
		(start 165.2778 -13.6906)
		(end 164.465 -13.6906)
		(stroke
			(width 0.254)
			(type default)
		)
		(layer "In3.Cu")
	)
	(gr_line
		(start 165.2778 -11.2776)
		(end 165.2778 -13.6906)
		(stroke
			(width 0.254)
			(type default)
		)
		(layer "In3.Cu")
	)
	(gr_line
		(start 165.2778 -9.566656)
		(end 164.2872 -9.566656)
		(stroke
			(width 0.1016)
			(type default)
		)
		(layer "In3.Cu")
	)
	(gr_line
		(start 165.2778 -9.490456)
		(end 164.465 -9.490456)
		(stroke
			(width 0.254)
			(type default)
		)
		(layer "In3.Cu")
	)
	(gr_line
		(start 165.2778 -7.077456)
		(end 165.2778 -9.490456)
		(stroke
			(width 0.254)
			(type default)
		)
		(layer "In3.Cu")
	)
	(gr_line
		(start 165.2778 -5.366512)
		(end 164.2872 -5.366512)
		(stroke
			(width 0.1016)
			(type default)
		)
		(layer "In3.Cu")
	)
	(gr_line
		(start 165.2778 -5.290312)
		(end 164.465 -5.290312)
		(stroke
			(width 0.254)
			(type default)
		)
		(layer "In3.Cu")
	)
	(gr_line
		(start 165.2778 -2.877312)
		(end 165.2778 -5.290312)
		(stroke
			(width 0.254)
			(type default)
		)
		(layer "In3.Cu")
	)
	(gr_line
		(start 165.3032 -13.716)
		(end 164.4396 -13.716)
		(stroke
			(width 0.254)
			(type default)
		)
		(layer "In3.Cu")
	)
	(gr_line
		(start 165.3032 -11.2522)
		(end 165.3032 -13.716)
		(stroke
			(width 0.254)
			(type default)
		)
		(layer "In3.Cu")
	)
	(gr_line
		(start 165.3032 -9.515856)
		(end 164.4396 -9.515856)
		(stroke
			(width 0.254)
			(type default)
		)
		(layer "In3.Cu")
	)
	(gr_line
		(start 165.3032 -7.052056)
		(end 165.3032 -9.515856)
		(stroke
			(width 0.254)
			(type default)
		)
		(layer "In3.Cu")
	)
	(gr_line
		(start 165.3032 -5.315712)
		(end 164.4396 -5.315712)
		(stroke
			(width 0.254)
			(type default)
		)
		(layer "In3.Cu")
	)
	(gr_line
		(start 165.3032 -2.851912)
		(end 165.3032 -5.315712)
		(stroke
			(width 0.254)
			(type default)
		)
		(layer "In3.Cu")
	)
	(gr_line
		(start 165.354 -13.7414)
		(end 164.4142 -13.7414)
		(stroke
			(width 0.254)
			(type default)
		)
		(layer "In3.Cu")
	)
	(gr_line
		(start 165.354 -11.2522)
		(end 165.354 -13.7414)
		(stroke
			(width 0.254)
			(type default)
		)
		(layer "In3.Cu")
	)
	(gr_line
		(start 165.354 -9.541256)
		(end 164.4142 -9.541256)
		(stroke
			(width 0.254)
			(type default)
		)
		(layer "In3.Cu")
	)
	(gr_line
		(start 165.354 -7.052056)
		(end 165.354 -9.541256)
		(stroke
			(width 0.254)
			(type default)
		)
		(layer "In3.Cu")
	)
	(gr_line
		(start 165.354 -5.341112)
		(end 164.4142 -5.341112)
		(stroke
			(width 0.254)
			(type default)
		)
		(layer "In3.Cu")
	)
	(gr_line
		(start 165.354 -2.851912)
		(end 165.354 -5.341112)
		(stroke
			(width 0.254)
			(type default)
		)
		(layer "In3.Cu")
	)
	(gr_line
		(start 165.3794 -13.7414)
		(end 164.4142 -13.7414)
		(stroke
			(width 0.2032)
			(type default)
		)
		(layer "In3.Cu")
	)
	(gr_line
		(start 165.3794 -11.2014)
		(end 165.3794 -13.7414)
		(stroke
			(width 0.2032)
			(type default)
		)
		(layer "In3.Cu")
	)
	(gr_line
		(start 165.3794 -9.541256)
		(end 164.4142 -9.541256)
		(stroke
			(width 0.2032)
			(type default)
		)
		(layer "In3.Cu")
	)
	(gr_line
		(start 165.3794 -7.001256)
		(end 165.3794 -9.541256)
		(stroke
			(width 0.2032)
			(type default)
		)
		(layer "In3.Cu")
	)
	(gr_line
		(start 165.3794 -5.341112)
		(end 164.4142 -5.341112)
		(stroke
			(width 0.2032)
			(type default)
		)
		(layer "In3.Cu")
	)
	(gr_line
		(start 165.3794 -2.801112)
		(end 165.3794 -5.341112)
		(stroke
			(width 0.2032)
			(type default)
		)
		(layer "In3.Cu")
	)
	(gr_line
		(start 165.4302 -13.7668)
		(end 164.3634 -13.7668)
		(stroke
			(width 0.2032)
			(type default)
		)
		(layer "In3.Cu")
	)
	(gr_line
		(start 165.4302 -11.2014)
		(end 165.4302 -13.7668)
		(stroke
			(width 0.2032)
			(type default)
		)
		(layer "In3.Cu")
	)
	(gr_line
		(start 165.4302 -9.566656)
		(end 164.3634 -9.566656)
		(stroke
			(width 0.2032)
			(type default)
		)
		(layer "In3.Cu")
	)
	(gr_line
		(start 165.4302 -7.001256)
		(end 165.4302 -9.566656)
		(stroke
			(width 0.2032)
			(type default)
		)
		(layer "In3.Cu")
	)
	(gr_line
		(start 165.4302 -5.366512)
		(end 164.3634 -5.366512)
		(stroke
			(width 0.2032)
			(type default)
		)
		(layer "In3.Cu")
	)
	(gr_line
		(start 165.4302 -2.801112)
		(end 165.4302 -5.366512)
		(stroke
			(width 0.2032)
			(type default)
		)
		(layer "In3.Cu")
	)
	(gr_line
		(start 165.4556 -13.7668)
		(end 164.338 -13.7668)
		(stroke
			(width 0.1016)
			(type default)
		)
		(layer "In3.Cu")
	)
	(gr_line
		(start 165.4556 -11.176)
		(end 165.4556 -13.7668)
		(stroke
			(width 0.1016)
			(type default)
		)
		(layer "In3.Cu")
	)
	(gr_line
		(start 165.4556 -9.566656)
		(end 164.338 -9.566656)
		(stroke
			(width 0.1016)
			(type default)
		)
		(layer "In3.Cu")
	)
	(gr_line
		(start 165.4556 -6.975856)
		(end 165.4556 -9.566656)
		(stroke
			(width 0.1016)
			(type default)
		)
		(layer "In3.Cu")
	)
	(gr_line
		(start 165.4556 -5.366512)
		(end 164.338 -5.366512)
		(stroke
			(width 0.1016)
			(type default)
		)
		(layer "In3.Cu")
	)
	(gr_line
		(start 165.4556 -2.775712)
		(end 165.4556 -5.366512)
		(stroke
			(width 0.1016)
			(type default)
		)
		(layer "In3.Cu")
	)
	(gr_line
		(start 165.481 -13.8176)
		(end 165.0746 -13.8176)
		(stroke
			(width 0.1016)
			(type default)
		)
		(layer "In3.Cu")
	)
	(gr_line
		(start 165.481 -13.8176)
		(end 165.481 -11.1506)
		(stroke
			(width 0.1016)
			(type default)
		)
		(layer "In3.Cu")
	)
	(gr_line
		(start 165.481 -11.1506)
		(end 164.2872 -11.1506)
		(stroke
			(width 0.1016)
			(type default)
		)
		(layer "In3.Cu")
	)
	(gr_line
		(start 165.481 -11.1506)
		(end 165.481 -13.8176)
		(stroke
			(width 0.1016)
			(type default)
		)
		(layer "In3.Cu")
	)
	(gr_line
		(start 165.481 -9.617456)
		(end 165.0746 -9.617456)
		(stroke
			(width 0.1016)
			(type default)
		)
		(layer "In3.Cu")
	)
	(gr_line
		(start 165.481 -9.617456)
		(end 165.481 -6.950456)
		(stroke
			(width 0.1016)
			(type default)
		)
		(layer "In3.Cu")
	)
	(gr_line
		(start 165.481 -6.950456)
		(end 164.2872 -6.950456)
		(stroke
			(width 0.1016)
			(type default)
		)
		(layer "In3.Cu")
	)
	(gr_line
		(start 165.481 -6.950456)
		(end 165.481 -9.617456)
		(stroke
			(width 0.1016)
			(type default)
		)
		(layer "In3.Cu")
	)
	(gr_line
		(start 165.481 -5.417312)
		(end 165.0746 -5.417312)
		(stroke
			(width 0.1016)
			(type default)
		)
		(layer "In3.Cu")
	)
	(gr_line
		(start 165.481 -5.417312)
		(end 165.481 -2.750312)
		(stroke
			(width 0.1016)
			(type default)
		)
		(layer "In3.Cu")
	)
	(gr_line
		(start 165.481 -2.750312)
		(end 164.2872 -2.750312)
		(stroke
			(width 0.1016)
			(type default)
		)
		(layer "In3.Cu")
	)
	(gr_line
		(start 165.481 -2.750312)
		(end 165.481 -5.417312)
		(stroke
			(width 0.1016)
			(type default)
		)
		(layer "In3.Cu")
	)
	(gr_line
		(start 166.2176 -24.6634)
		(end 166.2176 -23.3934)
		(stroke
			(width 0.7874)
			(type default)
		)
		(layer "In3.Cu")
	)
	(gr_line
		(start 166.287196 -12.563348)
		(end 167.074596 -12.563348)
		(stroke
			(width 0.1016)
			(type default)
		)
		(layer "In3.Cu")
	)
	(gr_line
		(start 166.287196 -12.512548)
		(end 166.287196 -9.896348)
		(stroke
			(width 0.1016)
			(type default)
		)
		(layer "In3.Cu")
	)
	(gr_line
		(start 166.287196 -12.463272)
		(end 167.074596 -12.463272)
		(stroke
			(width 0.1016)
			(type default)
		)
		(layer "In3.Cu")
	)
	(gr_line
		(start 166.287196 -12.412472)
		(end 166.287196 -9.796272)
		(stroke
			(width 0.1016)
			(type default)
		)
		(layer "In3.Cu")
	)
	(gr_line
		(start 166.287196 -9.896348)
		(end 166.287196 -12.563348)
		(stroke
			(width 0.1016)
			(type default)
		)
		(layer "In3.Cu")
	)
	(gr_line
		(start 166.287196 -9.896348)
		(end 167.480996 -9.896348)
		(stroke
			(width 0.1016)
			(type default)
		)
		(layer "In3.Cu")
	)
	(gr_line
		(start 166.287196 -9.796272)
		(end 166.287196 -12.463272)
		(stroke
			(width 0.1016)
			(type default)
		)
		(layer "In3.Cu")
	)
	(gr_line
		(start 166.287196 -9.796272)
		(end 167.480996 -9.796272)
		(stroke
			(width 0.1016)
			(type default)
		)
		(layer "In3.Cu")
	)
	(gr_line
		(start 166.287196 -8.363204)
		(end 167.074596 -8.363204)
		(stroke
			(width 0.1016)
			(type default)
		)
		(layer "In3.Cu")
	)
	(gr_line
		(start 166.287196 -8.312404)
		(end 166.287196 -5.696204)
		(stroke
			(width 0.1016)
			(type default)
		)
		(layer "In3.Cu")
	)
	(gr_line
		(start 166.287196 -8.263128)
		(end 167.074596 -8.263128)
		(stroke
			(width 0.1016)
			(type default)
		)
		(layer "In3.Cu")
	)
	(gr_line
		(start 166.287196 -8.212328)
		(end 166.287196 -5.596128)
		(stroke
			(width 0.1016)
			(type default)
		)
		(layer "In3.Cu")
	)
	(gr_line
		(start 166.287196 -5.696204)
		(end 166.287196 -8.363204)
		(stroke
			(width 0.1016)
			(type default)
		)
		(layer "In3.Cu")
	)
	(gr_line
		(start 166.287196 -5.696204)
		(end 167.480996 -5.696204)
		(stroke
			(width 0.1016)
			(type default)
		)
		(layer "In3.Cu")
	)
	(gr_line
		(start 166.287196 -5.596128)
		(end 166.287196 -8.263128)
		(stroke
			(width 0.1016)
			(type default)
		)
		(layer "In3.Cu")
	)
	(gr_line
		(start 166.287196 -5.596128)
		(end 167.480996 -5.596128)
		(stroke
			(width 0.1016)
			(type default)
		)
		(layer "In3.Cu")
	)
	(gr_line
		(start 166.287196 -4.16306)
		(end 167.074596 -4.16306)
		(stroke
			(width 0.1016)
			(type default)
		)
		(layer "In3.Cu")
	)
	(gr_line
		(start 166.287196 -4.11226)
		(end 166.287196 -1.49606)
		(stroke
			(width 0.1016)
			(type default)
		)
		(layer "In3.Cu")
	)
	(gr_line
		(start 166.287196 -4.062984)
		(end 167.074596 -4.062984)
		(stroke
			(width 0.1016)
			(type default)
		)
		(layer "In3.Cu")
	)
	(gr_line
		(start 166.287196 -4.012184)
		(end 166.287196 -1.395984)
		(stroke
			(width 0.1016)
			(type default)
		)
		(layer "In3.Cu")
	)
	(gr_line
		(start 166.287196 -1.49606)
		(end 166.287196 -4.16306)
		(stroke
			(width 0.1016)
			(type default)
		)
		(layer "In3.Cu")
	)
	(gr_line
		(start 166.287196 -1.49606)
		(end 167.480996 -1.49606)
		(stroke
			(width 0.1016)
			(type default)
		)
		(layer "In3.Cu")
	)
	(gr_line
		(start 166.287196 -1.395984)
		(end 166.287196 -4.062984)
		(stroke
			(width 0.1016)
			(type default)
		)
		(layer "In3.Cu")
	)
	(gr_line
		(start 166.287196 -1.395984)
		(end 167.480996 -1.395984)
		(stroke
			(width 0.1016)
			(type default)
		)
		(layer "In3.Cu")
	)
	(gr_line
		(start 166.312596 -12.512548)
		(end 166.312596 -9.921748)
		(stroke
			(width 0.1016)
			(type default)
		)
		(layer "In3.Cu")
	)
	(gr_line
		(start 166.312596 -12.412472)
		(end 166.312596 -9.821672)
		(stroke
			(width 0.1016)
			(type default)
		)
		(layer "In3.Cu")
	)
	(gr_line
		(start 166.312596 -9.921748)
		(end 167.455596 -9.921748)
		(stroke
			(width 0.1016)
			(type default)
		)
		(layer "In3.Cu")
	)
	(gr_line
		(start 166.312596 -9.821672)
		(end 167.455596 -9.821672)
		(stroke
			(width 0.1016)
			(type default)
		)
		(layer "In3.Cu")
	)
	(gr_line
		(start 166.312596 -8.312404)
		(end 166.312596 -5.721604)
		(stroke
			(width 0.1016)
			(type default)
		)
		(layer "In3.Cu")
	)
	(gr_line
		(start 166.312596 -8.212328)
		(end 166.312596 -5.621528)
		(stroke
			(width 0.1016)
			(type default)
		)
		(layer "In3.Cu")
	)
	(gr_line
		(start 166.312596 -5.721604)
		(end 167.455596 -5.721604)
		(stroke
			(width 0.1016)
			(type default)
		)
		(layer "In3.Cu")
	)
	(gr_line
		(start 166.312596 -5.621528)
		(end 167.455596 -5.621528)
		(stroke
			(width 0.1016)
			(type default)
		)
		(layer "In3.Cu")
	)
	(gr_line
		(start 166.312596 -4.11226)
		(end 166.312596 -1.52146)
		(stroke
			(width 0.1016)
			(type default)
		)
		(layer "In3.Cu")
	)
	(gr_line
		(start 166.312596 -4.012184)
		(end 166.312596 -1.421384)
		(stroke
			(width 0.1016)
			(type default)
		)
		(layer "In3.Cu")
	)
	(gr_line
		(start 166.312596 -1.52146)
		(end 167.455596 -1.52146)
		(stroke
			(width 0.1016)
			(type default)
		)
		(layer "In3.Cu")
	)
	(gr_line
		(start 166.312596 -1.421384)
		(end 167.455596 -1.421384)
		(stroke
			(width 0.1016)
			(type default)
		)
		(layer "In3.Cu")
	)
	(gr_line
		(start 166.337996 -12.512548)
		(end 166.337996 -9.947148)
		(stroke
			(width 0.1016)
			(type default)
		)
		(layer "In3.Cu")
	)
	(gr_line
		(start 166.337996 -12.412472)
		(end 166.337996 -9.847072)
		(stroke
			(width 0.1016)
			(type default)
		)
		(layer "In3.Cu")
	)
	(gr_line
		(start 166.337996 -9.947148)
		(end 166.591996 -9.947148)
		(stroke
			(width 0.1016)
			(type default)
		)
		(layer "In3.Cu")
	)
	(gr_line
		(start 166.337996 -9.847072)
		(end 166.591996 -9.847072)
		(stroke
			(width 0.1016)
			(type default)
		)
		(layer "In3.Cu")
	)
	(gr_line
		(start 166.337996 -8.312404)
		(end 166.337996 -5.747004)
		(stroke
			(width 0.1016)
			(type default)
		)
		(layer "In3.Cu")
	)
	(gr_line
		(start 166.337996 -8.212328)
		(end 166.337996 -5.646928)
		(stroke
			(width 0.1016)
			(type default)
		)
		(layer "In3.Cu")
	)
	(gr_line
		(start 166.337996 -5.747004)
		(end 166.591996 -5.747004)
		(stroke
			(width 0.1016)
			(type default)
		)
		(layer "In3.Cu")
	)
	(gr_line
		(start 166.337996 -5.646928)
		(end 166.591996 -5.646928)
		(stroke
			(width 0.1016)
			(type default)
		)
		(layer "In3.Cu")
	)
	(gr_line
		(start 166.337996 -4.11226)
		(end 166.337996 -1.54686)
		(stroke
			(width 0.1016)
			(type default)
		)
		(layer "In3.Cu")
	)
	(gr_line
		(start 166.337996 -4.012184)
		(end 166.337996 -1.446784)
		(stroke
			(width 0.1016)
			(type default)
		)
		(layer "In3.Cu")
	)
	(gr_line
		(start 166.337996 -1.54686)
		(end 166.591996 -1.54686)
		(stroke
			(width 0.1016)
			(type default)
		)
		(layer "In3.Cu")
	)
	(gr_line
		(start 166.337996 -1.446784)
		(end 166.591996 -1.446784)
		(stroke
			(width 0.1016)
			(type default)
		)
		(layer "In3.Cu")
	)
	(gr_line
		(start 166.363396 -12.512548)
		(end 166.363396 -9.947148)
		(stroke
			(width 0.2032)
			(type default)
		)
		(layer "In3.Cu")
	)
	(gr_line
		(start 166.363396 -12.412472)
		(end 166.363396 -9.847072)
		(stroke
			(width 0.2032)
			(type default)
		)
		(layer "In3.Cu")
	)
	(gr_line
		(start 166.363396 -9.947148)
		(end 167.379396 -9.947148)
		(stroke
			(width 0.2032)
			(type default)
		)
		(layer "In3.Cu")
	)
	(gr_line
		(start 166.363396 -9.847072)
		(end 167.379396 -9.847072)
		(stroke
			(width 0.2032)
			(type default)
		)
		(layer "In3.Cu")
	)
	(gr_line
		(start 166.363396 -8.312404)
		(end 166.363396 -5.747004)
		(stroke
			(width 0.2032)
			(type default)
		)
		(layer "In3.Cu")
	)
	(gr_line
		(start 166.363396 -8.212328)
		(end 166.363396 -5.646928)
		(stroke
			(width 0.2032)
			(type default)
		)
		(layer "In3.Cu")
	)
	(gr_line
		(start 166.363396 -5.747004)
		(end 167.379396 -5.747004)
		(stroke
			(width 0.2032)
			(type default)
		)
		(layer "In3.Cu")
	)
	(gr_line
		(start 166.363396 -5.646928)
		(end 167.379396 -5.646928)
		(stroke
			(width 0.2032)
			(type default)
		)
		(layer "In3.Cu")
	)
	(gr_line
		(start 166.363396 -4.11226)
		(end 166.363396 -1.54686)
		(stroke
			(width 0.2032)
			(type default)
		)
		(layer "In3.Cu")
	)
	(gr_line
		(start 166.363396 -4.012184)
		(end 166.363396 -1.446784)
		(stroke
			(width 0.2032)
			(type default)
		)
		(layer "In3.Cu")
	)
	(gr_line
		(start 166.363396 -1.54686)
		(end 167.379396 -1.54686)
		(stroke
			(width 0.2032)
			(type default)
		)
		(layer "In3.Cu")
	)
	(gr_line
		(start 166.363396 -1.446784)
		(end 167.379396 -1.446784)
		(stroke
			(width 0.2032)
			(type default)
		)
		(layer "In3.Cu")
	)
	(gr_line
		(start 166.414196 -12.487148)
		(end 166.414196 -9.997948)
		(stroke
			(width 0.2032)
			(type default)
		)
		(layer "In3.Cu")
	)
	(gr_line
		(start 166.414196 -12.487148)
		(end 166.414196 -9.997948)
		(stroke
			(width 0.254)
			(type default)
		)
		(layer "In3.Cu")
	)
	(gr_line
		(start 166.414196 -12.387072)
		(end 166.414196 -9.897872)
		(stroke
			(width 0.2032)
			(type default)
		)
		(layer "In3.Cu")
	)
	(gr_line
		(start 166.414196 -12.387072)
		(end 166.414196 -9.897872)
		(stroke
			(width 0.254)
			(type default)
		)
		(layer "In3.Cu")
	)
	(gr_line
		(start 166.414196 -9.997948)
		(end 166.617396 -9.997948)
		(stroke
			(width 0.2032)
			(type default)
		)
		(layer "In3.Cu")
	)
	(gr_line
		(start 166.414196 -9.997948)
		(end 167.303196 -9.997948)
		(stroke
			(width 0.254)
			(type default)
		)
		(layer "In3.Cu")
	)
	(gr_line
		(start 166.414196 -9.897872)
		(end 166.617396 -9.897872)
		(stroke
			(width 0.2032)
			(type default)
		)
		(layer "In3.Cu")
	)
	(gr_line
		(start 166.414196 -9.897872)
		(end 167.303196 -9.897872)
		(stroke
			(width 0.254)
			(type default)
		)
		(layer "In3.Cu")
	)
	(gr_line
		(start 166.414196 -8.287004)
		(end 166.414196 -5.797804)
		(stroke
			(width 0.2032)
			(type default)
		)
		(layer "In3.Cu")
	)
	(gr_line
		(start 166.414196 -8.287004)
		(end 166.414196 -5.797804)
		(stroke
			(width 0.254)
			(type default)
		)
		(layer "In3.Cu")
	)
	(gr_line
		(start 166.414196 -8.186928)
		(end 166.414196 -5.697728)
		(stroke
			(width 0.2032)
			(type default)
		)
		(layer "In3.Cu")
	)
	(gr_line
		(start 166.414196 -8.186928)
		(end 166.414196 -5.697728)
		(stroke
			(width 0.254)
			(type default)
		)
		(layer "In3.Cu")
	)
	(gr_line
		(start 166.414196 -5.797804)
		(end 166.617396 -5.797804)
		(stroke
			(width 0.2032)
			(type default)
		)
		(layer "In3.Cu")
	)
	(gr_line
		(start 166.414196 -5.797804)
		(end 167.303196 -5.797804)
		(stroke
			(width 0.254)
			(type default)
		)
		(layer "In3.Cu")
	)
	(gr_line
		(start 166.414196 -5.697728)
		(end 166.617396 -5.697728)
		(stroke
			(width 0.2032)
			(type default)
		)
		(layer "In3.Cu")
	)
	(gr_line
		(start 166.414196 -5.697728)
		(end 167.303196 -5.697728)
		(stroke
			(width 0.254)
			(type default)
		)
		(layer "In3.Cu")
	)
	(gr_line
		(start 166.414196 -4.08686)
		(end 166.414196 -1.59766)
		(stroke
			(width 0.2032)
			(type default)
		)
		(layer "In3.Cu")
	)
	(gr_line
		(start 166.414196 -4.08686)
		(end 166.414196 -1.59766)
		(stroke
			(width 0.254)
			(type default)
		)
		(layer "In3.Cu")
	)
	(gr_line
		(start 166.414196 -3.986784)
		(end 166.414196 -1.497584)
		(stroke
			(width 0.2032)
			(type default)
		)
		(layer "In3.Cu")
	)
	(gr_line
		(start 166.414196 -3.986784)
		(end 166.414196 -1.497584)
		(stroke
			(width 0.254)
			(type default)
		)
		(layer "In3.Cu")
	)
	(gr_line
		(start 166.414196 -1.59766)
		(end 166.617396 -1.59766)
		(stroke
			(width 0.2032)
			(type default)
		)
		(layer "In3.Cu")
	)
	(gr_line
		(start 166.414196 -1.59766)
		(end 167.303196 -1.59766)
		(stroke
			(width 0.254)
			(type default)
		)
		(layer "In3.Cu")
	)
	(gr_line
		(start 166.414196 -1.497584)
		(end 166.617396 -1.497584)
		(stroke
			(width 0.2032)
			(type default)
		)
		(layer "In3.Cu")
	)
	(gr_line
		(start 166.414196 -1.497584)
		(end 167.303196 -1.497584)
		(stroke
			(width 0.254)
			(type default)
		)
		(layer "In3.Cu")
	)
	(gr_line
		(start 166.439596 -12.461748)
		(end 166.439596 -10.023348)
		(stroke
			(width 0.254)
			(type default)
		)
		(layer "In3.Cu")
	)
	(gr_line
		(start 166.439596 -12.361672)
		(end 166.439596 -9.923272)
		(stroke
			(width 0.254)
			(type default)
		)
		(layer "In3.Cu")
	)
	(gr_line
		(start 166.439596 -10.023348)
		(end 167.277796 -10.023348)
		(stroke
			(width 0.254)
			(type default)
		)
		(layer "In3.Cu")
	)
	(gr_line
		(start 166.439596 -9.923272)
		(end 167.277796 -9.923272)
		(stroke
			(width 0.254)
			(type default)
		)
		(layer "In3.Cu")
	)
	(gr_line
		(start 166.439596 -8.261604)
		(end 166.439596 -5.823204)
		(stroke
			(width 0.254)
			(type default)
		)
		(layer "In3.Cu")
	)
	(gr_line
		(start 166.439596 -8.161528)
		(end 166.439596 -5.723128)
		(stroke
			(width 0.254)
			(type default)
		)
		(layer "In3.Cu")
	)
	(gr_line
		(start 166.439596 -5.823204)
		(end 167.277796 -5.823204)
		(stroke
			(width 0.254)
			(type default)
		)
		(layer "In3.Cu")
	)
	(gr_line
		(start 166.439596 -5.723128)
		(end 167.277796 -5.723128)
		(stroke
			(width 0.254)
			(type default)
		)
		(layer "In3.Cu")
	)
	(gr_line
		(start 166.439596 -4.06146)
		(end 166.439596 -1.62306)
		(stroke
			(width 0.254)
			(type default)
		)
		(layer "In3.Cu")
	)
	(gr_line
		(start 166.439596 -3.961384)
		(end 166.439596 -1.522984)
		(stroke
			(width 0.254)
			(type default)
		)
		(layer "In3.Cu")
	)
	(gr_line
		(start 166.439596 -1.62306)
		(end 167.277796 -1.62306)
		(stroke
			(width 0.254)
			(type default)
		)
		(layer "In3.Cu")
	)
	(gr_line
		(start 166.439596 -1.522984)
		(end 167.277796 -1.522984)
		(stroke
			(width 0.254)
			(type default)
		)
		(layer "In3.Cu")
	)
	(gr_line
		(start 166.464996 -12.436348)
		(end 166.464996 -10.048748)
		(stroke
			(width 0.254)
			(type default)
		)
		(layer "In3.Cu")
	)
	(gr_line
		(start 166.464996 -12.336272)
		(end 166.464996 -9.948672)
		(stroke
			(width 0.254)
			(type default)
		)
		(layer "In3.Cu")
	)
	(gr_line
		(start 166.464996 -10.048748)
		(end 167.252396 -10.048748)
		(stroke
			(width 0.254)
			(type default)
		)
		(layer "In3.Cu")
	)
	(gr_line
		(start 166.464996 -9.948672)
		(end 167.252396 -9.948672)
		(stroke
			(width 0.254)
			(type default)
		)
		(layer "In3.Cu")
	)
	(gr_line
		(start 166.464996 -8.236204)
		(end 166.464996 -5.848604)
		(stroke
			(width 0.254)
			(type default)
		)
		(layer "In3.Cu")
	)
	(gr_line
		(start 166.464996 -8.136128)
		(end 166.464996 -5.748528)
		(stroke
			(width 0.254)
			(type default)
		)
		(layer "In3.Cu")
	)
	(gr_line
		(start 166.464996 -5.848604)
		(end 167.252396 -5.848604)
		(stroke
			(width 0.254)
			(type default)
		)
		(layer "In3.Cu")
	)
	(gr_line
		(start 166.464996 -5.748528)
		(end 167.252396 -5.748528)
		(stroke
			(width 0.254)
			(type default)
		)
		(layer "In3.Cu")
	)
	(gr_line
		(start 166.464996 -4.03606)
		(end 166.464996 -1.64846)
		(stroke
			(width 0.254)
			(type default)
		)
		(layer "In3.Cu")
	)
	(gr_line
		(start 166.464996 -3.935984)
		(end 166.464996 -1.548384)
		(stroke
			(width 0.254)
			(type default)
		)
		(layer "In3.Cu")
	)
	(gr_line
		(start 166.464996 -1.64846)
		(end 167.252396 -1.64846)
		(stroke
			(width 0.254)
			(type default)
		)
		(layer "In3.Cu")
	)
	(gr_line
		(start 166.464996 -1.548384)
		(end 167.252396 -1.548384)
		(stroke
			(width 0.254)
			(type default)
		)
		(layer "In3.Cu")
	)
	(gr_line
		(start 166.490396 -12.360148)
		(end 167.125396 -12.360148)
		(stroke
			(width 0.508)
			(type default)
		)
		(layer "In3.Cu")
	)
	(gr_line
		(start 166.490396 -12.260072)
		(end 167.125396 -12.260072)
		(stroke
			(width 0.508)
			(type default)
		)
		(layer "In3.Cu")
	)
	(gr_line
		(start 166.490396 -10.175748)
		(end 167.125396 -10.175748)
		(stroke
			(width 0.508)
			(type default)
		)
		(layer "In3.Cu")
	)
	(gr_line
		(start 166.490396 -10.124948)
		(end 167.125396 -10.124948)
		(stroke
			(width 0.508)
			(type default)
		)
		(layer "In3.Cu")
	)
	(gr_line
		(start 166.490396 -10.075672)
		(end 167.125396 -10.075672)
		(stroke
			(width 0.508)
			(type default)
		)
		(layer "In3.Cu")
	)
	(gr_line
		(start 166.490396 -10.024872)
		(end 167.125396 -10.024872)
		(stroke
			(width 0.508)
			(type default)
		)
		(layer "In3.Cu")
	)
	(gr_line
		(start 166.490396 -8.160004)
		(end 167.125396 -8.160004)
		(stroke
			(width 0.508)
			(type default)
		)
		(layer "In3.Cu")
	)
	(gr_line
		(start 166.490396 -8.059928)
		(end 167.125396 -8.059928)
		(stroke
			(width 0.508)
			(type default)
		)
		(layer "In3.Cu")
	)
	(gr_line
		(start 166.490396 -5.975604)
		(end 167.125396 -5.975604)
		(stroke
			(width 0.508)
			(type default)
		)
		(layer "In3.Cu")
	)
	(gr_line
		(start 166.490396 -5.924804)
		(end 167.125396 -5.924804)
		(stroke
			(width 0.508)
			(type default)
		)
		(layer "In3.Cu")
	)
	(gr_line
		(start 166.490396 -5.875528)
		(end 167.125396 -5.875528)
		(stroke
			(width 0.508)
			(type default)
		)
		(layer "In3.Cu")
	)
	(gr_line
		(start 166.490396 -5.824728)
		(end 167.125396 -5.824728)
		(stroke
			(width 0.508)
			(type default)
		)
		(layer "In3.Cu")
	)
	(gr_line
		(start 166.490396 -3.95986)
		(end 167.125396 -3.95986)
		(stroke
			(width 0.508)
			(type default)
		)
		(layer "In3.Cu")
	)
	(gr_line
		(start 166.490396 -3.859784)
		(end 167.125396 -3.859784)
		(stroke
			(width 0.508)
			(type default)
		)
		(layer "In3.Cu")
	)
	(gr_line
		(start 166.490396 -1.77546)
		(end 167.125396 -1.77546)
		(stroke
			(width 0.508)
			(type default)
		)
		(layer "In3.Cu")
	)
	(gr_line
		(start 166.490396 -1.72466)
		(end 167.125396 -1.72466)
		(stroke
			(width 0.508)
			(type default)
		)
		(layer "In3.Cu")
	)
	(gr_line
		(start 166.490396 -1.675384)
		(end 167.125396 -1.675384)
		(stroke
			(width 0.508)
			(type default)
		)
		(layer "In3.Cu")
	)
	(gr_line
		(start 166.490396 -1.624584)
		(end 167.125396 -1.624584)
		(stroke
			(width 0.508)
			(type default)
		)
		(layer "In3.Cu")
	)
	(gr_line
		(start 166.515796 -10.429748)
		(end 167.150796 -10.429748)
		(stroke
			(width 0.508)
			(type default)
		)
		(layer "In3.Cu")
	)
	(gr_line
		(start 166.515796 -10.329672)
		(end 167.150796 -10.329672)
		(stroke
			(width 0.508)
			(type default)
		)
		(layer "In3.Cu")
	)
	(gr_line
		(start 166.515796 -6.229604)
		(end 167.150796 -6.229604)
		(stroke
			(width 0.508)
			(type default)
		)
		(layer "In3.Cu")
	)
	(gr_line
		(start 166.515796 -6.129528)
		(end 167.150796 -6.129528)
		(stroke
			(width 0.508)
			(type default)
		)
		(layer "In3.Cu")
	)
	(gr_line
		(start 166.515796 -2.02946)
		(end 167.150796 -2.02946)
		(stroke
			(width 0.508)
			(type default)
		)
		(layer "In3.Cu")
	)
	(gr_line
		(start 166.515796 -1.929384)
		(end 167.150796 -1.929384)
		(stroke
			(width 0.508)
			(type default)
		)
		(layer "In3.Cu")
	)
	(gr_line
		(start 166.541196 -12.385548)
		(end 166.541196 -10.124948)
		(stroke
			(width 0.254)
			(type default)
		)
		(layer "In3.Cu")
	)
	(gr_line
		(start 166.541196 -12.285472)
		(end 166.541196 -10.024872)
		(stroke
			(width 0.254)
			(type default)
		)
		(layer "In3.Cu")
	)
	(gr_line
		(start 166.541196 -12.233148)
		(end 167.176196 -12.233148)
		(stroke
			(width 0.508)
			(type default)
		)
		(layer "In3.Cu")
	)
	(gr_line
		(start 166.541196 -12.133072)
		(end 167.176196 -12.133072)
		(stroke
			(width 0.508)
			(type default)
		)
		(layer "In3.Cu")
	)
	(gr_line
		(start 166.541196 -10.124948)
		(end 167.176196 -10.124948)
		(stroke
			(width 0.254)
			(type default)
		)
		(layer "In3.Cu")
	)
	(gr_line
		(start 166.541196 -10.024872)
		(end 167.176196 -10.024872)
		(stroke
			(width 0.254)
			(type default)
		)
		(layer "In3.Cu")
	)
	(gr_line
		(start 166.541196 -8.185404)
		(end 166.541196 -5.924804)
		(stroke
			(width 0.254)
			(type default)
		)
		(layer "In3.Cu")
	)
	(gr_line
		(start 166.541196 -8.085328)
		(end 166.541196 -5.824728)
		(stroke
			(width 0.254)
			(type default)
		)
		(layer "In3.Cu")
	)
	(gr_line
		(start 166.541196 -8.033004)
		(end 167.176196 -8.033004)
		(stroke
			(width 0.508)
			(type default)
		)
		(layer "In3.Cu")
	)
	(gr_line
		(start 166.541196 -7.932928)
		(end 167.176196 -7.932928)
		(stroke
			(width 0.508)
			(type default)
		)
		(layer "In3.Cu")
	)
	(gr_line
		(start 166.541196 -5.924804)
		(end 167.176196 -5.924804)
		(stroke
			(width 0.254)
			(type default)
		)
		(layer "In3.Cu")
	)
	(gr_line
		(start 166.541196 -5.824728)
		(end 167.176196 -5.824728)
		(stroke
			(width 0.254)
			(type default)
		)
		(layer "In3.Cu")
	)
	(gr_line
		(start 166.541196 -3.98526)
		(end 166.541196 -1.72466)
		(stroke
			(width 0.254)
			(type default)
		)
		(layer "In3.Cu")
	)
	(gr_line
		(start 166.541196 -3.885184)
		(end 166.541196 -1.624584)
		(stroke
			(width 0.254)
			(type default)
		)
		(layer "In3.Cu")
	)
	(gr_line
		(start 166.541196 -3.83286)
		(end 167.176196 -3.83286)
		(stroke
			(width 0.508)
			(type default)
		)
		(layer "In3.Cu")
	)
	(gr_line
		(start 166.541196 -3.732784)
		(end 167.176196 -3.732784)
		(stroke
			(width 0.508)
			(type default)
		)
		(layer "In3.Cu")
	)
	(gr_line
		(start 166.541196 -1.72466)
		(end 167.176196 -1.72466)
		(stroke
			(width 0.254)
			(type default)
		)
		(layer "In3.Cu")
	)
	(gr_line
		(start 166.541196 -1.624584)
		(end 167.176196 -1.624584)
		(stroke
			(width 0.254)
			(type default)
		)
		(layer "In3.Cu")
	)
	(gr_line
		(start 166.566596 -12.080748)
		(end 167.201596 -12.080748)
		(stroke
			(width 0.508)
			(type default)
		)
		(layer "In3.Cu")
	)
	(gr_line
		(start 166.566596 -11.980672)
		(end 167.201596 -11.980672)
		(stroke
			(width 0.508)
			(type default)
		)
		(layer "In3.Cu")
	)
	(gr_line
		(start 166.566596 -7.880604)
		(end 167.201596 -7.880604)
		(stroke
			(width 0.508)
			(type default)
		)
		(layer "In3.Cu")
	)
	(gr_line
		(start 166.566596 -7.780528)
		(end 167.201596 -7.780528)
		(stroke
			(width 0.508)
			(type default)
		)
		(layer "In3.Cu")
	)
	(gr_line
		(start 166.566596 -3.68046)
		(end 167.201596 -3.68046)
		(stroke
			(width 0.508)
			(type default)
		)
		(layer "In3.Cu")
	)
	(gr_line
		(start 166.566596 -3.580384)
		(end 167.201596 -3.580384)
		(stroke
			(width 0.508)
			(type default)
		)
		(layer "In3.Cu")
	)
	(gr_line
		(start 166.591996 -12.360148)
		(end 167.226996 -12.360148)
		(stroke
			(width 0.508)
			(type default)
		)
		(layer "In3.Cu")
	)
	(gr_line
		(start 166.591996 -12.260072)
		(end 167.226996 -12.260072)
		(stroke
			(width 0.508)
			(type default)
		)
		(layer "In3.Cu")
	)
	(gr_line
		(start 166.591996 -9.947148)
		(end 167.430196 -9.947148)
		(stroke
			(width 0.2032)
			(type default)
		)
		(layer "In3.Cu")
	)
	(gr_line
		(start 166.591996 -9.847072)
		(end 167.430196 -9.847072)
		(stroke
			(width 0.2032)
			(type default)
		)
		(layer "In3.Cu")
	)
	(gr_line
		(start 166.591996 -8.160004)
		(end 167.226996 -8.160004)
		(stroke
			(width 0.508)
			(type default)
		)
		(layer "In3.Cu")
	)
	(gr_line
		(start 166.591996 -8.059928)
		(end 167.226996 -8.059928)
		(stroke
			(width 0.508)
			(type default)
		)
		(layer "In3.Cu")
	)
	(gr_line
		(start 166.591996 -5.747004)
		(end 167.430196 -5.747004)
		(stroke
			(width 0.2032)
			(type default)
		)
		(layer "In3.Cu")
	)
	(gr_line
		(start 166.591996 -5.646928)
		(end 167.430196 -5.646928)
		(stroke
			(width 0.2032)
			(type default)
		)
		(layer "In3.Cu")
	)
	(gr_line
		(start 166.591996 -3.95986)
		(end 167.226996 -3.95986)
		(stroke
			(width 0.508)
			(type default)
		)
		(layer "In3.Cu")
	)
	(gr_line
		(start 166.591996 -3.859784)
		(end 167.226996 -3.859784)
		(stroke
			(width 0.508)
			(type default)
		)
		(layer "In3.Cu")
	)
	(gr_line
		(start 166.591996 -1.54686)
		(end 167.430196 -1.54686)
		(stroke
			(width 0.2032)
			(type default)
		)
		(layer "In3.Cu")
	)
	(gr_line
		(start 166.591996 -1.446784)
		(end 167.430196 -1.446784)
		(stroke
			(width 0.2032)
			(type default)
		)
		(layer "In3.Cu")
	)
	(gr_line
		(start 166.617396 -12.360148)
		(end 166.617396 -10.175748)
		(stroke
			(width 0.254)
			(type default)
		)
		(layer "In3.Cu")
	)
	(gr_line
		(start 166.617396 -12.260072)
		(end 166.617396 -10.075672)
		(stroke
			(width 0.254)
			(type default)
		)
		(layer "In3.Cu")
	)
	(gr_line
		(start 166.617396 -10.175748)
		(end 167.099996 -10.175748)
		(stroke
			(width 0.254)
			(type default)
		)
		(layer "In3.Cu")
	)
	(gr_line
		(start 166.617396 -10.075672)
		(end 167.099996 -10.075672)
		(stroke
			(width 0.254)
			(type default)
		)
		(layer "In3.Cu")
	)
	(gr_line
		(start 166.617396 -9.997948)
		(end 167.353996 -9.997948)
		(stroke
			(width 0.254)
			(type default)
		)
		(layer "In3.Cu")
	)
	(gr_line
		(start 166.617396 -9.897872)
		(end 167.353996 -9.897872)
		(stroke
			(width 0.254)
			(type default)
		)
		(layer "In3.Cu")
	)
	(gr_line
		(start 166.617396 -8.160004)
		(end 166.617396 -5.975604)
		(stroke
			(width 0.254)
			(type default)
		)
		(layer "In3.Cu")
	)
	(gr_line
		(start 166.617396 -8.059928)
		(end 166.617396 -5.875528)
		(stroke
			(width 0.254)
			(type default)
		)
		(layer "In3.Cu")
	)
	(gr_line
		(start 166.617396 -5.975604)
		(end 167.099996 -5.975604)
		(stroke
			(width 0.254)
			(type default)
		)
		(layer "In3.Cu")
	)
	(gr_line
		(start 166.617396 -5.875528)
		(end 167.099996 -5.875528)
		(stroke
			(width 0.254)
			(type default)
		)
		(layer "In3.Cu")
	)
	(gr_line
		(start 166.617396 -5.797804)
		(end 167.353996 -5.797804)
		(stroke
			(width 0.254)
			(type default)
		)
		(layer "In3.Cu")
	)
	(gr_line
		(start 166.617396 -5.697728)
		(end 167.353996 -5.697728)
		(stroke
			(width 0.254)
			(type default)
		)
		(layer "In3.Cu")
	)
	(gr_line
		(start 166.617396 -3.95986)
		(end 166.617396 -1.77546)
		(stroke
			(width 0.254)
			(type default)
		)
		(layer "In3.Cu")
	)
	(gr_line
		(start 166.617396 -3.859784)
		(end 166.617396 -1.675384)
		(stroke
			(width 0.254)
			(type default)
		)
		(layer "In3.Cu")
	)
	(gr_line
		(start 166.617396 -1.77546)
		(end 167.099996 -1.77546)
		(stroke
			(width 0.254)
			(type default)
		)
		(layer "In3.Cu")
	)
	(gr_line
		(start 166.617396 -1.675384)
		(end 167.099996 -1.675384)
		(stroke
			(width 0.254)
			(type default)
		)
		(layer "In3.Cu")
	)
	(gr_line
		(start 166.617396 -1.59766)
		(end 167.353996 -1.59766)
		(stroke
			(width 0.254)
			(type default)
		)
		(layer "In3.Cu")
	)
	(gr_line
		(start 166.617396 -1.497584)
		(end 167.353996 -1.497584)
		(stroke
			(width 0.254)
			(type default)
		)
		(layer "In3.Cu")
	)
	(gr_line
		(start 166.635938 -10.110978)
		(end 167.270938 -10.110978)
		(stroke
			(width 0.508)
			(type default)
		)
		(layer "In3.Cu")
	)
	(gr_line
		(start 166.635938 -10.010902)
		(end 167.270938 -10.010902)
		(stroke
			(width 0.508)
			(type default)
		)
		(layer "In3.Cu")
	)
	(gr_line
		(start 166.635938 -5.910834)
		(end 167.270938 -5.910834)
		(stroke
			(width 0.508)
			(type default)
		)
		(layer "In3.Cu")
	)
	(gr_line
		(start 166.635938 -5.810758)
		(end 167.270938 -5.810758)
		(stroke
			(width 0.508)
			(type default)
		)
		(layer "In3.Cu")
	)
	(gr_line
		(start 166.635938 -1.71069)
		(end 167.270938 -1.71069)
		(stroke
			(width 0.508)
			(type default)
		)
		(layer "In3.Cu")
	)
	(gr_line
		(start 166.635938 -1.610614)
		(end 167.270938 -1.610614)
		(stroke
			(width 0.508)
			(type default)
		)
		(layer "In3.Cu")
	)
	(gr_line
		(start 166.642796 -12.360148)
		(end 167.277796 -12.360148)
		(stroke
			(width 0.508)
			(type default)
		)
		(layer "In3.Cu")
	)
	(gr_line
		(start 166.642796 -12.260072)
		(end 167.277796 -12.260072)
		(stroke
			(width 0.508)
			(type default)
		)
		(layer "In3.Cu")
	)
	(gr_line
		(start 166.642796 -12.233148)
		(end 166.642796 -10.251948)
		(stroke
			(width 0.762)
			(type default)
		)
		(layer "In3.Cu")
	)
	(gr_line
		(start 166.642796 -12.133072)
		(end 166.642796 -10.151872)
		(stroke
			(width 0.762)
			(type default)
		)
		(layer "In3.Cu")
	)
	(gr_line
		(start 166.642796 -10.251948)
		(end 167.277796 -10.251948)
		(stroke
			(width 0.508)
			(type default)
		)
		(layer "In3.Cu")
	)
	(gr_line
		(start 166.642796 -10.151872)
		(end 167.277796 -10.151872)
		(stroke
			(width 0.508)
			(type default)
		)
		(layer "In3.Cu")
	)
	(gr_line
		(start 166.642796 -8.160004)
		(end 167.277796 -8.160004)
		(stroke
			(width 0.508)
			(type default)
		)
		(layer "In3.Cu")
	)
	(gr_line
		(start 166.642796 -8.059928)
		(end 167.277796 -8.059928)
		(stroke
			(width 0.508)
			(type default)
		)
		(layer "In3.Cu")
	)
	(gr_line
		(start 166.642796 -8.033004)
		(end 166.642796 -6.051804)
		(stroke
			(width 0.762)
			(type default)
		)
		(layer "In3.Cu")
	)
	(gr_line
		(start 166.642796 -7.932928)
		(end 166.642796 -5.951728)
		(stroke
			(width 0.762)
			(type default)
		)
		(layer "In3.Cu")
	)
	(gr_line
		(start 166.642796 -6.051804)
		(end 167.277796 -6.051804)
		(stroke
			(width 0.508)
			(type default)
		)
		(layer "In3.Cu")
	)
	(gr_line
		(start 166.642796 -5.951728)
		(end 167.277796 -5.951728)
		(stroke
			(width 0.508)
			(type default)
		)
		(layer "In3.Cu")
	)
	(gr_line
		(start 166.642796 -3.95986)
		(end 167.277796 -3.95986)
		(stroke
			(width 0.508)
			(type default)
		)
		(layer "In3.Cu")
	)
	(gr_line
		(start 166.642796 -3.859784)
		(end 167.277796 -3.859784)
		(stroke
			(width 0.508)
			(type default)
		)
		(layer "In3.Cu")
	)
	(gr_line
		(start 166.642796 -3.83286)
		(end 166.642796 -1.85166)
		(stroke
			(width 0.762)
			(type default)
		)
		(layer "In3.Cu")
	)
	(gr_line
		(start 166.642796 -3.732784)
		(end 166.642796 -1.751584)
		(stroke
			(width 0.762)
			(type default)
		)
		(layer "In3.Cu")
	)
	(gr_line
		(start 166.642796 -1.85166)
		(end 167.277796 -1.85166)
		(stroke
			(width 0.508)
			(type default)
		)
		(layer "In3.Cu")
	)
	(gr_line
		(start 166.642796 -1.751584)
		(end 167.277796 -1.751584)
		(stroke
			(width 0.508)
			(type default)
		)
		(layer "In3.Cu")
	)
	(gr_line
		(start 166.693596 -12.283948)
		(end 166.693596 -10.251948)
		(stroke
			(width 0.254)
			(type default)
		)
		(layer "In3.Cu")
	)
	(gr_line
		(start 166.693596 -12.183872)
		(end 166.693596 -10.151872)
		(stroke
			(width 0.254)
			(type default)
		)
		(layer "In3.Cu")
	)
	(gr_line
		(start 166.693596 -10.251948)
		(end 167.023796 -10.251948)
		(stroke
			(width 0.254)
			(type default)
		)
		(layer "In3.Cu")
	)
	(gr_line
		(start 166.693596 -10.151872)
		(end 167.023796 -10.151872)
		(stroke
			(width 0.254)
			(type default)
		)
		(layer "In3.Cu")
	)
	(gr_line
		(start 166.693596 -8.083804)
		(end 166.693596 -6.051804)
		(stroke
			(width 0.254)
			(type default)
		)
		(layer "In3.Cu")
	)
	(gr_line
		(start 166.693596 -7.983728)
		(end 166.693596 -5.951728)
		(stroke
			(width 0.254)
			(type default)
		)
		(layer "In3.Cu")
	)
	(gr_line
		(start 166.693596 -6.051804)
		(end 167.023796 -6.051804)
		(stroke
			(width 0.254)
			(type default)
		)
		(layer "In3.Cu")
	)
	(gr_line
		(start 166.693596 -5.951728)
		(end 167.023796 -5.951728)
		(stroke
			(width 0.254)
			(type default)
		)
		(layer "In3.Cu")
	)
	(gr_line
		(start 166.693596 -3.88366)
		(end 166.693596 -1.85166)
		(stroke
			(width 0.254)
			(type default)
		)
		(layer "In3.Cu")
	)
	(gr_line
		(start 166.693596 -3.783584)
		(end 166.693596 -1.751584)
		(stroke
			(width 0.254)
			(type default)
		)
		(layer "In3.Cu")
	)
	(gr_line
		(start 166.693596 -1.85166)
		(end 167.023796 -1.85166)
		(stroke
			(width 0.254)
			(type default)
		)
		(layer "In3.Cu")
	)
	(gr_line
		(start 166.693596 -1.751584)
		(end 167.023796 -1.751584)
		(stroke
			(width 0.254)
			(type default)
		)
		(layer "In3.Cu")
	)
	(gr_line
		(start 166.795196 -12.207748)
		(end 166.795196 -10.404348)
		(stroke
			(width 0.254)
			(type default)
		)
		(layer "In3.Cu")
	)
	(gr_line
		(start 166.795196 -12.207748)
		(end 166.795196 -10.226548)
		(stroke
			(width 0.762)
			(type default)
		)
		(layer "In3.Cu")
	)
	(gr_line
		(start 166.795196 -12.107672)
		(end 166.795196 -10.304272)
		(stroke
			(width 0.254)
			(type default)
		)
		(layer "In3.Cu")
	)
	(gr_line
		(start 166.795196 -12.107672)
		(end 166.795196 -10.126472)
		(stroke
			(width 0.762)
			(type default)
		)
		(layer "In3.Cu")
	)
	(gr_line
		(start 166.795196 -10.404348)
		(end 166.896796 -10.404348)
		(stroke
			(width 0.254)
			(type default)
		)
		(layer "In3.Cu")
	)
	(gr_line
		(start 166.795196 -10.304272)
		(end 166.896796 -10.304272)
		(stroke
			(width 0.254)
			(type default)
		)
		(layer "In3.Cu")
	)
	(gr_line
		(start 166.795196 -8.007604)
		(end 166.795196 -6.204204)
		(stroke
			(width 0.254)
			(type default)
		)
		(layer "In3.Cu")
	)
	(gr_line
		(start 166.795196 -8.007604)
		(end 166.795196 -6.026404)
		(stroke
			(width 0.762)
			(type default)
		)
		(layer "In3.Cu")
	)
	(gr_line
		(start 166.795196 -7.907528)
		(end 166.795196 -6.104128)
		(stroke
			(width 0.254)
			(type default)
		)
		(layer "In3.Cu")
	)
	(gr_line
		(start 166.795196 -7.907528)
		(end 166.795196 -5.926328)
		(stroke
			(width 0.762)
			(type default)
		)
		(layer "In3.Cu")
	)
	(gr_line
		(start 166.795196 -6.204204)
		(end 166.896796 -6.204204)
		(stroke
			(width 0.254)
			(type default)
		)
		(layer "In3.Cu")
	)
	(gr_line
		(start 166.795196 -6.104128)
		(end 166.896796 -6.104128)
		(stroke
			(width 0.254)
			(type default)
		)
		(layer "In3.Cu")
	)
	(gr_line
		(start 166.795196 -3.80746)
		(end 166.795196 -2.00406)
		(stroke
			(width 0.254)
			(type default)
		)
		(layer "In3.Cu")
	)
	(gr_line
		(start 166.795196 -3.80746)
		(end 166.795196 -1.82626)
		(stroke
			(width 0.762)
			(type default)
		)
		(layer "In3.Cu")
	)
	(gr_line
		(start 166.795196 -3.707384)
		(end 166.795196 -1.903984)
		(stroke
			(width 0.254)
			(type default)
		)
		(layer "In3.Cu")
	)
	(gr_line
		(start 166.795196 -3.707384)
		(end 166.795196 -1.726184)
		(stroke
			(width 0.762)
			(type default)
		)
		(layer "In3.Cu")
	)
	(gr_line
		(start 166.795196 -2.00406)
		(end 166.896796 -2.00406)
		(stroke
			(width 0.254)
			(type default)
		)
		(layer "In3.Cu")
	)
	(gr_line
		(start 166.795196 -1.903984)
		(end 166.896796 -1.903984)
		(stroke
			(width 0.254)
			(type default)
		)
		(layer "In3.Cu")
	)
	(gr_line
		(start 166.896796 -12.309348)
		(end 166.845996 -12.309348)
		(stroke
			(width 0.254)
			(type default)
		)
		(layer "In3.Cu")
	)
	(gr_line
		(start 166.896796 -12.209272)
		(end 166.845996 -12.209272)
		(stroke
			(width 0.254)
			(type default)
		)
		(layer "In3.Cu")
	)
	(gr_line
		(start 166.896796 -10.404348)
		(end 166.896796 -12.309348)
		(stroke
			(width 0.254)
			(type default)
		)
		(layer "In3.Cu")
	)
	(gr_line
		(start 166.896796 -10.304272)
		(end 166.896796 -12.209272)
		(stroke
			(width 0.254)
			(type default)
		)
		(layer "In3.Cu")
	)
	(gr_line
		(start 166.896796 -8.109204)
		(end 166.845996 -8.109204)
		(stroke
			(width 0.254)
			(type default)
		)
		(layer "In3.Cu")
	)
	(gr_line
		(start 166.896796 -8.009128)
		(end 166.845996 -8.009128)
		(stroke
			(width 0.254)
			(type default)
		)
		(layer "In3.Cu")
	)
	(gr_line
		(start 166.896796 -6.204204)
		(end 166.896796 -8.109204)
		(stroke
			(width 0.254)
			(type default)
		)
		(layer "In3.Cu")
	)
	(gr_line
		(start 166.896796 -6.104128)
		(end 166.896796 -8.009128)
		(stroke
			(width 0.254)
			(type default)
		)
		(layer "In3.Cu")
	)
	(gr_line
		(start 166.896796 -3.90906)
		(end 166.845996 -3.90906)
		(stroke
			(width 0.254)
			(type default)
		)
		(layer "In3.Cu")
	)
	(gr_line
		(start 166.896796 -3.808984)
		(end 166.845996 -3.808984)
		(stroke
			(width 0.254)
			(type default)
		)
		(layer "In3.Cu")
	)
	(gr_line
		(start 166.896796 -2.00406)
		(end 166.896796 -3.90906)
		(stroke
			(width 0.254)
			(type default)
		)
		(layer "In3.Cu")
	)
	(gr_line
		(start 166.896796 -1.903984)
		(end 166.896796 -3.808984)
		(stroke
			(width 0.254)
			(type default)
		)
		(layer "In3.Cu")
	)
	(gr_line
		(start 166.947596 -12.233148)
		(end 166.947596 -10.251948)
		(stroke
			(width 0.762)
			(type default)
		)
		(layer "In3.Cu")
	)
	(gr_line
		(start 166.947596 -12.133072)
		(end 166.947596 -10.151872)
		(stroke
			(width 0.762)
			(type default)
		)
		(layer "In3.Cu")
	)
	(gr_line
		(start 166.947596 -8.033004)
		(end 166.947596 -6.051804)
		(stroke
			(width 0.762)
			(type default)
		)
		(layer "In3.Cu")
	)
	(gr_line
		(start 166.947596 -7.932928)
		(end 166.947596 -5.951728)
		(stroke
			(width 0.762)
			(type default)
		)
		(layer "In3.Cu")
	)
	(gr_line
		(start 166.947596 -3.83286)
		(end 166.947596 -1.85166)
		(stroke
			(width 0.762)
			(type default)
		)
		(layer "In3.Cu")
	)
	(gr_line
		(start 166.947596 -3.732784)
		(end 166.947596 -1.751584)
		(stroke
			(width 0.762)
			(type default)
		)
		(layer "In3.Cu")
	)
	(gr_line
		(start 167.023796 -12.207748)
		(end 166.795196 -12.207748)
		(stroke
			(width 0.254)
			(type default)
		)
		(layer "In3.Cu")
	)
	(gr_line
		(start 167.023796 -12.107672)
		(end 166.795196 -12.107672)
		(stroke
			(width 0.254)
			(type default)
		)
		(layer "In3.Cu")
	)
	(gr_line
		(start 167.023796 -10.251948)
		(end 167.023796 -12.207748)
		(stroke
			(width 0.254)
			(type default)
		)
		(layer "In3.Cu")
	)
	(gr_line
		(start 167.023796 -10.151872)
		(end 167.023796 -12.107672)
		(stroke
			(width 0.254)
			(type default)
		)
		(layer "In3.Cu")
	)
	(gr_line
		(start 167.023796 -8.007604)
		(end 166.795196 -8.007604)
		(stroke
			(width 0.254)
			(type default)
		)
		(layer "In3.Cu")
	)
	(gr_line
		(start 167.023796 -7.907528)
		(end 166.795196 -7.907528)
		(stroke
			(width 0.254)
			(type default)
		)
		(layer "In3.Cu")
	)
	(gr_line
		(start 167.023796 -6.051804)
		(end 167.023796 -8.007604)
		(stroke
			(width 0.254)
			(type default)
		)
		(layer "In3.Cu")
	)
	(gr_line
		(start 167.023796 -5.951728)
		(end 167.023796 -7.907528)
		(stroke
			(width 0.254)
			(type default)
		)
		(layer "In3.Cu")
	)
	(gr_line
		(start 167.023796 -3.80746)
		(end 166.795196 -3.80746)
		(stroke
			(width 0.254)
			(type default)
		)
		(layer "In3.Cu")
	)
	(gr_line
		(start 167.023796 -3.707384)
		(end 166.795196 -3.707384)
		(stroke
			(width 0.254)
			(type default)
		)
		(layer "In3.Cu")
	)
	(gr_line
		(start 167.023796 -1.85166)
		(end 167.023796 -3.80746)
		(stroke
			(width 0.254)
			(type default)
		)
		(layer "In3.Cu")
	)
	(gr_line
		(start 167.023796 -1.751584)
		(end 167.023796 -3.707384)
		(stroke
			(width 0.254)
			(type default)
		)
		(layer "In3.Cu")
	)
	(gr_line
		(start 167.074596 -12.563348)
		(end 167.074596 -12.512548)
		(stroke
			(width 0.1016)
			(type default)
		)
		(layer "In3.Cu")
	)
	(gr_line
		(start 167.074596 -12.563348)
		(end 167.480996 -12.563348)
		(stroke
			(width 0.1016)
			(type default)
		)
		(layer "In3.Cu")
	)
	(gr_line
		(start 167.074596 -12.512548)
		(end 166.312596 -12.512548)
		(stroke
			(width 0.1016)
			(type default)
		)
		(layer "In3.Cu")
	)
	(gr_line
		(start 167.074596 -12.463272)
		(end 167.074596 -12.412472)
		(stroke
			(width 0.1016)
			(type default)
		)
		(layer "In3.Cu")
	)
	(gr_line
		(start 167.074596 -12.463272)
		(end 167.480996 -12.463272)
		(stroke
			(width 0.1016)
			(type default)
		)
		(layer "In3.Cu")
	)
	(gr_line
		(start 167.074596 -12.412472)
		(end 166.312596 -12.412472)
		(stroke
			(width 0.1016)
			(type default)
		)
		(layer "In3.Cu")
	)
	(gr_line
		(start 167.074596 -12.233148)
		(end 167.074596 -10.251948)
		(stroke
			(width 0.762)
			(type default)
		)
		(layer "In3.Cu")
	)
	(gr_line
		(start 167.074596 -12.133072)
		(end 167.074596 -10.151872)
		(stroke
			(width 0.762)
			(type default)
		)
		(layer "In3.Cu")
	)
	(gr_line
		(start 167.074596 -8.363204)
		(end 167.074596 -8.312404)
		(stroke
			(width 0.1016)
			(type default)
		)
		(layer "In3.Cu")
	)
	(gr_line
		(start 167.074596 -8.363204)
		(end 167.480996 -8.363204)
		(stroke
			(width 0.1016)
			(type default)
		)
		(layer "In3.Cu")
	)
	(gr_line
		(start 167.074596 -8.312404)
		(end 166.312596 -8.312404)
		(stroke
			(width 0.1016)
			(type default)
		)
		(layer "In3.Cu")
	)
	(gr_line
		(start 167.074596 -8.263128)
		(end 167.074596 -8.212328)
		(stroke
			(width 0.1016)
			(type default)
		)
		(layer "In3.Cu")
	)
	(gr_line
		(start 167.074596 -8.263128)
		(end 167.480996 -8.263128)
		(stroke
			(width 0.1016)
			(type default)
		)
		(layer "In3.Cu")
	)
	(gr_line
		(start 167.074596 -8.212328)
		(end 166.312596 -8.212328)
		(stroke
			(width 0.1016)
			(type default)
		)
		(layer "In3.Cu")
	)
	(gr_line
		(start 167.074596 -8.033004)
		(end 167.074596 -6.051804)
		(stroke
			(width 0.762)
			(type default)
		)
		(layer "In3.Cu")
	)
	(gr_line
		(start 167.074596 -7.932928)
		(end 167.074596 -5.951728)
		(stroke
			(width 0.762)
			(type default)
		)
		(layer "In3.Cu")
	)
	(gr_line
		(start 167.074596 -4.16306)
		(end 167.074596 -4.11226)
		(stroke
			(width 0.1016)
			(type default)
		)
		(layer "In3.Cu")
	)
	(gr_line
		(start 167.074596 -4.16306)
		(end 167.480996 -4.16306)
		(stroke
			(width 0.1016)
			(type default)
		)
		(layer "In3.Cu")
	)
	(gr_line
		(start 167.074596 -4.11226)
		(end 166.312596 -4.11226)
		(stroke
			(width 0.1016)
			(type default)
		)
		(layer "In3.Cu")
	)
	(gr_line
		(start 167.074596 -4.062984)
		(end 167.074596 -4.012184)
		(stroke
			(width 0.1016)
			(type default)
		)
		(layer "In3.Cu")
	)
	(gr_line
		(start 167.074596 -4.062984)
		(end 167.480996 -4.062984)
		(stroke
			(width 0.1016)
			(type default)
		)
		(layer "In3.Cu")
	)
	(gr_line
		(start 167.074596 -4.012184)
		(end 166.312596 -4.012184)
		(stroke
			(width 0.1016)
			(type default)
		)
		(layer "In3.Cu")
	)
	(gr_line
		(start 167.074596 -3.83286)
		(end 167.074596 -1.85166)
		(stroke
			(width 0.762)
			(type default)
		)
		(layer "In3.Cu")
	)
	(gr_line
		(start 167.074596 -3.732784)
		(end 167.074596 -1.751584)
		(stroke
			(width 0.762)
			(type default)
		)
		(layer "In3.Cu")
	)
	(gr_line
		(start 167.099996 -12.283948)
		(end 166.693596 -12.283948)
		(stroke
			(width 0.254)
			(type default)
		)
		(layer "In3.Cu")
	)
	(gr_line
		(start 167.099996 -12.183872)
		(end 166.693596 -12.183872)
		(stroke
			(width 0.254)
			(type default)
		)
		(layer "In3.Cu")
	)
	(gr_line
		(start 167.099996 -10.175748)
		(end 167.099996 -12.283948)
		(stroke
			(width 0.254)
			(type default)
		)
		(layer "In3.Cu")
	)
	(gr_line
		(start 167.099996 -10.075672)
		(end 167.099996 -12.183872)
		(stroke
			(width 0.254)
			(type default)
		)
		(layer "In3.Cu")
	)
	(gr_line
		(start 167.099996 -8.083804)
		(end 166.693596 -8.083804)
		(stroke
			(width 0.254)
			(type default)
		)
		(layer "In3.Cu")
	)
	(gr_line
		(start 167.099996 -7.983728)
		(end 166.693596 -7.983728)
		(stroke
			(width 0.254)
			(type default)
		)
		(layer "In3.Cu")
	)
	(gr_line
		(start 167.099996 -5.975604)
		(end 167.099996 -8.083804)
		(stroke
			(width 0.254)
			(type default)
		)
		(layer "In3.Cu")
	)
	(gr_line
		(start 167.099996 -5.875528)
		(end 167.099996 -7.983728)
		(stroke
			(width 0.254)
			(type default)
		)
		(layer "In3.Cu")
	)
	(gr_line
		(start 167.099996 -3.88366)
		(end 166.693596 -3.88366)
		(stroke
			(width 0.254)
			(type default)
		)
		(layer "In3.Cu")
	)
	(gr_line
		(start 167.099996 -3.783584)
		(end 166.693596 -3.783584)
		(stroke
			(width 0.254)
			(type default)
		)
		(layer "In3.Cu")
	)
	(gr_line
		(start 167.099996 -1.77546)
		(end 167.099996 -3.88366)
		(stroke
			(width 0.254)
			(type default)
		)
		(layer "In3.Cu")
	)
	(gr_line
		(start 167.099996 -1.675384)
		(end 167.099996 -3.783584)
		(stroke
			(width 0.254)
			(type default)
		)
		(layer "In3.Cu")
	)
	(gr_line
		(start 167.150796 -12.233148)
		(end 167.150796 -10.251948)
		(stroke
			(width 0.762)
			(type default)
		)
		(layer "In3.Cu")
	)
	(gr_line
		(start 167.150796 -12.133072)
		(end 167.150796 -10.151872)
		(stroke
			(width 0.762)
			(type default)
		)
		(layer "In3.Cu")
	)
	(gr_line
		(start 167.150796 -8.033004)
		(end 167.150796 -6.051804)
		(stroke
			(width 0.762)
			(type default)
		)
		(layer "In3.Cu")
	)
	(gr_line
		(start 167.150796 -7.932928)
		(end 167.150796 -5.951728)
		(stroke
			(width 0.762)
			(type default)
		)
		(layer "In3.Cu")
	)
	(gr_line
		(start 167.150796 -3.83286)
		(end 167.150796 -1.85166)
		(stroke
			(width 0.762)
			(type default)
		)
		(layer "In3.Cu")
	)
	(gr_line
		(start 167.150796 -3.732784)
		(end 167.150796 -1.751584)
		(stroke
			(width 0.762)
			(type default)
		)
		(layer "In3.Cu")
	)
	(gr_line
		(start 167.176196 -12.360148)
		(end 166.617396 -12.360148)
		(stroke
			(width 0.254)
			(type default)
		)
		(layer "In3.Cu")
	)
	(gr_line
		(start 167.176196 -12.260072)
		(end 166.617396 -12.260072)
		(stroke
			(width 0.254)
			(type default)
		)
		(layer "In3.Cu")
	)
	(gr_line
		(start 167.176196 -10.124948)
		(end 167.176196 -12.360148)
		(stroke
			(width 0.254)
			(type default)
		)
		(layer "In3.Cu")
	)
	(gr_line
		(start 167.176196 -10.024872)
		(end 167.176196 -12.260072)
		(stroke
			(width 0.254)
			(type default)
		)
		(layer "In3.Cu")
	)
	(gr_line
		(start 167.176196 -8.160004)
		(end 166.617396 -8.160004)
		(stroke
			(width 0.254)
			(type default)
		)
		(layer "In3.Cu")
	)
	(gr_line
		(start 167.176196 -8.059928)
		(end 166.617396 -8.059928)
		(stroke
			(width 0.254)
			(type default)
		)
		(layer "In3.Cu")
	)
	(gr_line
		(start 167.176196 -5.924804)
		(end 167.176196 -8.160004)
		(stroke
			(width 0.254)
			(type default)
		)
		(layer "In3.Cu")
	)
	(gr_line
		(start 167.176196 -5.824728)
		(end 167.176196 -8.059928)
		(stroke
			(width 0.254)
			(type default)
		)
		(layer "In3.Cu")
	)
	(gr_line
		(start 167.176196 -3.95986)
		(end 166.617396 -3.95986)
		(stroke
			(width 0.254)
			(type default)
		)
		(layer "In3.Cu")
	)
	(gr_line
		(start 167.176196 -3.859784)
		(end 166.617396 -3.859784)
		(stroke
			(width 0.254)
			(type default)
		)
		(layer "In3.Cu")
	)
	(gr_line
		(start 167.176196 -1.72466)
		(end 167.176196 -3.95986)
		(stroke
			(width 0.254)
			(type default)
		)
		(layer "In3.Cu")
	)
	(gr_line
		(start 167.176196 -1.624584)
		(end 167.176196 -3.859784)
		(stroke
			(width 0.254)
			(type default)
		)
		(layer "In3.Cu")
	)
	(gr_line
		(start 167.252396 -12.385548)
		(end 166.541196 -12.385548)
		(stroke
			(width 0.254)
			(type default)
		)
		(layer "In3.Cu")
	)
	(gr_line
		(start 167.252396 -12.285472)
		(end 166.541196 -12.285472)
		(stroke
			(width 0.254)
			(type default)
		)
		(layer "In3.Cu")
	)
	(gr_line
		(start 167.252396 -10.048748)
		(end 167.252396 -12.385548)
		(stroke
			(width 0.254)
			(type default)
		)
		(layer "In3.Cu")
	)
	(gr_line
		(start 167.252396 -9.948672)
		(end 167.252396 -12.285472)
		(stroke
			(width 0.254)
			(type default)
		)
		(layer "In3.Cu")
	)
	(gr_line
		(start 167.252396 -8.185404)
		(end 166.541196 -8.185404)
		(stroke
			(width 0.254)
			(type default)
		)
		(layer "In3.Cu")
	)
	(gr_line
		(start 167.252396 -8.085328)
		(end 166.541196 -8.085328)
		(stroke
			(width 0.254)
			(type default)
		)
		(layer "In3.Cu")
	)
	(gr_line
		(start 167.252396 -5.848604)
		(end 167.252396 -8.185404)
		(stroke
			(width 0.254)
			(type default)
		)
		(layer "In3.Cu")
	)
	(gr_line
		(start 167.252396 -5.748528)
		(end 167.252396 -8.085328)
		(stroke
			(width 0.254)
			(type default)
		)
		(layer "In3.Cu")
	)
	(gr_line
		(start 167.252396 -3.98526)
		(end 166.541196 -3.98526)
		(stroke
			(width 0.254)
			(type default)
		)
		(layer "In3.Cu")
	)
	(gr_line
		(start 167.252396 -3.885184)
		(end 166.541196 -3.885184)
		(stroke
			(width 0.254)
			(type default)
		)
		(layer "In3.Cu")
	)
	(gr_line
		(start 167.252396 -1.64846)
		(end 167.252396 -3.98526)
		(stroke
			(width 0.254)
			(type default)
		)
		(layer "In3.Cu")
	)
	(gr_line
		(start 167.252396 -1.548384)
		(end 167.252396 -3.885184)
		(stroke
			(width 0.254)
			(type default)
		)
		(layer "In3.Cu")
	)
	(gr_line
		(start 167.277796 -12.512548)
		(end 166.287196 -12.512548)
		(stroke
			(width 0.1016)
			(type default)
		)
		(layer "In3.Cu")
	)
	(gr_line
		(start 167.277796 -12.436348)
		(end 166.464996 -12.436348)
		(stroke
			(width 0.254)
			(type default)
		)
		(layer "In3.Cu")
	)
	(gr_line
		(start 167.277796 -12.412472)
		(end 166.287196 -12.412472)
		(stroke
			(width 0.1016)
			(type default)
		)
		(layer "In3.Cu")
	)
	(gr_line
		(start 167.277796 -12.336272)
		(end 166.464996 -12.336272)
		(stroke
			(width 0.254)
			(type default)
		)
		(layer "In3.Cu")
	)
	(gr_line
		(start 167.277796 -10.023348)
		(end 167.277796 -12.436348)
		(stroke
			(width 0.254)
			(type default)
		)
		(layer "In3.Cu")
	)
	(gr_line
		(start 167.277796 -9.923272)
		(end 167.277796 -12.336272)
		(stroke
			(width 0.254)
			(type default)
		)
		(layer "In3.Cu")
	)
	(gr_line
		(start 167.277796 -8.312404)
		(end 166.287196 -8.312404)
		(stroke
			(width 0.1016)
			(type default)
		)
		(layer "In3.Cu")
	)
	(gr_line
		(start 167.277796 -8.236204)
		(end 166.464996 -8.236204)
		(stroke
			(width 0.254)
			(type default)
		)
		(layer "In3.Cu")
	)
	(gr_line
		(start 167.277796 -8.212328)
		(end 166.287196 -8.212328)
		(stroke
			(width 0.1016)
			(type default)
		)
		(layer "In3.Cu")
	)
	(gr_line
		(start 167.277796 -8.136128)
		(end 166.464996 -8.136128)
		(stroke
			(width 0.254)
			(type default)
		)
		(layer "In3.Cu")
	)
	(gr_line
		(start 167.277796 -5.823204)
		(end 167.277796 -8.236204)
		(stroke
			(width 0.254)
			(type default)
		)
		(layer "In3.Cu")
	)
	(gr_line
		(start 167.277796 -5.723128)
		(end 167.277796 -8.136128)
		(stroke
			(width 0.254)
			(type default)
		)
		(layer "In3.Cu")
	)
	(gr_line
		(start 167.277796 -4.11226)
		(end 166.287196 -4.11226)
		(stroke
			(width 0.1016)
			(type default)
		)
		(layer "In3.Cu")
	)
	(gr_line
		(start 167.277796 -4.03606)
		(end 166.464996 -4.03606)
		(stroke
			(width 0.254)
			(type default)
		)
		(layer "In3.Cu")
	)
	(gr_line
		(start 167.277796 -4.012184)
		(end 166.287196 -4.012184)
		(stroke
			(width 0.1016)
			(type default)
		)
		(layer "In3.Cu")
	)
	(gr_line
		(start 167.277796 -3.935984)
		(end 166.464996 -3.935984)
		(stroke
			(width 0.254)
			(type default)
		)
		(layer "In3.Cu")
	)
	(gr_line
		(start 167.277796 -1.62306)
		(end 167.277796 -4.03606)
		(stroke
			(width 0.254)
			(type default)
		)
		(layer "In3.Cu")
	)
	(gr_line
		(start 167.277796 -1.522984)
		(end 167.277796 -3.935984)
		(stroke
			(width 0.254)
			(type default)
		)
		(layer "In3.Cu")
	)
	(gr_line
		(start 167.303196 -12.461748)
		(end 166.439596 -12.461748)
		(stroke
			(width 0.254)
			(type default)
		)
		(layer "In3.Cu")
	)
	(gr_line
		(start 167.303196 -12.361672)
		(end 166.439596 -12.361672)
		(stroke
			(width 0.254)
			(type default)
		)
		(layer "In3.Cu")
	)
	(gr_line
		(start 167.303196 -9.997948)
		(end 167.303196 -12.461748)
		(stroke
			(width 0.254)
			(type default)
		)
		(layer "In3.Cu")
	)
	(gr_line
		(start 167.303196 -9.897872)
		(end 167.303196 -12.361672)
		(stroke
			(width 0.254)
			(type default)
		)
		(layer "In3.Cu")
	)
	(gr_line
		(start 167.303196 -8.261604)
		(end 166.439596 -8.261604)
		(stroke
			(width 0.254)
			(type default)
		)
		(layer "In3.Cu")
	)
	(gr_line
		(start 167.303196 -8.161528)
		(end 166.439596 -8.161528)
		(stroke
			(width 0.254)
			(type default)
		)
		(layer "In3.Cu")
	)
	(gr_line
		(start 167.303196 -5.797804)
		(end 167.303196 -8.261604)
		(stroke
			(width 0.254)
			(type default)
		)
		(layer "In3.Cu")
	)
	(gr_line
		(start 167.303196 -5.697728)
		(end 167.303196 -8.161528)
		(stroke
			(width 0.254)
			(type default)
		)
		(layer "In3.Cu")
	)
	(gr_line
		(start 167.303196 -4.06146)
		(end 166.439596 -4.06146)
		(stroke
			(width 0.254)
			(type default)
		)
		(layer "In3.Cu")
	)
	(gr_line
		(start 167.303196 -3.961384)
		(end 166.439596 -3.961384)
		(stroke
			(width 0.254)
			(type default)
		)
		(layer "In3.Cu")
	)
	(gr_line
		(start 167.303196 -1.59766)
		(end 167.303196 -4.06146)
		(stroke
			(width 0.254)
			(type default)
		)
		(layer "In3.Cu")
	)
	(gr_line
		(start 167.303196 -1.497584)
		(end 167.303196 -3.961384)
		(stroke
			(width 0.254)
			(type default)
		)
		(layer "In3.Cu")
	)
	(gr_line
		(start 167.353996 -12.487148)
		(end 166.414196 -12.487148)
		(stroke
			(width 0.254)
			(type default)
		)
		(layer "In3.Cu")
	)
	(gr_line
		(start 167.353996 -12.387072)
		(end 166.414196 -12.387072)
		(stroke
			(width 0.254)
			(type default)
		)
		(layer "In3.Cu")
	)
	(gr_line
		(start 167.353996 -9.997948)
		(end 167.353996 -12.487148)
		(stroke
			(width 0.254)
			(type default)
		)
		(layer "In3.Cu")
	)
	(gr_line
		(start 167.353996 -9.897872)
		(end 167.353996 -12.387072)
		(stroke
			(width 0.254)
			(type default)
		)
		(layer "In3.Cu")
	)
	(gr_line
		(start 167.353996 -8.287004)
		(end 166.414196 -8.287004)
		(stroke
			(width 0.254)
			(type default)
		)
		(layer "In3.Cu")
	)
	(gr_line
		(start 167.353996 -8.186928)
		(end 166.414196 -8.186928)
		(stroke
			(width 0.254)
			(type default)
		)
		(layer "In3.Cu")
	)
	(gr_line
		(start 167.353996 -5.797804)
		(end 167.353996 -8.287004)
		(stroke
			(width 0.254)
			(type default)
		)
		(layer "In3.Cu")
	)
	(gr_line
		(start 167.353996 -5.697728)
		(end 167.353996 -8.186928)
		(stroke
			(width 0.254)
			(type default)
		)
		(layer "In3.Cu")
	)
	(gr_line
		(start 167.353996 -4.08686)
		(end 166.414196 -4.08686)
		(stroke
			(width 0.254)
			(type default)
		)
		(layer "In3.Cu")
	)
	(gr_line
		(start 167.353996 -3.986784)
		(end 166.414196 -3.986784)
		(stroke
			(width 0.254)
			(type default)
		)
		(layer "In3.Cu")
	)
	(gr_line
		(start 167.353996 -1.59766)
		(end 167.353996 -4.08686)
		(stroke
			(width 0.254)
			(type default)
		)
		(layer "In3.Cu")
	)
	(gr_line
		(start 167.353996 -1.497584)
		(end 167.353996 -3.986784)
		(stroke
			(width 0.254)
			(type default)
		)
		(layer "In3.Cu")
	)
	(gr_line
		(start 167.379396 -12.487148)
		(end 166.414196 -12.487148)
		(stroke
			(width 0.2032)
			(type default)
		)
		(layer "In3.Cu")
	)
	(gr_line
		(start 167.379396 -12.387072)
		(end 166.414196 -12.387072)
		(stroke
			(width 0.2032)
			(type default)
		)
		(layer "In3.Cu")
	)
	(gr_line
		(start 167.379396 -9.947148)
		(end 167.379396 -12.487148)
		(stroke
			(width 0.2032)
			(type default)
		)
		(layer "In3.Cu")
	)
	(gr_line
		(start 167.379396 -9.847072)
		(end 167.379396 -12.387072)
		(stroke
			(width 0.2032)
			(type default)
		)
		(layer "In3.Cu")
	)
	(gr_line
		(start 167.379396 -8.287004)
		(end 166.414196 -8.287004)
		(stroke
			(width 0.2032)
			(type default)
		)
		(layer "In3.Cu")
	)
	(gr_line
		(start 167.379396 -8.186928)
		(end 166.414196 -8.186928)
		(stroke
			(width 0.2032)
			(type default)
		)
		(layer "In3.Cu")
	)
	(gr_line
		(start 167.379396 -5.747004)
		(end 167.379396 -8.287004)
		(stroke
			(width 0.2032)
			(type default)
		)
		(layer "In3.Cu")
	)
	(gr_line
		(start 167.379396 -5.646928)
		(end 167.379396 -8.186928)
		(stroke
			(width 0.2032)
			(type default)
		)
		(layer "In3.Cu")
	)
	(gr_line
		(start 167.379396 -4.08686)
		(end 166.414196 -4.08686)
		(stroke
			(width 0.2032)
			(type default)
		)
		(layer "In3.Cu")
	)
	(gr_line
		(start 167.379396 -3.986784)
		(end 166.414196 -3.986784)
		(stroke
			(width 0.2032)
			(type default)
		)
		(layer "In3.Cu")
	)
	(gr_line
		(start 167.379396 -1.54686)
		(end 167.379396 -4.08686)
		(stroke
			(width 0.2032)
			(type default)
		)
		(layer "In3.Cu")
	)
	(gr_line
		(start 167.379396 -1.446784)
		(end 167.379396 -3.986784)
		(stroke
			(width 0.2032)
			(type default)
		)
		(layer "In3.Cu")
	)
	(gr_line
		(start 167.430196 -12.512548)
		(end 166.363396 -12.512548)
		(stroke
			(width 0.2032)
			(type default)
		)
		(layer "In3.Cu")
	)
	(gr_line
		(start 167.430196 -12.412472)
		(end 166.363396 -12.412472)
		(stroke
			(width 0.2032)
			(type default)
		)
		(layer "In3.Cu")
	)
	(gr_line
		(start 167.430196 -9.947148)
		(end 167.430196 -12.512548)
		(stroke
			(width 0.2032)
			(type default)
		)
		(layer "In3.Cu")
	)
	(gr_line
		(start 167.430196 -9.847072)
		(end 167.430196 -12.412472)
		(stroke
			(width 0.2032)
			(type default)
		)
		(layer "In3.Cu")
	)
	(gr_line
		(start 167.430196 -8.312404)
		(end 166.363396 -8.312404)
		(stroke
			(width 0.2032)
			(type default)
		)
		(layer "In3.Cu")
	)
	(gr_line
		(start 167.430196 -8.212328)
		(end 166.363396 -8.212328)
		(stroke
			(width 0.2032)
			(type default)
		)
		(layer "In3.Cu")
	)
	(gr_line
		(start 167.430196 -5.747004)
		(end 167.430196 -8.312404)
		(stroke
			(width 0.2032)
			(type default)
		)
		(layer "In3.Cu")
	)
	(gr_line
		(start 167.430196 -5.646928)
		(end 167.430196 -8.212328)
		(stroke
			(width 0.2032)
			(type default)
		)
		(layer "In3.Cu")
	)
	(gr_line
		(start 167.430196 -4.11226)
		(end 166.363396 -4.11226)
		(stroke
			(width 0.2032)
			(type default)
		)
		(layer "In3.Cu")
	)
	(gr_line
		(start 167.430196 -4.012184)
		(end 166.363396 -4.012184)
		(stroke
			(width 0.2032)
			(type default)
		)
		(layer "In3.Cu")
	)
	(gr_line
		(start 167.430196 -1.54686)
		(end 167.430196 -4.11226)
		(stroke
			(width 0.2032)
			(type default)
		)
		(layer "In3.Cu")
	)
	(gr_line
		(start 167.430196 -1.446784)
		(end 167.430196 -4.012184)
		(stroke
			(width 0.2032)
			(type default)
		)
		(layer "In3.Cu")
	)
	(gr_line
		(start 167.455596 -12.512548)
		(end 166.337996 -12.512548)
		(stroke
			(width 0.1016)
			(type default)
		)
		(layer "In3.Cu")
	)
	(gr_line
		(start 167.455596 -12.412472)
		(end 166.337996 -12.412472)
		(stroke
			(width 0.1016)
			(type default)
		)
		(layer "In3.Cu")
	)
	(gr_line
		(start 167.455596 -9.921748)
		(end 167.455596 -12.512548)
		(stroke
			(width 0.1016)
			(type default)
		)
		(layer "In3.Cu")
	)
	(gr_line
		(start 167.455596 -9.821672)
		(end 167.455596 -12.412472)
		(stroke
			(width 0.1016)
			(type default)
		)
		(layer "In3.Cu")
	)
	(gr_line
		(start 167.455596 -8.312404)
		(end 166.337996 -8.312404)
		(stroke
			(width 0.1016)
			(type default)
		)
		(layer "In3.Cu")
	)
	(gr_line
		(start 167.455596 -8.212328)
		(end 166.337996 -8.212328)
		(stroke
			(width 0.1016)
			(type default)
		)
		(layer "In3.Cu")
	)
	(gr_line
		(start 167.455596 -5.721604)
		(end 167.455596 -8.312404)
		(stroke
			(width 0.1016)
			(type default)
		)
		(layer "In3.Cu")
	)
	(gr_line
		(start 167.455596 -5.621528)
		(end 167.455596 -8.212328)
		(stroke
			(width 0.1016)
			(type default)
		)
		(layer "In3.Cu")
	)
	(gr_line
		(start 167.455596 -4.11226)
		(end 166.337996 -4.11226)
		(stroke
			(width 0.1016)
			(type default)
		)
		(layer "In3.Cu")
	)
	(gr_line
		(start 167.455596 -4.012184)
		(end 166.337996 -4.012184)
		(stroke
			(width 0.1016)
			(type default)
		)
		(layer "In3.Cu")
	)
	(gr_line
		(start 167.455596 -1.52146)
		(end 167.455596 -4.11226)
		(stroke
			(width 0.1016)
			(type default)
		)
		(layer "In3.Cu")
	)
	(gr_line
		(start 167.455596 -1.421384)
		(end 167.455596 -4.012184)
		(stroke
			(width 0.1016)
			(type default)
		)
		(layer "In3.Cu")
	)
	(gr_line
		(start 167.480996 -12.563348)
		(end 167.074596 -12.563348)
		(stroke
			(width 0.1016)
			(type default)
		)
		(layer "In3.Cu")
	)
	(gr_line
		(start 167.480996 -12.563348)
		(end 167.480996 -9.896348)
		(stroke
			(width 0.1016)
			(type default)
		)
		(layer "In3.Cu")
	)
	(gr_line
		(start 167.480996 -12.463272)
		(end 167.074596 -12.463272)
		(stroke
			(width 0.1016)
			(type default)
		)
		(layer "In3.Cu")
	)
	(gr_line
		(start 167.480996 -12.463272)
		(end 167.480996 -9.796272)
		(stroke
			(width 0.1016)
			(type default)
		)
		(layer "In3.Cu")
	)
	(gr_line
		(start 167.480996 -9.896348)
		(end 166.287196 -9.896348)
		(stroke
			(width 0.1016)
			(type default)
		)
		(layer "In3.Cu")
	)
	(gr_line
		(start 167.480996 -9.896348)
		(end 167.480996 -12.563348)
		(stroke
			(width 0.1016)
			(type default)
		)
		(layer "In3.Cu")
	)
	(gr_line
		(start 167.480996 -9.796272)
		(end 166.287196 -9.796272)
		(stroke
			(width 0.1016)
			(type default)
		)
		(layer "In3.Cu")
	)
	(gr_line
		(start 167.480996 -9.796272)
		(end 167.480996 -12.463272)
		(stroke
			(width 0.1016)
			(type default)
		)
		(layer "In3.Cu")
	)
	(gr_line
		(start 167.480996 -8.363204)
		(end 167.074596 -8.363204)
		(stroke
			(width 0.1016)
			(type default)
		)
		(layer "In3.Cu")
	)
	(gr_line
		(start 167.480996 -8.363204)
		(end 167.480996 -5.696204)
		(stroke
			(width 0.1016)
			(type default)
		)
		(layer "In3.Cu")
	)
	(gr_line
		(start 167.480996 -8.263128)
		(end 167.074596 -8.263128)
		(stroke
			(width 0.1016)
			(type default)
		)
		(layer "In3.Cu")
	)
	(gr_line
		(start 167.480996 -8.263128)
		(end 167.480996 -5.596128)
		(stroke
			(width 0.1016)
			(type default)
		)
		(layer "In3.Cu")
	)
	(gr_line
		(start 167.480996 -5.696204)
		(end 166.287196 -5.696204)
		(stroke
			(width 0.1016)
			(type default)
		)
		(layer "In3.Cu")
	)
	(gr_line
		(start 167.480996 -5.696204)
		(end 167.480996 -8.363204)
		(stroke
			(width 0.1016)
			(type default)
		)
		(layer "In3.Cu")
	)
	(gr_line
		(start 167.480996 -5.596128)
		(end 166.287196 -5.596128)
		(stroke
			(width 0.1016)
			(type default)
		)
		(layer "In3.Cu")
	)
	(gr_line
		(start 167.480996 -5.596128)
		(end 167.480996 -8.263128)
		(stroke
			(width 0.1016)
			(type default)
		)
		(layer "In3.Cu")
	)
	(gr_line
		(start 167.480996 -4.16306)
		(end 167.074596 -4.16306)
		(stroke
			(width 0.1016)
			(type default)
		)
		(layer "In3.Cu")
	)
	(gr_line
		(start 167.480996 -4.16306)
		(end 167.480996 -1.49606)
		(stroke
			(width 0.1016)
			(type default)
		)
		(layer "In3.Cu")
	)
	(gr_line
		(start 167.480996 -4.062984)
		(end 167.074596 -4.062984)
		(stroke
			(width 0.1016)
			(type default)
		)
		(layer "In3.Cu")
	)
	(gr_line
		(start 167.480996 -4.062984)
		(end 167.480996 -1.395984)
		(stroke
			(width 0.1016)
			(type default)
		)
		(layer "In3.Cu")
	)
	(gr_line
		(start 167.480996 -1.49606)
		(end 166.287196 -1.49606)
		(stroke
			(width 0.1016)
			(type default)
		)
		(layer "In3.Cu")
	)
	(gr_line
		(start 167.480996 -1.49606)
		(end 167.480996 -4.16306)
		(stroke
			(width 0.1016)
			(type default)
		)
		(layer "In3.Cu")
	)
	(gr_line
		(start 167.480996 -1.494028)
		(end 166.261796 -1.494028)
		(stroke
			(width 0.1016)
			(type default)
		)
		(layer "In3.Cu")
	)
	(gr_line
		(start 167.480996 -1.494028)
		(end 166.287196 -1.494028)
		(stroke
			(width 0.1016)
			(type default)
		)
		(layer "In3.Cu")
	)
	(gr_line
		(start 167.480996 -1.395984)
		(end 166.287196 -1.395984)
		(stroke
			(width 0.1016)
			(type default)
		)
		(layer "In3.Cu")
	)
	(gr_line
		(start 167.480996 -1.395984)
		(end 167.480996 -4.062984)
		(stroke
			(width 0.1016)
			(type default)
		)
		(layer "In3.Cu")
	)
	(gr_line
		(start 167.506396 -1.468628)
		(end 166.261796 -1.468628)
		(stroke
			(width 0.1016)
			(type default)
		)
		(layer "In3.Cu")
	)
	(gr_line
		(start 168.287192 -13.8176)
		(end 169.074592 -13.8176)
		(stroke
			(width 0.1016)
			(type default)
		)
		(layer "In3.Cu")
	)
	(gr_line
		(start 168.287192 -13.7668)
		(end 168.287192 -11.1506)
		(stroke
			(width 0.1016)
			(type default)
		)
		(layer "In3.Cu")
	)
	(gr_line
		(start 168.287192 -11.1506)
		(end 168.287192 -13.8176)
		(stroke
			(width 0.1016)
			(type default)
		)
		(layer "In3.Cu")
	)
	(gr_line
		(start 168.287192 -11.1506)
		(end 169.480992 -11.1506)
		(stroke
			(width 0.1016)
			(type default)
		)
		(layer "In3.Cu")
	)
	(gr_line
		(start 168.287192 -9.617456)
		(end 169.074592 -9.617456)
		(stroke
			(width 0.1016)
			(type default)
		)
		(layer "In3.Cu")
	)
	(gr_line
		(start 168.287192 -9.566656)
		(end 168.287192 -6.950456)
		(stroke
			(width 0.1016)
			(type default)
		)
		(layer "In3.Cu")
	)
	(gr_line
		(start 168.287192 -6.950456)
		(end 168.287192 -9.617456)
		(stroke
			(width 0.1016)
			(type default)
		)
		(layer "In3.Cu")
	)
	(gr_line
		(start 168.287192 -6.950456)
		(end 169.480992 -6.950456)
		(stroke
			(width 0.1016)
			(type default)
		)
		(layer "In3.Cu")
	)
	(gr_line
		(start 168.312592 -13.7668)
		(end 168.312592 -11.176)
		(stroke
			(width 0.1016)
			(type default)
		)
		(layer "In3.Cu")
	)
	(gr_line
		(start 168.312592 -11.176)
		(end 169.455592 -11.176)
		(stroke
			(width 0.1016)
			(type default)
		)
		(layer "In3.Cu")
	)
	(gr_line
		(start 168.312592 -9.566656)
		(end 168.312592 -6.975856)
		(stroke
			(width 0.1016)
			(type default)
		)
		(layer "In3.Cu")
	)
	(gr_line
		(start 168.312592 -6.975856)
		(end 169.455592 -6.975856)
		(stroke
			(width 0.1016)
			(type default)
		)
		(layer "In3.Cu")
	)
	(gr_line
		(start 168.337992 -13.7668)
		(end 168.337992 -11.2014)
		(stroke
			(width 0.1016)
			(type default)
		)
		(layer "In3.Cu")
	)
	(gr_line
		(start 168.337992 -11.2014)
		(end 168.591992 -11.2014)
		(stroke
			(width 0.1016)
			(type default)
		)
		(layer "In3.Cu")
	)
	(gr_line
		(start 168.337992 -9.566656)
		(end 168.337992 -7.001256)
		(stroke
			(width 0.1016)
			(type default)
		)
		(layer "In3.Cu")
	)
	(gr_line
		(start 168.337992 -7.001256)
		(end 168.591992 -7.001256)
		(stroke
			(width 0.1016)
			(type default)
		)
		(layer "In3.Cu")
	)
	(gr_line
		(start 168.363392 -13.7668)
		(end 168.363392 -11.2014)
		(stroke
			(width 0.2032)
			(type default)
		)
		(layer "In3.Cu")
	)
	(gr_line
		(start 168.363392 -11.2014)
		(end 169.379392 -11.2014)
		(stroke
			(width 0.2032)
			(type default)
		)
		(layer "In3.Cu")
	)
	(gr_line
		(start 168.363392 -9.566656)
		(end 168.363392 -7.001256)
		(stroke
			(width 0.2032)
			(type default)
		)
		(layer "In3.Cu")
	)
	(gr_line
		(start 168.363392 -7.001256)
		(end 169.379392 -7.001256)
		(stroke
			(width 0.2032)
			(type default)
		)
		(layer "In3.Cu")
	)
	(gr_line
		(start 168.414192 -13.7414)
		(end 168.414192 -11.2522)
		(stroke
			(width 0.2032)
			(type default)
		)
		(layer "In3.Cu")
	)
	(gr_line
		(start 168.414192 -13.7414)
		(end 168.414192 -11.2522)
		(stroke
			(width 0.254)
			(type default)
		)
		(layer "In3.Cu")
	)
	(gr_line
		(start 168.414192 -11.2522)
		(end 168.617392 -11.2522)
		(stroke
			(width 0.2032)
			(type default)
		)
		(layer "In3.Cu")
	)
	(gr_line
		(start 168.414192 -11.2522)
		(end 169.303192 -11.2522)
		(stroke
			(width 0.254)
			(type default)
		)
		(layer "In3.Cu")
	)
	(gr_line
		(start 168.414192 -9.541256)
		(end 168.414192 -7.052056)
		(stroke
			(width 0.2032)
			(type default)
		)
		(layer "In3.Cu")
	)
	(gr_line
		(start 168.414192 -9.541256)
		(end 168.414192 -7.052056)
		(stroke
			(width 0.254)
			(type default)
		)
		(layer "In3.Cu")
	)
	(gr_line
		(start 168.414192 -7.052056)
		(end 168.617392 -7.052056)
		(stroke
			(width 0.2032)
			(type default)
		)
		(layer "In3.Cu")
	)
	(gr_line
		(start 168.414192 -7.052056)
		(end 169.303192 -7.052056)
		(stroke
			(width 0.254)
			(type default)
		)
		(layer "In3.Cu")
	)
	(gr_line
		(start 168.439592 -13.716)
		(end 168.439592 -11.2776)
		(stroke
			(width 0.254)
			(type default)
		)
		(layer "In3.Cu")
	)
	(gr_line
		(start 168.439592 -11.2776)
		(end 169.277792 -11.2776)
		(stroke
			(width 0.254)
			(type default)
		)
		(layer "In3.Cu")
	)
	(gr_line
		(start 168.439592 -9.515856)
		(end 168.439592 -7.077456)
		(stroke
			(width 0.254)
			(type default)
		)
		(layer "In3.Cu")
	)
	(gr_line
		(start 168.439592 -7.077456)
		(end 169.277792 -7.077456)
		(stroke
			(width 0.254)
			(type default)
		)
		(layer "In3.Cu")
	)
	(gr_line
		(start 168.464992 -13.6906)
		(end 168.464992 -11.303)
		(stroke
			(width 0.254)
			(type default)
		)
		(layer "In3.Cu")
	)
	(gr_line
		(start 168.464992 -11.303)
		(end 169.252392 -11.303)
		(stroke
			(width 0.254)
			(type default)
		)
		(layer "In3.Cu")
	)
	(gr_line
		(start 168.464992 -9.490456)
		(end 168.464992 -7.102856)
		(stroke
			(width 0.254)
			(type default)
		)
		(layer "In3.Cu")
	)
	(gr_line
		(start 168.464992 -7.102856)
		(end 169.252392 -7.102856)
		(stroke
			(width 0.254)
			(type default)
		)
		(layer "In3.Cu")
	)
	(gr_line
		(start 168.490392 -13.6144)
		(end 169.125392 -13.6144)
		(stroke
			(width 0.508)
			(type default)
		)
		(layer "In3.Cu")
	)
	(gr_line
		(start 168.490392 -11.43)
		(end 169.125392 -11.43)
		(stroke
			(width 0.508)
			(type default)
		)
		(layer "In3.Cu")
	)
	(gr_line
		(start 168.490392 -11.3792)
		(end 169.125392 -11.3792)
		(stroke
			(width 0.508)
			(type default)
		)
		(layer "In3.Cu")
	)
	(gr_line
		(start 168.490392 -9.414256)
		(end 169.125392 -9.414256)
		(stroke
			(width 0.508)
			(type default)
		)
		(layer "In3.Cu")
	)
	(gr_line
		(start 168.490392 -7.229856)
		(end 169.125392 -7.229856)
		(stroke
			(width 0.508)
			(type default)
		)
		(layer "In3.Cu")
	)
	(gr_line
		(start 168.490392 -7.179056)
		(end 169.125392 -7.179056)
		(stroke
			(width 0.508)
			(type default)
		)
		(layer "In3.Cu")
	)
	(gr_line
		(start 168.515792 -11.684)
		(end 169.150792 -11.684)
		(stroke
			(width 0.508)
			(type default)
		)
		(layer "In3.Cu")
	)
	(gr_line
		(start 168.515792 -7.483856)
		(end 169.150792 -7.483856)
		(stroke
			(width 0.508)
			(type default)
		)
		(layer "In3.Cu")
	)
	(gr_line
		(start 168.541192 -13.6398)
		(end 168.541192 -11.3792)
		(stroke
			(width 0.254)
			(type default)
		)
		(layer "In3.Cu")
	)
	(gr_line
		(start 168.541192 -13.4874)
		(end 169.176192 -13.4874)
		(stroke
			(width 0.508)
			(type default)
		)
		(layer "In3.Cu")
	)
	(gr_line
		(start 168.541192 -11.3792)
		(end 169.176192 -11.3792)
		(stroke
			(width 0.254)
			(type default)
		)
		(layer "In3.Cu")
	)
	(gr_line
		(start 168.541192 -9.439656)
		(end 168.541192 -7.179056)
		(stroke
			(width 0.254)
			(type default)
		)
		(layer "In3.Cu")
	)
	(gr_line
		(start 168.541192 -9.287256)
		(end 169.176192 -9.287256)
		(stroke
			(width 0.508)
			(type default)
		)
		(layer "In3.Cu")
	)
	(gr_line
		(start 168.541192 -7.179056)
		(end 169.176192 -7.179056)
		(stroke
			(width 0.254)
			(type default)
		)
		(layer "In3.Cu")
	)
	(gr_line
		(start 168.566592 -13.335)
		(end 169.201592 -13.335)
		(stroke
			(width 0.508)
			(type default)
		)
		(layer "In3.Cu")
	)
	(gr_line
		(start 168.566592 -9.134856)
		(end 169.201592 -9.134856)
		(stroke
			(width 0.508)
			(type default)
		)
		(layer "In3.Cu")
	)
	(gr_line
		(start 168.591992 -13.6144)
		(end 169.226992 -13.6144)
		(stroke
			(width 0.508)
			(type default)
		)
		(layer "In3.Cu")
	)
	(gr_line
		(start 168.591992 -11.2014)
		(end 169.430192 -11.2014)
		(stroke
			(width 0.2032)
			(type default)
		)
		(layer "In3.Cu")
	)
	(gr_line
		(start 168.591992 -9.414256)
		(end 169.226992 -9.414256)
		(stroke
			(width 0.508)
			(type default)
		)
		(layer "In3.Cu")
	)
	(gr_line
		(start 168.591992 -7.001256)
		(end 169.430192 -7.001256)
		(stroke
			(width 0.2032)
			(type default)
		)
		(layer "In3.Cu")
	)
	(gr_line
		(start 168.617392 -13.6144)
		(end 168.617392 -11.43)
		(stroke
			(width 0.254)
			(type default)
		)
		(layer "In3.Cu")
	)
	(gr_line
		(start 168.617392 -11.43)
		(end 169.099992 -11.43)
		(stroke
			(width 0.254)
			(type default)
		)
		(layer "In3.Cu")
	)
	(gr_line
		(start 168.617392 -11.2522)
		(end 169.353992 -11.2522)
		(stroke
			(width 0.254)
			(type default)
		)
		(layer "In3.Cu")
	)
	(gr_line
		(start 168.617392 -9.414256)
		(end 168.617392 -7.229856)
		(stroke
			(width 0.254)
			(type default)
		)
		(layer "In3.Cu")
	)
	(gr_line
		(start 168.617392 -7.229856)
		(end 169.099992 -7.229856)
		(stroke
			(width 0.254)
			(type default)
		)
		(layer "In3.Cu")
	)
	(gr_line
		(start 168.617392 -7.052056)
		(end 169.353992 -7.052056)
		(stroke
			(width 0.254)
			(type default)
		)
		(layer "In3.Cu")
	)
	(gr_line
		(start 168.635934 -11.36523)
		(end 169.270934 -11.36523)
		(stroke
			(width 0.508)
			(type default)
		)
		(layer "In3.Cu")
	)
	(gr_line
		(start 168.635934 -7.165086)
		(end 169.270934 -7.165086)
		(stroke
			(width 0.508)
			(type default)
		)
		(layer "In3.Cu")
	)
	(gr_line
		(start 168.642792 -13.6144)
		(end 169.277792 -13.6144)
		(stroke
			(width 0.508)
			(type default)
		)
		(layer "In3.Cu")
	)
	(gr_line
		(start 168.642792 -13.4874)
		(end 168.642792 -11.5062)
		(stroke
			(width 0.762)
			(type default)
		)
		(layer "In3.Cu")
	)
	(gr_line
		(start 168.642792 -11.5062)
		(end 169.277792 -11.5062)
		(stroke
			(width 0.508)
			(type default)
		)
		(layer "In3.Cu")
	)
	(gr_line
		(start 168.642792 -9.414256)
		(end 169.277792 -9.414256)
		(stroke
			(width 0.508)
			(type default)
		)
		(layer "In3.Cu")
	)
	(gr_line
		(start 168.642792 -9.287256)
		(end 168.642792 -7.306056)
		(stroke
			(width 0.762)
			(type default)
		)
		(layer "In3.Cu")
	)
	(gr_line
		(start 168.642792 -7.306056)
		(end 169.277792 -7.306056)
		(stroke
			(width 0.508)
			(type default)
		)
		(layer "In3.Cu")
	)
	(gr_line
		(start 168.693592 -13.5382)
		(end 168.693592 -11.5062)
		(stroke
			(width 0.254)
			(type default)
		)
		(layer "In3.Cu")
	)
	(gr_line
		(start 168.693592 -11.5062)
		(end 169.023792 -11.5062)
		(stroke
			(width 0.254)
			(type default)
		)
		(layer "In3.Cu")
	)
	(gr_line
		(start 168.693592 -9.338056)
		(end 168.693592 -7.306056)
		(stroke
			(width 0.254)
			(type default)
		)
		(layer "In3.Cu")
	)
	(gr_line
		(start 168.693592 -7.306056)
		(end 169.023792 -7.306056)
		(stroke
			(width 0.254)
			(type default)
		)
		(layer "In3.Cu")
	)
	(gr_line
		(start 168.73474 -18.5166)
		(end 167.46474 -18.5166)
		(stroke
			(width 0.7874)
			(type default)
		)
		(layer "In3.Cu")
	)
	(gr_line
		(start 168.795192 -13.462)
		(end 168.795192 -11.6586)
		(stroke
			(width 0.254)
			(type default)
		)
		(layer "In3.Cu")
	)
	(gr_line
		(start 168.795192 -13.462)
		(end 168.795192 -11.4808)
		(stroke
			(width 0.762)
			(type default)
		)
		(layer "In3.Cu")
	)
	(gr_line
		(start 168.795192 -11.6586)
		(end 168.896792 -11.6586)
		(stroke
			(width 0.254)
			(type default)
		)
		(layer "In3.Cu")
	)
	(gr_line
		(start 168.795192 -9.261856)
		(end 168.795192 -7.458456)
		(stroke
			(width 0.254)
			(type default)
		)
		(layer "In3.Cu")
	)
	(gr_line
		(start 168.795192 -9.261856)
		(end 168.795192 -7.280656)
		(stroke
			(width 0.762)
			(type default)
		)
		(layer "In3.Cu")
	)
	(gr_line
		(start 168.795192 -7.458456)
		(end 168.896792 -7.458456)
		(stroke
			(width 0.254)
			(type default)
		)
		(layer "In3.Cu")
	)
	(gr_line
		(start 168.896792 -13.5636)
		(end 168.845992 -13.5636)
		(stroke
			(width 0.254)
			(type default)
		)
		(layer "In3.Cu")
	)
	(gr_line
		(start 168.896792 -11.6586)
		(end 168.896792 -13.5636)
		(stroke
			(width 0.254)
			(type default)
		)
		(layer "In3.Cu")
	)
	(gr_line
		(start 168.896792 -9.363456)
		(end 168.845992 -9.363456)
		(stroke
			(width 0.254)
			(type default)
		)
		(layer "In3.Cu")
	)
	(gr_line
		(start 168.896792 -7.458456)
		(end 168.896792 -9.363456)
		(stroke
			(width 0.254)
			(type default)
		)
		(layer "In3.Cu")
	)
	(gr_line
		(start 168.947592 -13.4874)
		(end 168.947592 -11.5062)
		(stroke
			(width 0.762)
			(type default)
		)
		(layer "In3.Cu")
	)
	(gr_line
		(start 168.947592 -9.287256)
		(end 168.947592 -7.306056)
		(stroke
			(width 0.762)
			(type default)
		)
		(layer "In3.Cu")
	)
	(gr_line
		(start 169.023792 -13.462)
		(end 168.795192 -13.462)
		(stroke
			(width 0.254)
			(type default)
		)
		(layer "In3.Cu")
	)
	(gr_line
		(start 169.023792 -11.5062)
		(end 169.023792 -13.462)
		(stroke
			(width 0.254)
			(type default)
		)
		(layer "In3.Cu")
	)
	(gr_line
		(start 169.023792 -9.261856)
		(end 168.795192 -9.261856)
		(stroke
			(width 0.254)
			(type default)
		)
		(layer "In3.Cu")
	)
	(gr_line
		(start 169.023792 -7.306056)
		(end 169.023792 -9.261856)
		(stroke
			(width 0.254)
			(type default)
		)
		(layer "In3.Cu")
	)
	(gr_line
		(start 169.074592 -13.8176)
		(end 169.074592 -13.7668)
		(stroke
			(width 0.1016)
			(type default)
		)
		(layer "In3.Cu")
	)
	(gr_line
		(start 169.074592 -13.8176)
		(end 169.480992 -13.8176)
		(stroke
			(width 0.1016)
			(type default)
		)
		(layer "In3.Cu")
	)
	(gr_line
		(start 169.074592 -13.7668)
		(end 168.312592 -13.7668)
		(stroke
			(width 0.1016)
			(type default)
		)
		(layer "In3.Cu")
	)
	(gr_line
		(start 169.074592 -13.4874)
		(end 169.074592 -11.5062)
		(stroke
			(width 0.762)
			(type default)
		)
		(layer "In3.Cu")
	)
	(gr_line
		(start 169.074592 -9.617456)
		(end 169.074592 -9.566656)
		(stroke
			(width 0.1016)
			(type default)
		)
		(layer "In3.Cu")
	)
	(gr_line
		(start 169.074592 -9.617456)
		(end 169.480992 -9.617456)
		(stroke
			(width 0.1016)
			(type default)
		)
		(layer "In3.Cu")
	)
	(gr_line
		(start 169.074592 -9.566656)
		(end 168.312592 -9.566656)
		(stroke
			(width 0.1016)
			(type default)
		)
		(layer "In3.Cu")
	)
	(gr_line
		(start 169.074592 -9.287256)
		(end 169.074592 -7.306056)
		(stroke
			(width 0.762)
			(type default)
		)
		(layer "In3.Cu")
	)
	(gr_line
		(start 169.099992 -13.5382)
		(end 168.693592 -13.5382)
		(stroke
			(width 0.254)
			(type default)
		)
		(layer "In3.Cu")
	)
	(gr_line
		(start 169.099992 -11.43)
		(end 169.099992 -13.5382)
		(stroke
			(width 0.254)
			(type default)
		)
		(layer "In3.Cu")
	)
	(gr_line
		(start 169.099992 -9.338056)
		(end 168.693592 -9.338056)
		(stroke
			(width 0.254)
			(type default)
		)
		(layer "In3.Cu")
	)
	(gr_line
		(start 169.099992 -7.229856)
		(end 169.099992 -9.338056)
		(stroke
			(width 0.254)
			(type default)
		)
		(layer "In3.Cu")
	)
	(gr_line
		(start 169.150792 -13.4874)
		(end 169.150792 -11.5062)
		(stroke
			(width 0.762)
			(type default)
		)
		(layer "In3.Cu")
	)
	(gr_line
		(start 169.150792 -9.287256)
		(end 169.150792 -7.306056)
		(stroke
			(width 0.762)
			(type default)
		)
		(layer "In3.Cu")
	)
	(gr_line
		(start 169.176192 -13.6144)
		(end 168.617392 -13.6144)
		(stroke
			(width 0.254)
			(type default)
		)
		(layer "In3.Cu")
	)
	(gr_line
		(start 169.176192 -11.3792)
		(end 169.176192 -13.6144)
		(stroke
			(width 0.254)
			(type default)
		)
		(layer "In3.Cu")
	)
	(gr_line
		(start 169.176192 -9.414256)
		(end 168.617392 -9.414256)
		(stroke
			(width 0.254)
			(type default)
		)
		(layer "In3.Cu")
	)
	(gr_line
		(start 169.176192 -7.179056)
		(end 169.176192 -9.414256)
		(stroke
			(width 0.254)
			(type default)
		)
		(layer "In3.Cu")
	)
	(gr_line
		(start 169.252392 -13.6398)
		(end 168.541192 -13.6398)
		(stroke
			(width 0.254)
			(type default)
		)
		(layer "In3.Cu")
	)
	(gr_line
		(start 169.252392 -11.303)
		(end 169.252392 -13.6398)
		(stroke
			(width 0.254)
			(type default)
		)
		(layer "In3.Cu")
	)
	(gr_line
		(start 169.252392 -9.439656)
		(end 168.541192 -9.439656)
		(stroke
			(width 0.254)
			(type default)
		)
		(layer "In3.Cu")
	)
	(gr_line
		(start 169.252392 -7.102856)
		(end 169.252392 -9.439656)
		(stroke
			(width 0.254)
			(type default)
		)
		(layer "In3.Cu")
	)
	(gr_line
		(start 169.277792 -13.7668)
		(end 168.287192 -13.7668)
		(stroke
			(width 0.1016)
			(type default)
		)
		(layer "In3.Cu")
	)
	(gr_line
		(start 169.277792 -13.6906)
		(end 168.464992 -13.6906)
		(stroke
			(width 0.254)
			(type default)
		)
		(layer "In3.Cu")
	)
	(gr_line
		(start 169.277792 -11.2776)
		(end 169.277792 -13.6906)
		(stroke
			(width 0.254)
			(type default)
		)
		(layer "In3.Cu")
	)
	(gr_line
		(start 169.277792 -9.566656)
		(end 168.287192 -9.566656)
		(stroke
			(width 0.1016)
			(type default)
		)
		(layer "In3.Cu")
	)
	(gr_line
		(start 169.277792 -9.490456)
		(end 168.464992 -9.490456)
		(stroke
			(width 0.254)
			(type default)
		)
		(layer "In3.Cu")
	)
	(gr_line
		(start 169.277792 -7.077456)
		(end 169.277792 -9.490456)
		(stroke
			(width 0.254)
			(type default)
		)
		(layer "In3.Cu")
	)
	(gr_line
		(start 169.303192 -13.716)
		(end 168.439592 -13.716)
		(stroke
			(width 0.254)
			(type default)
		)
		(layer "In3.Cu")
	)
	(gr_line
		(start 169.303192 -11.2522)
		(end 169.303192 -13.716)
		(stroke
			(width 0.254)
			(type default)
		)
		(layer "In3.Cu")
	)
	(gr_line
		(start 169.303192 -9.515856)
		(end 168.439592 -9.515856)
		(stroke
			(width 0.254)
			(type default)
		)
		(layer "In3.Cu")
	)
	(gr_line
		(start 169.303192 -7.052056)
		(end 169.303192 -9.515856)
		(stroke
			(width 0.254)
			(type default)
		)
		(layer "In3.Cu")
	)
	(gr_line
		(start 169.319956 -30.734)
		(end 168.049956 -30.734)
		(stroke
			(width 0.7874)
			(type default)
		)
		(layer "In3.Cu")
	)
	(gr_line
		(start 169.353992 -13.7414)
		(end 168.414192 -13.7414)
		(stroke
			(width 0.254)
			(type default)
		)
		(layer "In3.Cu")
	)
	(gr_line
		(start 169.353992 -11.2522)
		(end 169.353992 -13.7414)
		(stroke
			(width 0.254)
			(type default)
		)
		(layer "In3.Cu")
	)
	(gr_line
		(start 169.353992 -9.541256)
		(end 168.414192 -9.541256)
		(stroke
			(width 0.254)
			(type default)
		)
		(layer "In3.Cu")
	)
	(gr_line
		(start 169.353992 -7.052056)
		(end 169.353992 -9.541256)
		(stroke
			(width 0.254)
			(type default)
		)
		(layer "In3.Cu")
	)
	(gr_line
		(start 169.379392 -13.7414)
		(end 168.414192 -13.7414)
		(stroke
			(width 0.2032)
			(type default)
		)
		(layer "In3.Cu")
	)
	(gr_line
		(start 169.379392 -11.2014)
		(end 169.379392 -13.7414)
		(stroke
			(width 0.2032)
			(type default)
		)
		(layer "In3.Cu")
	)
	(gr_line
		(start 169.379392 -9.541256)
		(end 168.414192 -9.541256)
		(stroke
			(width 0.2032)
			(type default)
		)
		(layer "In3.Cu")
	)
	(gr_line
		(start 169.379392 -7.001256)
		(end 169.379392 -9.541256)
		(stroke
			(width 0.2032)
			(type default)
		)
		(layer "In3.Cu")
	)
	(gr_line
		(start 169.430192 -13.7668)
		(end 168.363392 -13.7668)
		(stroke
			(width 0.2032)
			(type default)
		)
		(layer "In3.Cu")
	)
	(gr_line
		(start 169.430192 -11.2014)
		(end 169.430192 -13.7668)
		(stroke
			(width 0.2032)
			(type default)
		)
		(layer "In3.Cu")
	)
	(gr_line
		(start 169.430192 -9.566656)
		(end 168.363392 -9.566656)
		(stroke
			(width 0.2032)
			(type default)
		)
		(layer "In3.Cu")
	)
	(gr_line
		(start 169.430192 -7.001256)
		(end 169.430192 -9.566656)
		(stroke
			(width 0.2032)
			(type default)
		)
		(layer "In3.Cu")
	)
	(gr_line
		(start 169.455592 -13.7668)
		(end 168.337992 -13.7668)
		(stroke
			(width 0.1016)
			(type default)
		)
		(layer "In3.Cu")
	)
	(gr_line
		(start 169.455592 -11.176)
		(end 169.455592 -13.7668)
		(stroke
			(width 0.1016)
			(type default)
		)
		(layer "In3.Cu")
	)
	(gr_line
		(start 169.455592 -9.566656)
		(end 168.337992 -9.566656)
		(stroke
			(width 0.1016)
			(type default)
		)
		(layer "In3.Cu")
	)
	(gr_line
		(start 169.455592 -6.975856)
		(end 169.455592 -9.566656)
		(stroke
			(width 0.1016)
			(type default)
		)
		(layer "In3.Cu")
	)
	(gr_line
		(start 169.480992 -13.8176)
		(end 169.074592 -13.8176)
		(stroke
			(width 0.1016)
			(type default)
		)
		(layer "In3.Cu")
	)
	(gr_line
		(start 169.480992 -13.8176)
		(end 169.480992 -11.1506)
		(stroke
			(width 0.1016)
			(type default)
		)
		(layer "In3.Cu")
	)
	(gr_line
		(start 169.480992 -11.1506)
		(end 168.287192 -11.1506)
		(stroke
			(width 0.1016)
			(type default)
		)
		(layer "In3.Cu")
	)
	(gr_line
		(start 169.480992 -11.1506)
		(end 169.480992 -13.8176)
		(stroke
			(width 0.1016)
			(type default)
		)
		(layer "In3.Cu")
	)
	(gr_line
		(start 169.480992 -9.617456)
		(end 169.074592 -9.617456)
		(stroke
			(width 0.1016)
			(type default)
		)
		(layer "In3.Cu")
	)
	(gr_line
		(start 169.480992 -9.617456)
		(end 169.480992 -6.950456)
		(stroke
			(width 0.1016)
			(type default)
		)
		(layer "In3.Cu")
	)
	(gr_line
		(start 169.480992 -6.950456)
		(end 168.287192 -6.950456)
		(stroke
			(width 0.1016)
			(type default)
		)
		(layer "In3.Cu")
	)
	(gr_line
		(start 169.480992 -6.950456)
		(end 169.480992 -9.617456)
		(stroke
			(width 0.1016)
			(type default)
		)
		(layer "In3.Cu")
	)
	(gr_line
		(start 170.287188 -12.563348)
		(end 171.074588 -12.563348)
		(stroke
			(width 0.1016)
			(type default)
		)
		(layer "In3.Cu")
	)
	(gr_line
		(start 170.287188 -12.512548)
		(end 170.287188 -9.896348)
		(stroke
			(width 0.1016)
			(type default)
		)
		(layer "In3.Cu")
	)
	(gr_line
		(start 170.287188 -12.463272)
		(end 171.074588 -12.463272)
		(stroke
			(width 0.1016)
			(type default)
		)
		(layer "In3.Cu")
	)
	(gr_line
		(start 170.287188 -12.412472)
		(end 170.287188 -9.796272)
		(stroke
			(width 0.1016)
			(type default)
		)
		(layer "In3.Cu")
	)
	(gr_line
		(start 170.287188 -9.896348)
		(end 170.287188 -12.563348)
		(stroke
			(width 0.1016)
			(type default)
		)
		(layer "In3.Cu")
	)
	(gr_line
		(start 170.287188 -9.896348)
		(end 171.480988 -9.896348)
		(stroke
			(width 0.1016)
			(type default)
		)
		(layer "In3.Cu")
	)
	(gr_line
		(start 170.287188 -9.796272)
		(end 170.287188 -12.463272)
		(stroke
			(width 0.1016)
			(type default)
		)
		(layer "In3.Cu")
	)
	(gr_line
		(start 170.287188 -9.796272)
		(end 171.480988 -9.796272)
		(stroke
			(width 0.1016)
			(type default)
		)
		(layer "In3.Cu")
	)
	(gr_line
		(start 170.287188 -8.363204)
		(end 171.074588 -8.363204)
		(stroke
			(width 0.1016)
			(type default)
		)
		(layer "In3.Cu")
	)
	(gr_line
		(start 170.287188 -8.312404)
		(end 170.287188 -5.696204)
		(stroke
			(width 0.1016)
			(type default)
		)
		(layer "In3.Cu")
	)
	(gr_line
		(start 170.287188 -8.263128)
		(end 171.074588 -8.263128)
		(stroke
			(width 0.1016)
			(type default)
		)
		(layer "In3.Cu")
	)
	(gr_line
		(start 170.287188 -8.212328)
		(end 170.287188 -5.596128)
		(stroke
			(width 0.1016)
			(type default)
		)
		(layer "In3.Cu")
	)
	(gr_line
		(start 170.287188 -5.696204)
		(end 170.287188 -8.363204)
		(stroke
			(width 0.1016)
			(type default)
		)
		(layer "In3.Cu")
	)
	(gr_line
		(start 170.287188 -5.696204)
		(end 171.480988 -5.696204)
		(stroke
			(width 0.1016)
			(type default)
		)
		(layer "In3.Cu")
	)
	(gr_line
		(start 170.287188 -5.596128)
		(end 170.287188 -8.263128)
		(stroke
			(width 0.1016)
			(type default)
		)
		(layer "In3.Cu")
	)
	(gr_line
		(start 170.287188 -5.596128)
		(end 171.480988 -5.596128)
		(stroke
			(width 0.1016)
			(type default)
		)
		(layer "In3.Cu")
	)
	(gr_line
		(start 170.312588 -12.512548)
		(end 170.312588 -9.921748)
		(stroke
			(width 0.1016)
			(type default)
		)
		(layer "In3.Cu")
	)
	(gr_line
		(start 170.312588 -12.412472)
		(end 170.312588 -9.821672)
		(stroke
			(width 0.1016)
			(type default)
		)
		(layer "In3.Cu")
	)
	(gr_line
		(start 170.312588 -9.921748)
		(end 171.455588 -9.921748)
		(stroke
			(width 0.1016)
			(type default)
		)
		(layer "In3.Cu")
	)
	(gr_line
		(start 170.312588 -9.821672)
		(end 171.455588 -9.821672)
		(stroke
			(width 0.1016)
			(type default)
		)
		(layer "In3.Cu")
	)
	(gr_line
		(start 170.312588 -8.312404)
		(end 170.312588 -5.721604)
		(stroke
			(width 0.1016)
			(type default)
		)
		(layer "In3.Cu")
	)
	(gr_line
		(start 170.312588 -8.212328)
		(end 170.312588 -5.621528)
		(stroke
			(width 0.1016)
			(type default)
		)
		(layer "In3.Cu")
	)
	(gr_line
		(start 170.312588 -5.721604)
		(end 171.455588 -5.721604)
		(stroke
			(width 0.1016)
			(type default)
		)
		(layer "In3.Cu")
	)
	(gr_line
		(start 170.312588 -5.621528)
		(end 171.455588 -5.621528)
		(stroke
			(width 0.1016)
			(type default)
		)
		(layer "In3.Cu")
	)
	(gr_line
		(start 170.337988 -12.512548)
		(end 170.337988 -9.947148)
		(stroke
			(width 0.1016)
			(type default)
		)
		(layer "In3.Cu")
	)
	(gr_line
		(start 170.337988 -12.412472)
		(end 170.337988 -9.847072)
		(stroke
			(width 0.1016)
			(type default)
		)
		(layer "In3.Cu")
	)
	(gr_line
		(start 170.337988 -9.947148)
		(end 170.591988 -9.947148)
		(stroke
			(width 0.1016)
			(type default)
		)
		(layer "In3.Cu")
	)
	(gr_line
		(start 170.337988 -9.847072)
		(end 170.591988 -9.847072)
		(stroke
			(width 0.1016)
			(type default)
		)
		(layer "In3.Cu")
	)
	(gr_line
		(start 170.337988 -8.312404)
		(end 170.337988 -5.747004)
		(stroke
			(width 0.1016)
			(type default)
		)
		(layer "In3.Cu")
	)
	(gr_line
		(start 170.337988 -8.212328)
		(end 170.337988 -5.646928)
		(stroke
			(width 0.1016)
			(type default)
		)
		(layer "In3.Cu")
	)
	(gr_line
		(start 170.337988 -5.747004)
		(end 170.591988 -5.747004)
		(stroke
			(width 0.1016)
			(type default)
		)
		(layer "In3.Cu")
	)
	(gr_line
		(start 170.337988 -5.646928)
		(end 170.591988 -5.646928)
		(stroke
			(width 0.1016)
			(type default)
		)
		(layer "In3.Cu")
	)
	(gr_line
		(start 170.363388 -12.512548)
		(end 170.363388 -9.947148)
		(stroke
			(width 0.2032)
			(type default)
		)
		(layer "In3.Cu")
	)
	(gr_line
		(start 170.363388 -12.412472)
		(end 170.363388 -9.847072)
		(stroke
			(width 0.2032)
			(type default)
		)
		(layer "In3.Cu")
	)
	(gr_line
		(start 170.363388 -9.947148)
		(end 171.379388 -9.947148)
		(stroke
			(width 0.2032)
			(type default)
		)
		(layer "In3.Cu")
	)
	(gr_line
		(start 170.363388 -9.847072)
		(end 171.379388 -9.847072)
		(stroke
			(width 0.2032)
			(type default)
		)
		(layer "In3.Cu")
	)
	(gr_line
		(start 170.363388 -8.312404)
		(end 170.363388 -5.747004)
		(stroke
			(width 0.2032)
			(type default)
		)
		(layer "In3.Cu")
	)
	(gr_line
		(start 170.363388 -8.212328)
		(end 170.363388 -5.646928)
		(stroke
			(width 0.2032)
			(type default)
		)
		(layer "In3.Cu")
	)
	(gr_line
		(start 170.363388 -5.747004)
		(end 171.379388 -5.747004)
		(stroke
			(width 0.2032)
			(type default)
		)
		(layer "In3.Cu")
	)
	(gr_line
		(start 170.363388 -5.646928)
		(end 171.379388 -5.646928)
		(stroke
			(width 0.2032)
			(type default)
		)
		(layer "In3.Cu")
	)
	(gr_line
		(start 170.414188 -12.487148)
		(end 170.414188 -9.997948)
		(stroke
			(width 0.2032)
			(type default)
		)
		(layer "In3.Cu")
	)
	(gr_line
		(start 170.414188 -12.487148)
		(end 170.414188 -9.997948)
		(stroke
			(width 0.254)
			(type default)
		)
		(layer "In3.Cu")
	)
	(gr_line
		(start 170.414188 -12.387072)
		(end 170.414188 -9.897872)
		(stroke
			(width 0.2032)
			(type default)
		)
		(layer "In3.Cu")
	)
	(gr_line
		(start 170.414188 -12.387072)
		(end 170.414188 -9.897872)
		(stroke
			(width 0.254)
			(type default)
		)
		(layer "In3.Cu")
	)
	(gr_line
		(start 170.414188 -9.997948)
		(end 170.617388 -9.997948)
		(stroke
			(width 0.2032)
			(type default)
		)
		(layer "In3.Cu")
	)
	(gr_line
		(start 170.414188 -9.997948)
		(end 171.303188 -9.997948)
		(stroke
			(width 0.254)
			(type default)
		)
		(layer "In3.Cu")
	)
	(gr_line
		(start 170.414188 -9.897872)
		(end 170.617388 -9.897872)
		(stroke
			(width 0.2032)
			(type default)
		)
		(layer "In3.Cu")
	)
	(gr_line
		(start 170.414188 -9.897872)
		(end 171.303188 -9.897872)
		(stroke
			(width 0.254)
			(type default)
		)
		(layer "In3.Cu")
	)
	(gr_line
		(start 170.414188 -8.287004)
		(end 170.414188 -5.797804)
		(stroke
			(width 0.2032)
			(type default)
		)
		(layer "In3.Cu")
	)
	(gr_line
		(start 170.414188 -8.287004)
		(end 170.414188 -5.797804)
		(stroke
			(width 0.254)
			(type default)
		)
		(layer "In3.Cu")
	)
	(gr_line
		(start 170.414188 -8.186928)
		(end 170.414188 -5.697728)
		(stroke
			(width 0.2032)
			(type default)
		)
		(layer "In3.Cu")
	)
	(gr_line
		(start 170.414188 -8.186928)
		(end 170.414188 -5.697728)
		(stroke
			(width 0.254)
			(type default)
		)
		(layer "In3.Cu")
	)
	(gr_line
		(start 170.414188 -5.797804)
		(end 170.617388 -5.797804)
		(stroke
			(width 0.2032)
			(type default)
		)
		(layer "In3.Cu")
	)
	(gr_line
		(start 170.414188 -5.797804)
		(end 171.303188 -5.797804)
		(stroke
			(width 0.254)
			(type default)
		)
		(layer "In3.Cu")
	)
	(gr_line
		(start 170.414188 -5.697728)
		(end 170.617388 -5.697728)
		(stroke
			(width 0.2032)
			(type default)
		)
		(layer "In3.Cu")
	)
	(gr_line
		(start 170.414188 -5.697728)
		(end 171.303188 -5.697728)
		(stroke
			(width 0.254)
			(type default)
		)
		(layer "In3.Cu")
	)
	(gr_line
		(start 170.439588 -12.461748)
		(end 170.439588 -10.023348)
		(stroke
			(width 0.254)
			(type default)
		)
		(layer "In3.Cu")
	)
	(gr_line
		(start 170.439588 -12.361672)
		(end 170.439588 -9.923272)
		(stroke
			(width 0.254)
			(type default)
		)
		(layer "In3.Cu")
	)
	(gr_line
		(start 170.439588 -10.023348)
		(end 171.277788 -10.023348)
		(stroke
			(width 0.254)
			(type default)
		)
		(layer "In3.Cu")
	)
	(gr_line
		(start 170.439588 -9.923272)
		(end 171.277788 -9.923272)
		(stroke
			(width 0.254)
			(type default)
		)
		(layer "In3.Cu")
	)
	(gr_line
		(start 170.439588 -8.261604)
		(end 170.439588 -5.823204)
		(stroke
			(width 0.254)
			(type default)
		)
		(layer "In3.Cu")
	)
	(gr_line
		(start 170.439588 -8.161528)
		(end 170.439588 -5.723128)
		(stroke
			(width 0.254)
			(type default)
		)
		(layer "In3.Cu")
	)
	(gr_line
		(start 170.439588 -5.823204)
		(end 171.277788 -5.823204)
		(stroke
			(width 0.254)
			(type default)
		)
		(layer "In3.Cu")
	)
	(gr_line
		(start 170.439588 -5.723128)
		(end 171.277788 -5.723128)
		(stroke
			(width 0.254)
			(type default)
		)
		(layer "In3.Cu")
	)
	(gr_line
		(start 170.464988 -12.436348)
		(end 170.464988 -10.048748)
		(stroke
			(width 0.254)
			(type default)
		)
		(layer "In3.Cu")
	)
	(gr_line
		(start 170.464988 -12.336272)
		(end 170.464988 -9.948672)
		(stroke
			(width 0.254)
			(type default)
		)
		(layer "In3.Cu")
	)
	(gr_line
		(start 170.464988 -10.048748)
		(end 171.252388 -10.048748)
		(stroke
			(width 0.254)
			(type default)
		)
		(layer "In3.Cu")
	)
	(gr_line
		(start 170.464988 -9.948672)
		(end 171.252388 -9.948672)
		(stroke
			(width 0.254)
			(type default)
		)
		(layer "In3.Cu")
	)
	(gr_line
		(start 170.464988 -8.236204)
		(end 170.464988 -5.848604)
		(stroke
			(width 0.254)
			(type default)
		)
		(layer "In3.Cu")
	)
	(gr_line
		(start 170.464988 -8.136128)
		(end 170.464988 -5.748528)
		(stroke
			(width 0.254)
			(type default)
		)
		(layer "In3.Cu")
	)
	(gr_line
		(start 170.464988 -5.848604)
		(end 171.252388 -5.848604)
		(stroke
			(width 0.254)
			(type default)
		)
		(layer "In3.Cu")
	)
	(gr_line
		(start 170.464988 -5.748528)
		(end 171.252388 -5.748528)
		(stroke
			(width 0.254)
			(type default)
		)
		(layer "In3.Cu")
	)
	(gr_line
		(start 170.490388 -12.360148)
		(end 171.125388 -12.360148)
		(stroke
			(width 0.508)
			(type default)
		)
		(layer "In3.Cu")
	)
	(gr_line
		(start 170.490388 -12.260072)
		(end 171.125388 -12.260072)
		(stroke
			(width 0.508)
			(type default)
		)
		(layer "In3.Cu")
	)
	(gr_line
		(start 170.490388 -10.175748)
		(end 171.125388 -10.175748)
		(stroke
			(width 0.508)
			(type default)
		)
		(layer "In3.Cu")
	)
	(gr_line
		(start 170.490388 -10.124948)
		(end 171.125388 -10.124948)
		(stroke
			(width 0.508)
			(type default)
		)
		(layer "In3.Cu")
	)
	(gr_line
		(start 170.490388 -10.075672)
		(end 171.125388 -10.075672)
		(stroke
			(width 0.508)
			(type default)
		)
		(layer "In3.Cu")
	)
	(gr_line
		(start 170.490388 -10.024872)
		(end 171.125388 -10.024872)
		(stroke
			(width 0.508)
			(type default)
		)
		(layer "In3.Cu")
	)
	(gr_line
		(start 170.490388 -8.160004)
		(end 171.125388 -8.160004)
		(stroke
			(width 0.508)
			(type default)
		)
		(layer "In3.Cu")
	)
	(gr_line
		(start 170.490388 -8.059928)
		(end 171.125388 -8.059928)
		(stroke
			(width 0.508)
			(type default)
		)
		(layer "In3.Cu")
	)
	(gr_line
		(start 170.490388 -5.975604)
		(end 171.125388 -5.975604)
		(stroke
			(width 0.508)
			(type default)
		)
		(layer "In3.Cu")
	)
	(gr_line
		(start 170.490388 -5.924804)
		(end 171.125388 -5.924804)
		(stroke
			(width 0.508)
			(type default)
		)
		(layer "In3.Cu")
	)
	(gr_line
		(start 170.490388 -5.875528)
		(end 171.125388 -5.875528)
		(stroke
			(width 0.508)
			(type default)
		)
		(layer "In3.Cu")
	)
	(gr_line
		(start 170.490388 -5.824728)
		(end 171.125388 -5.824728)
		(stroke
			(width 0.508)
			(type default)
		)
		(layer "In3.Cu")
	)
	(gr_line
		(start 170.515788 -10.429748)
		(end 171.150788 -10.429748)
		(stroke
			(width 0.508)
			(type default)
		)
		(layer "In3.Cu")
	)
	(gr_line
		(start 170.515788 -10.329672)
		(end 171.150788 -10.329672)
		(stroke
			(width 0.508)
			(type default)
		)
		(layer "In3.Cu")
	)
	(gr_line
		(start 170.515788 -6.229604)
		(end 171.150788 -6.229604)
		(stroke
			(width 0.508)
			(type default)
		)
		(layer "In3.Cu")
	)
	(gr_line
		(start 170.515788 -6.129528)
		(end 171.150788 -6.129528)
		(stroke
			(width 0.508)
			(type default)
		)
		(layer "In3.Cu")
	)
	(gr_line
		(start 170.541188 -12.385548)
		(end 170.541188 -10.124948)
		(stroke
			(width 0.254)
			(type default)
		)
		(layer "In3.Cu")
	)
	(gr_line
		(start 170.541188 -12.285472)
		(end 170.541188 -10.024872)
		(stroke
			(width 0.254)
			(type default)
		)
		(layer "In3.Cu")
	)
	(gr_line
		(start 170.541188 -12.233148)
		(end 171.176188 -12.233148)
		(stroke
			(width 0.508)
			(type default)
		)
		(layer "In3.Cu")
	)
	(gr_line
		(start 170.541188 -12.133072)
		(end 171.176188 -12.133072)
		(stroke
			(width 0.508)
			(type default)
		)
		(layer "In3.Cu")
	)
	(gr_line
		(start 170.541188 -10.124948)
		(end 171.176188 -10.124948)
		(stroke
			(width 0.254)
			(type default)
		)
		(layer "In3.Cu")
	)
	(gr_line
		(start 170.541188 -10.024872)
		(end 171.176188 -10.024872)
		(stroke
			(width 0.254)
			(type default)
		)
		(layer "In3.Cu")
	)
	(gr_line
		(start 170.541188 -8.185404)
		(end 170.541188 -5.924804)
		(stroke
			(width 0.254)
			(type default)
		)
		(layer "In3.Cu")
	)
	(gr_line
		(start 170.541188 -8.085328)
		(end 170.541188 -5.824728)
		(stroke
			(width 0.254)
			(type default)
		)
		(layer "In3.Cu")
	)
	(gr_line
		(start 170.541188 -8.033004)
		(end 171.176188 -8.033004)
		(stroke
			(width 0.508)
			(type default)
		)
		(layer "In3.Cu")
	)
	(gr_line
		(start 170.541188 -7.932928)
		(end 171.176188 -7.932928)
		(stroke
			(width 0.508)
			(type default)
		)
		(layer "In3.Cu")
	)
	(gr_line
		(start 170.541188 -5.924804)
		(end 171.176188 -5.924804)
		(stroke
			(width 0.254)
			(type default)
		)
		(layer "In3.Cu")
	)
	(gr_line
		(start 170.541188 -5.824728)
		(end 171.176188 -5.824728)
		(stroke
			(width 0.254)
			(type default)
		)
		(layer "In3.Cu")
	)
	(gr_line
		(start 170.566588 -12.080748)
		(end 171.201588 -12.080748)
		(stroke
			(width 0.508)
			(type default)
		)
		(layer "In3.Cu")
	)
	(gr_line
		(start 170.566588 -11.980672)
		(end 171.201588 -11.980672)
		(stroke
			(width 0.508)
			(type default)
		)
		(layer "In3.Cu")
	)
	(gr_line
		(start 170.566588 -7.880604)
		(end 171.201588 -7.880604)
		(stroke
			(width 0.508)
			(type default)
		)
		(layer "In3.Cu")
	)
	(gr_line
		(start 170.566588 -7.780528)
		(end 171.201588 -7.780528)
		(stroke
			(width 0.508)
			(type default)
		)
		(layer "In3.Cu")
	)
	(gr_line
		(start 170.591988 -12.360148)
		(end 171.226988 -12.360148)
		(stroke
			(width 0.508)
			(type default)
		)
		(layer "In3.Cu")
	)
	(gr_line
		(start 170.591988 -12.260072)
		(end 171.226988 -12.260072)
		(stroke
			(width 0.508)
			(type default)
		)
		(layer "In3.Cu")
	)
	(gr_line
		(start 170.591988 -9.947148)
		(end 171.430188 -9.947148)
		(stroke
			(width 0.2032)
			(type default)
		)
		(layer "In3.Cu")
	)
	(gr_line
		(start 170.591988 -9.847072)
		(end 171.430188 -9.847072)
		(stroke
			(width 0.2032)
			(type default)
		)
		(layer "In3.Cu")
	)
	(gr_line
		(start 170.591988 -8.160004)
		(end 171.226988 -8.160004)
		(stroke
			(width 0.508)
			(type default)
		)
		(layer "In3.Cu")
	)
	(gr_line
		(start 170.591988 -8.059928)
		(end 171.226988 -8.059928)
		(stroke
			(width 0.508)
			(type default)
		)
		(layer "In3.Cu")
	)
	(gr_line
		(start 170.591988 -5.747004)
		(end 171.430188 -5.747004)
		(stroke
			(width 0.2032)
			(type default)
		)
		(layer "In3.Cu")
	)
	(gr_line
		(start 170.591988 -5.646928)
		(end 171.430188 -5.646928)
		(stroke
			(width 0.2032)
			(type default)
		)
		(layer "In3.Cu")
	)
	(gr_line
		(start 170.617388 -12.360148)
		(end 170.617388 -10.175748)
		(stroke
			(width 0.254)
			(type default)
		)
		(layer "In3.Cu")
	)
	(gr_line
		(start 170.617388 -12.260072)
		(end 170.617388 -10.075672)
		(stroke
			(width 0.254)
			(type default)
		)
		(layer "In3.Cu")
	)
	(gr_line
		(start 170.617388 -10.175748)
		(end 171.099988 -10.175748)
		(stroke
			(width 0.254)
			(type default)
		)
		(layer "In3.Cu")
	)
	(gr_line
		(start 170.617388 -10.075672)
		(end 171.099988 -10.075672)
		(stroke
			(width 0.254)
			(type default)
		)
		(layer "In3.Cu")
	)
	(gr_line
		(start 170.617388 -9.997948)
		(end 171.353988 -9.997948)
		(stroke
			(width 0.254)
			(type default)
		)
		(layer "In3.Cu")
	)
	(gr_line
		(start 170.617388 -9.897872)
		(end 171.353988 -9.897872)
		(stroke
			(width 0.254)
			(type default)
		)
		(layer "In3.Cu")
	)
	(gr_line
		(start 170.617388 -8.160004)
		(end 170.617388 -5.975604)
		(stroke
			(width 0.254)
			(type default)
		)
		(layer "In3.Cu")
	)
	(gr_line
		(start 170.617388 -8.059928)
		(end 170.617388 -5.875528)
		(stroke
			(width 0.254)
			(type default)
		)
		(layer "In3.Cu")
	)
	(gr_line
		(start 170.617388 -5.975604)
		(end 171.099988 -5.975604)
		(stroke
			(width 0.254)
			(type default)
		)
		(layer "In3.Cu")
	)
	(gr_line
		(start 170.617388 -5.875528)
		(end 171.099988 -5.875528)
		(stroke
			(width 0.254)
			(type default)
		)
		(layer "In3.Cu")
	)
	(gr_line
		(start 170.617388 -5.797804)
		(end 171.353988 -5.797804)
		(stroke
			(width 0.254)
			(type default)
		)
		(layer "In3.Cu")
	)
	(gr_line
		(start 170.617388 -5.697728)
		(end 171.353988 -5.697728)
		(stroke
			(width 0.254)
			(type default)
		)
		(layer "In3.Cu")
	)
	(gr_line
		(start 170.63593 -10.110978)
		(end 171.27093 -10.110978)
		(stroke
			(width 0.508)
			(type default)
		)
		(layer "In3.Cu")
	)
	(gr_line
		(start 170.63593 -10.010902)
		(end 171.27093 -10.010902)
		(stroke
			(width 0.508)
			(type default)
		)
		(layer "In3.Cu")
	)
	(gr_line
		(start 170.63593 -5.910834)
		(end 171.27093 -5.910834)
		(stroke
			(width 0.508)
			(type default)
		)
		(layer "In3.Cu")
	)
	(gr_line
		(start 170.63593 -5.810758)
		(end 171.27093 -5.810758)
		(stroke
			(width 0.508)
			(type default)
		)
		(layer "In3.Cu")
	)
	(gr_line
		(start 170.642788 -12.360148)
		(end 171.277788 -12.360148)
		(stroke
			(width 0.508)
			(type default)
		)
		(layer "In3.Cu")
	)
	(gr_line
		(start 170.642788 -12.260072)
		(end 171.277788 -12.260072)
		(stroke
			(width 0.508)
			(type default)
		)
		(layer "In3.Cu")
	)
	(gr_line
		(start 170.642788 -12.233148)
		(end 170.642788 -10.251948)
		(stroke
			(width 0.762)
			(type default)
		)
		(layer "In3.Cu")
	)
	(gr_line
		(start 170.642788 -12.133072)
		(end 170.642788 -10.151872)
		(stroke
			(width 0.762)
			(type default)
		)
		(layer "In3.Cu")
	)
	(gr_line
		(start 170.642788 -10.251948)
		(end 171.277788 -10.251948)
		(stroke
			(width 0.508)
			(type default)
		)
		(layer "In3.Cu")
	)
	(gr_line
		(start 170.642788 -10.151872)
		(end 171.277788 -10.151872)
		(stroke
			(width 0.508)
			(type default)
		)
		(layer "In3.Cu")
	)
	(gr_line
		(start 170.642788 -8.160004)
		(end 171.277788 -8.160004)
		(stroke
			(width 0.508)
			(type default)
		)
		(layer "In3.Cu")
	)
	(gr_line
		(start 170.642788 -8.059928)
		(end 171.277788 -8.059928)
		(stroke
			(width 0.508)
			(type default)
		)
		(layer "In3.Cu")
	)
	(gr_line
		(start 170.642788 -8.033004)
		(end 170.642788 -6.051804)
		(stroke
			(width 0.762)
			(type default)
		)
		(layer "In3.Cu")
	)
	(gr_line
		(start 170.642788 -7.932928)
		(end 170.642788 -5.951728)
		(stroke
			(width 0.762)
			(type default)
		)
		(layer "In3.Cu")
	)
	(gr_line
		(start 170.642788 -6.051804)
		(end 171.277788 -6.051804)
		(stroke
			(width 0.508)
			(type default)
		)
		(layer "In3.Cu")
	)
	(gr_line
		(start 170.642788 -5.951728)
		(end 171.277788 -5.951728)
		(stroke
			(width 0.508)
			(type default)
		)
		(layer "In3.Cu")
	)
	(gr_line
		(start 170.693588 -12.283948)
		(end 170.693588 -10.251948)
		(stroke
			(width 0.254)
			(type default)
		)
		(layer "In3.Cu")
	)
	(gr_line
		(start 170.693588 -12.183872)
		(end 170.693588 -10.151872)
		(stroke
			(width 0.254)
			(type default)
		)
		(layer "In3.Cu")
	)
	(gr_line
		(start 170.693588 -10.251948)
		(end 171.023788 -10.251948)
		(stroke
			(width 0.254)
			(type default)
		)
		(layer "In3.Cu")
	)
	(gr_line
		(start 170.693588 -10.151872)
		(end 171.023788 -10.151872)
		(stroke
			(width 0.254)
			(type default)
		)
		(layer "In3.Cu")
	)
	(gr_line
		(start 170.693588 -8.083804)
		(end 170.693588 -6.051804)
		(stroke
			(width 0.254)
			(type default)
		)
		(layer "In3.Cu")
	)
	(gr_line
		(start 170.693588 -7.983728)
		(end 170.693588 -5.951728)
		(stroke
			(width 0.254)
			(type default)
		)
		(layer "In3.Cu")
	)
	(gr_line
		(start 170.693588 -6.051804)
		(end 171.023788 -6.051804)
		(stroke
			(width 0.254)
			(type default)
		)
		(layer "In3.Cu")
	)
	(gr_line
		(start 170.693588 -5.951728)
		(end 171.023788 -5.951728)
		(stroke
			(width 0.254)
			(type default)
		)
		(layer "In3.Cu")
	)
	(gr_line
		(start 170.795188 -12.207748)
		(end 170.795188 -10.404348)
		(stroke
			(width 0.254)
			(type default)
		)
		(layer "In3.Cu")
	)
	(gr_line
		(start 170.795188 -12.207748)
		(end 170.795188 -10.226548)
		(stroke
			(width 0.762)
			(type default)
		)
		(layer "In3.Cu")
	)
	(gr_line
		(start 170.795188 -12.107672)
		(end 170.795188 -10.304272)
		(stroke
			(width 0.254)
			(type default)
		)
		(layer "In3.Cu")
	)
	(gr_line
		(start 170.795188 -12.107672)
		(end 170.795188 -10.126472)
		(stroke
			(width 0.762)
			(type default)
		)
		(layer "In3.Cu")
	)
	(gr_line
		(start 170.795188 -10.404348)
		(end 170.896788 -10.404348)
		(stroke
			(width 0.254)
			(type default)
		)
		(layer "In3.Cu")
	)
	(gr_line
		(start 170.795188 -10.304272)
		(end 170.896788 -10.304272)
		(stroke
			(width 0.254)
			(type default)
		)
		(layer "In3.Cu")
	)
	(gr_line
		(start 170.795188 -8.007604)
		(end 170.795188 -6.204204)
		(stroke
			(width 0.254)
			(type default)
		)
		(layer "In3.Cu")
	)
	(gr_line
		(start 170.795188 -8.007604)
		(end 170.795188 -6.026404)
		(stroke
			(width 0.762)
			(type default)
		)
		(layer "In3.Cu")
	)
	(gr_line
		(start 170.795188 -7.907528)
		(end 170.795188 -6.104128)
		(stroke
			(width 0.254)
			(type default)
		)
		(layer "In3.Cu")
	)
	(gr_line
		(start 170.795188 -7.907528)
		(end 170.795188 -5.926328)
		(stroke
			(width 0.762)
			(type default)
		)
		(layer "In3.Cu")
	)
	(gr_line
		(start 170.795188 -6.204204)
		(end 170.896788 -6.204204)
		(stroke
			(width 0.254)
			(type default)
		)
		(layer "In3.Cu")
	)
	(gr_line
		(start 170.795188 -6.104128)
		(end 170.896788 -6.104128)
		(stroke
			(width 0.254)
			(type default)
		)
		(layer "In3.Cu")
	)
	(gr_line
		(start 170.896788 -12.309348)
		(end 170.845988 -12.309348)
		(stroke
			(width 0.254)
			(type default)
		)
		(layer "In3.Cu")
	)
	(gr_line
		(start 170.896788 -12.209272)
		(end 170.845988 -12.209272)
		(stroke
			(width 0.254)
			(type default)
		)
		(layer "In3.Cu")
	)
	(gr_line
		(start 170.896788 -10.404348)
		(end 170.896788 -12.309348)
		(stroke
			(width 0.254)
			(type default)
		)
		(layer "In3.Cu")
	)
	(gr_line
		(start 170.896788 -10.304272)
		(end 170.896788 -12.209272)
		(stroke
			(width 0.254)
			(type default)
		)
		(layer "In3.Cu")
	)
	(gr_line
		(start 170.896788 -8.109204)
		(end 170.845988 -8.109204)
		(stroke
			(width 0.254)
			(type default)
		)
		(layer "In3.Cu")
	)
	(gr_line
		(start 170.896788 -8.009128)
		(end 170.845988 -8.009128)
		(stroke
			(width 0.254)
			(type default)
		)
		(layer "In3.Cu")
	)
	(gr_line
		(start 170.896788 -6.204204)
		(end 170.896788 -8.109204)
		(stroke
			(width 0.254)
			(type default)
		)
		(layer "In3.Cu")
	)
	(gr_line
		(start 170.896788 -6.104128)
		(end 170.896788 -8.009128)
		(stroke
			(width 0.254)
			(type default)
		)
		(layer "In3.Cu")
	)
	(gr_line
		(start 170.947588 -12.233148)
		(end 170.947588 -10.251948)
		(stroke
			(width 0.762)
			(type default)
		)
		(layer "In3.Cu")
	)
	(gr_line
		(start 170.947588 -12.133072)
		(end 170.947588 -10.151872)
		(stroke
			(width 0.762)
			(type default)
		)
		(layer "In3.Cu")
	)
	(gr_line
		(start 170.947588 -8.033004)
		(end 170.947588 -6.051804)
		(stroke
			(width 0.762)
			(type default)
		)
		(layer "In3.Cu")
	)
	(gr_line
		(start 170.947588 -7.932928)
		(end 170.947588 -5.951728)
		(stroke
			(width 0.762)
			(type default)
		)
		(layer "In3.Cu")
	)
	(gr_line
		(start 171.023788 -12.207748)
		(end 170.795188 -12.207748)
		(stroke
			(width 0.254)
			(type default)
		)
		(layer "In3.Cu")
	)
	(gr_line
		(start 171.023788 -12.107672)
		(end 170.795188 -12.107672)
		(stroke
			(width 0.254)
			(type default)
		)
		(layer "In3.Cu")
	)
	(gr_line
		(start 171.023788 -10.251948)
		(end 171.023788 -12.207748)
		(stroke
			(width 0.254)
			(type default)
		)
		(layer "In3.Cu")
	)
	(gr_line
		(start 171.023788 -10.151872)
		(end 171.023788 -12.107672)
		(stroke
			(width 0.254)
			(type default)
		)
		(layer "In3.Cu")
	)
	(gr_line
		(start 171.023788 -8.007604)
		(end 170.795188 -8.007604)
		(stroke
			(width 0.254)
			(type default)
		)
		(layer "In3.Cu")
	)
	(gr_line
		(start 171.023788 -7.907528)
		(end 170.795188 -7.907528)
		(stroke
			(width 0.254)
			(type default)
		)
		(layer "In3.Cu")
	)
	(gr_line
		(start 171.023788 -6.051804)
		(end 171.023788 -8.007604)
		(stroke
			(width 0.254)
			(type default)
		)
		(layer "In3.Cu")
	)
	(gr_line
		(start 171.023788 -5.951728)
		(end 171.023788 -7.907528)
		(stroke
			(width 0.254)
			(type default)
		)
		(layer "In3.Cu")
	)
	(gr_line
		(start 171.074588 -12.563348)
		(end 171.074588 -12.512548)
		(stroke
			(width 0.1016)
			(type default)
		)
		(layer "In3.Cu")
	)
	(gr_line
		(start 171.074588 -12.563348)
		(end 171.480988 -12.563348)
		(stroke
			(width 0.1016)
			(type default)
		)
		(layer "In3.Cu")
	)
	(gr_line
		(start 171.074588 -12.512548)
		(end 170.312588 -12.512548)
		(stroke
			(width 0.1016)
			(type default)
		)
		(layer "In3.Cu")
	)
	(gr_line
		(start 171.074588 -12.463272)
		(end 171.074588 -12.412472)
		(stroke
			(width 0.1016)
			(type default)
		)
		(layer "In3.Cu")
	)
	(gr_line
		(start 171.074588 -12.463272)
		(end 171.480988 -12.463272)
		(stroke
			(width 0.1016)
			(type default)
		)
		(layer "In3.Cu")
	)
	(gr_line
		(start 171.074588 -12.412472)
		(end 170.312588 -12.412472)
		(stroke
			(width 0.1016)
			(type default)
		)
		(layer "In3.Cu")
	)
	(gr_line
		(start 171.074588 -12.233148)
		(end 171.074588 -10.251948)
		(stroke
			(width 0.762)
			(type default)
		)
		(layer "In3.Cu")
	)
	(gr_line
		(start 171.074588 -12.133072)
		(end 171.074588 -10.151872)
		(stroke
			(width 0.762)
			(type default)
		)
		(layer "In3.Cu")
	)
	(gr_line
		(start 171.074588 -8.363204)
		(end 171.074588 -8.312404)
		(stroke
			(width 0.1016)
			(type default)
		)
		(layer "In3.Cu")
	)
	(gr_line
		(start 171.074588 -8.363204)
		(end 171.480988 -8.363204)
		(stroke
			(width 0.1016)
			(type default)
		)
		(layer "In3.Cu")
	)
	(gr_line
		(start 171.074588 -8.312404)
		(end 170.312588 -8.312404)
		(stroke
			(width 0.1016)
			(type default)
		)
		(layer "In3.Cu")
	)
	(gr_line
		(start 171.074588 -8.263128)
		(end 171.074588 -8.212328)
		(stroke
			(width 0.1016)
			(type default)
		)
		(layer "In3.Cu")
	)
	(gr_line
		(start 171.074588 -8.263128)
		(end 171.480988 -8.263128)
		(stroke
			(width 0.1016)
			(type default)
		)
		(layer "In3.Cu")
	)
	(gr_line
		(start 171.074588 -8.212328)
		(end 170.312588 -8.212328)
		(stroke
			(width 0.1016)
			(type default)
		)
		(layer "In3.Cu")
	)
	(gr_line
		(start 171.074588 -8.033004)
		(end 171.074588 -6.051804)
		(stroke
			(width 0.762)
			(type default)
		)
		(layer "In3.Cu")
	)
	(gr_line
		(start 171.074588 -7.932928)
		(end 171.074588 -5.951728)
		(stroke
			(width 0.762)
			(type default)
		)
		(layer "In3.Cu")
	)
	(gr_line
		(start 171.099988 -12.283948)
		(end 170.693588 -12.283948)
		(stroke
			(width 0.254)
			(type default)
		)
		(layer "In3.Cu")
	)
	(gr_line
		(start 171.099988 -12.183872)
		(end 170.693588 -12.183872)
		(stroke
			(width 0.254)
			(type default)
		)
		(layer "In3.Cu")
	)
	(gr_line
		(start 171.099988 -10.175748)
		(end 171.099988 -12.283948)
		(stroke
			(width 0.254)
			(type default)
		)
		(layer "In3.Cu")
	)
	(gr_line
		(start 171.099988 -10.075672)
		(end 171.099988 -12.183872)
		(stroke
			(width 0.254)
			(type default)
		)
		(layer "In3.Cu")
	)
	(gr_line
		(start 171.099988 -8.083804)
		(end 170.693588 -8.083804)
		(stroke
			(width 0.254)
			(type default)
		)
		(layer "In3.Cu")
	)
	(gr_line
		(start 171.099988 -7.983728)
		(end 170.693588 -7.983728)
		(stroke
			(width 0.254)
			(type default)
		)
		(layer "In3.Cu")
	)
	(gr_line
		(start 171.099988 -5.975604)
		(end 171.099988 -8.083804)
		(stroke
			(width 0.254)
			(type default)
		)
		(layer "In3.Cu")
	)
	(gr_line
		(start 171.099988 -5.875528)
		(end 171.099988 -7.983728)
		(stroke
			(width 0.254)
			(type default)
		)
		(layer "In3.Cu")
	)
	(gr_line
		(start 171.150788 -12.233148)
		(end 171.150788 -10.251948)
		(stroke
			(width 0.762)
			(type default)
		)
		(layer "In3.Cu")
	)
	(gr_line
		(start 171.150788 -12.133072)
		(end 171.150788 -10.151872)
		(stroke
			(width 0.762)
			(type default)
		)
		(layer "In3.Cu")
	)
	(gr_line
		(start 171.150788 -8.033004)
		(end 171.150788 -6.051804)
		(stroke
			(width 0.762)
			(type default)
		)
		(layer "In3.Cu")
	)
	(gr_line
		(start 171.150788 -7.932928)
		(end 171.150788 -5.951728)
		(stroke
			(width 0.762)
			(type default)
		)
		(layer "In3.Cu")
	)
	(gr_line
		(start 171.176188 -12.360148)
		(end 170.617388 -12.360148)
		(stroke
			(width 0.254)
			(type default)
		)
		(layer "In3.Cu")
	)
	(gr_line
		(start 171.176188 -12.260072)
		(end 170.617388 -12.260072)
		(stroke
			(width 0.254)
			(type default)
		)
		(layer "In3.Cu")
	)
	(gr_line
		(start 171.176188 -10.124948)
		(end 171.176188 -12.360148)
		(stroke
			(width 0.254)
			(type default)
		)
		(layer "In3.Cu")
	)
	(gr_line
		(start 171.176188 -10.024872)
		(end 171.176188 -12.260072)
		(stroke
			(width 0.254)
			(type default)
		)
		(layer "In3.Cu")
	)
	(gr_line
		(start 171.176188 -8.160004)
		(end 170.617388 -8.160004)
		(stroke
			(width 0.254)
			(type default)
		)
		(layer "In3.Cu")
	)
	(gr_line
		(start 171.176188 -8.059928)
		(end 170.617388 -8.059928)
		(stroke
			(width 0.254)
			(type default)
		)
		(layer "In3.Cu")
	)
	(gr_line
		(start 171.176188 -5.924804)
		(end 171.176188 -8.160004)
		(stroke
			(width 0.254)
			(type default)
		)
		(layer "In3.Cu")
	)
	(gr_line
		(start 171.176188 -5.824728)
		(end 171.176188 -8.059928)
		(stroke
			(width 0.254)
			(type default)
		)
		(layer "In3.Cu")
	)
	(gr_line
		(start 171.252388 -12.385548)
		(end 170.541188 -12.385548)
		(stroke
			(width 0.254)
			(type default)
		)
		(layer "In3.Cu")
	)
	(gr_line
		(start 171.252388 -12.285472)
		(end 170.541188 -12.285472)
		(stroke
			(width 0.254)
			(type default)
		)
		(layer "In3.Cu")
	)
	(gr_line
		(start 171.252388 -10.048748)
		(end 171.252388 -12.385548)
		(stroke
			(width 0.254)
			(type default)
		)
		(layer "In3.Cu")
	)
	(gr_line
		(start 171.252388 -9.948672)
		(end 171.252388 -12.285472)
		(stroke
			(width 0.254)
			(type default)
		)
		(layer "In3.Cu")
	)
	(gr_line
		(start 171.252388 -8.185404)
		(end 170.541188 -8.185404)
		(stroke
			(width 0.254)
			(type default)
		)
		(layer "In3.Cu")
	)
	(gr_line
		(start 171.252388 -8.085328)
		(end 170.541188 -8.085328)
		(stroke
			(width 0.254)
			(type default)
		)
		(layer "In3.Cu")
	)
	(gr_line
		(start 171.252388 -5.848604)
		(end 171.252388 -8.185404)
		(stroke
			(width 0.254)
			(type default)
		)
		(layer "In3.Cu")
	)
	(gr_line
		(start 171.252388 -5.748528)
		(end 171.252388 -8.085328)
		(stroke
			(width 0.254)
			(type default)
		)
		(layer "In3.Cu")
	)
	(gr_line
		(start 171.277788 -12.512548)
		(end 170.287188 -12.512548)
		(stroke
			(width 0.1016)
			(type default)
		)
		(layer "In3.Cu")
	)
	(gr_line
		(start 171.277788 -12.436348)
		(end 170.464988 -12.436348)
		(stroke
			(width 0.254)
			(type default)
		)
		(layer "In3.Cu")
	)
	(gr_line
		(start 171.277788 -12.412472)
		(end 170.287188 -12.412472)
		(stroke
			(width 0.1016)
			(type default)
		)
		(layer "In3.Cu")
	)
	(gr_line
		(start 171.277788 -12.336272)
		(end 170.464988 -12.336272)
		(stroke
			(width 0.254)
			(type default)
		)
		(layer "In3.Cu")
	)
	(gr_line
		(start 171.277788 -10.023348)
		(end 171.277788 -12.436348)
		(stroke
			(width 0.254)
			(type default)
		)
		(layer "In3.Cu")
	)
	(gr_line
		(start 171.277788 -9.923272)
		(end 171.277788 -12.336272)
		(stroke
			(width 0.254)
			(type default)
		)
		(layer "In3.Cu")
	)
	(gr_line
		(start 171.277788 -8.312404)
		(end 170.287188 -8.312404)
		(stroke
			(width 0.1016)
			(type default)
		)
		(layer "In3.Cu")
	)
	(gr_line
		(start 171.277788 -8.236204)
		(end 170.464988 -8.236204)
		(stroke
			(width 0.254)
			(type default)
		)
		(layer "In3.Cu")
	)
	(gr_line
		(start 171.277788 -8.212328)
		(end 170.287188 -8.212328)
		(stroke
			(width 0.1016)
			(type default)
		)
		(layer "In3.Cu")
	)
	(gr_line
		(start 171.277788 -8.136128)
		(end 170.464988 -8.136128)
		(stroke
			(width 0.254)
			(type default)
		)
		(layer "In3.Cu")
	)
	(gr_line
		(start 171.277788 -5.823204)
		(end 171.277788 -8.236204)
		(stroke
			(width 0.254)
			(type default)
		)
		(layer "In3.Cu")
	)
	(gr_line
		(start 171.277788 -5.723128)
		(end 171.277788 -8.136128)
		(stroke
			(width 0.254)
			(type default)
		)
		(layer "In3.Cu")
	)
	(gr_line
		(start 171.303188 -12.461748)
		(end 170.439588 -12.461748)
		(stroke
			(width 0.254)
			(type default)
		)
		(layer "In3.Cu")
	)
	(gr_line
		(start 171.303188 -12.361672)
		(end 170.439588 -12.361672)
		(stroke
			(width 0.254)
			(type default)
		)
		(layer "In3.Cu")
	)
	(gr_line
		(start 171.303188 -9.997948)
		(end 171.303188 -12.461748)
		(stroke
			(width 0.254)
			(type default)
		)
		(layer "In3.Cu")
	)
	(gr_line
		(start 171.303188 -9.897872)
		(end 171.303188 -12.361672)
		(stroke
			(width 0.254)
			(type default)
		)
		(layer "In3.Cu")
	)
	(gr_line
		(start 171.303188 -8.261604)
		(end 170.439588 -8.261604)
		(stroke
			(width 0.254)
			(type default)
		)
		(layer "In3.Cu")
	)
	(gr_line
		(start 171.303188 -8.161528)
		(end 170.439588 -8.161528)
		(stroke
			(width 0.254)
			(type default)
		)
		(layer "In3.Cu")
	)
	(gr_line
		(start 171.303188 -5.797804)
		(end 171.303188 -8.261604)
		(stroke
			(width 0.254)
			(type default)
		)
		(layer "In3.Cu")
	)
	(gr_line
		(start 171.303188 -5.697728)
		(end 171.303188 -8.161528)
		(stroke
			(width 0.254)
			(type default)
		)
		(layer "In3.Cu")
	)
	(gr_line
		(start 171.353988 -12.487148)
		(end 170.414188 -12.487148)
		(stroke
			(width 0.254)
			(type default)
		)
		(layer "In3.Cu")
	)
	(gr_line
		(start 171.353988 -12.387072)
		(end 170.414188 -12.387072)
		(stroke
			(width 0.254)
			(type default)
		)
		(layer "In3.Cu")
	)
	(gr_line
		(start 171.353988 -9.997948)
		(end 171.353988 -12.487148)
		(stroke
			(width 0.254)
			(type default)
		)
		(layer "In3.Cu")
	)
	(gr_line
		(start 171.353988 -9.897872)
		(end 171.353988 -12.387072)
		(stroke
			(width 0.254)
			(type default)
		)
		(layer "In3.Cu")
	)
	(gr_line
		(start 171.353988 -8.287004)
		(end 170.414188 -8.287004)
		(stroke
			(width 0.254)
			(type default)
		)
		(layer "In3.Cu")
	)
	(gr_line
		(start 171.353988 -8.186928)
		(end 170.414188 -8.186928)
		(stroke
			(width 0.254)
			(type default)
		)
		(layer "In3.Cu")
	)
	(gr_line
		(start 171.353988 -5.797804)
		(end 171.353988 -8.287004)
		(stroke
			(width 0.254)
			(type default)
		)
		(layer "In3.Cu")
	)
	(gr_line
		(start 171.353988 -5.697728)
		(end 171.353988 -8.186928)
		(stroke
			(width 0.254)
			(type default)
		)
		(layer "In3.Cu")
	)
	(gr_line
		(start 171.379388 -12.487148)
		(end 170.414188 -12.487148)
		(stroke
			(width 0.2032)
			(type default)
		)
		(layer "In3.Cu")
	)
	(gr_line
		(start 171.379388 -12.387072)
		(end 170.414188 -12.387072)
		(stroke
			(width 0.2032)
			(type default)
		)
		(layer "In3.Cu")
	)
	(gr_line
		(start 171.379388 -9.947148)
		(end 171.379388 -12.487148)
		(stroke
			(width 0.2032)
			(type default)
		)
		(layer "In3.Cu")
	)
	(gr_line
		(start 171.379388 -9.847072)
		(end 171.379388 -12.387072)
		(stroke
			(width 0.2032)
			(type default)
		)
		(layer "In3.Cu")
	)
	(gr_line
		(start 171.379388 -8.287004)
		(end 170.414188 -8.287004)
		(stroke
			(width 0.2032)
			(type default)
		)
		(layer "In3.Cu")
	)
	(gr_line
		(start 171.379388 -8.186928)
		(end 170.414188 -8.186928)
		(stroke
			(width 0.2032)
			(type default)
		)
		(layer "In3.Cu")
	)
	(gr_line
		(start 171.379388 -5.747004)
		(end 171.379388 -8.287004)
		(stroke
			(width 0.2032)
			(type default)
		)
		(layer "In3.Cu")
	)
	(gr_line
		(start 171.379388 -5.646928)
		(end 171.379388 -8.186928)
		(stroke
			(width 0.2032)
			(type default)
		)
		(layer "In3.Cu")
	)
	(gr_line
		(start 171.430188 -12.512548)
		(end 170.363388 -12.512548)
		(stroke
			(width 0.2032)
			(type default)
		)
		(layer "In3.Cu")
	)
	(gr_line
		(start 171.430188 -12.412472)
		(end 170.363388 -12.412472)
		(stroke
			(width 0.2032)
			(type default)
		)
		(layer "In3.Cu")
	)
	(gr_line
		(start 171.430188 -9.947148)
		(end 171.430188 -12.512548)
		(stroke
			(width 0.2032)
			(type default)
		)
		(layer "In3.Cu")
	)
	(gr_line
		(start 171.430188 -9.847072)
		(end 171.430188 -12.412472)
		(stroke
			(width 0.2032)
			(type default)
		)
		(layer "In3.Cu")
	)
	(gr_line
		(start 171.430188 -8.312404)
		(end 170.363388 -8.312404)
		(stroke
			(width 0.2032)
			(type default)
		)
		(layer "In3.Cu")
	)
	(gr_line
		(start 171.430188 -8.212328)
		(end 170.363388 -8.212328)
		(stroke
			(width 0.2032)
			(type default)
		)
		(layer "In3.Cu")
	)
	(gr_line
		(start 171.430188 -5.747004)
		(end 171.430188 -8.312404)
		(stroke
			(width 0.2032)
			(type default)
		)
		(layer "In3.Cu")
	)
	(gr_line
		(start 171.430188 -5.646928)
		(end 171.430188 -8.212328)
		(stroke
			(width 0.2032)
			(type default)
		)
		(layer "In3.Cu")
	)
	(gr_line
		(start 171.455588 -12.512548)
		(end 170.337988 -12.512548)
		(stroke
			(width 0.1016)
			(type default)
		)
		(layer "In3.Cu")
	)
	(gr_line
		(start 171.455588 -12.412472)
		(end 170.337988 -12.412472)
		(stroke
			(width 0.1016)
			(type default)
		)
		(layer "In3.Cu")
	)
	(gr_line
		(start 171.455588 -9.921748)
		(end 171.455588 -12.512548)
		(stroke
			(width 0.1016)
			(type default)
		)
		(layer "In3.Cu")
	)
	(gr_line
		(start 171.455588 -9.821672)
		(end 171.455588 -12.412472)
		(stroke
			(width 0.1016)
			(type default)
		)
		(layer "In3.Cu")
	)
	(gr_line
		(start 171.455588 -8.312404)
		(end 170.337988 -8.312404)
		(stroke
			(width 0.1016)
			(type default)
		)
		(layer "In3.Cu")
	)
	(gr_line
		(start 171.455588 -8.212328)
		(end 170.337988 -8.212328)
		(stroke
			(width 0.1016)
			(type default)
		)
		(layer "In3.Cu")
	)
	(gr_line
		(start 171.455588 -5.721604)
		(end 171.455588 -8.312404)
		(stroke
			(width 0.1016)
			(type default)
		)
		(layer "In3.Cu")
	)
	(gr_line
		(start 171.455588 -5.621528)
		(end 171.455588 -8.212328)
		(stroke
			(width 0.1016)
			(type default)
		)
		(layer "In3.Cu")
	)
	(gr_line
		(start 171.480988 -12.563348)
		(end 171.074588 -12.563348)
		(stroke
			(width 0.1016)
			(type default)
		)
		(layer "In3.Cu")
	)
	(gr_line
		(start 171.480988 -12.563348)
		(end 171.480988 -9.896348)
		(stroke
			(width 0.1016)
			(type default)
		)
		(layer "In3.Cu")
	)
	(gr_line
		(start 171.480988 -12.463272)
		(end 171.074588 -12.463272)
		(stroke
			(width 0.1016)
			(type default)
		)
		(layer "In3.Cu")
	)
	(gr_line
		(start 171.480988 -12.463272)
		(end 171.480988 -9.796272)
		(stroke
			(width 0.1016)
			(type default)
		)
		(layer "In3.Cu")
	)
	(gr_line
		(start 171.480988 -9.896348)
		(end 170.287188 -9.896348)
		(stroke
			(width 0.1016)
			(type default)
		)
		(layer "In3.Cu")
	)
	(gr_line
		(start 171.480988 -9.896348)
		(end 171.480988 -12.563348)
		(stroke
			(width 0.1016)
			(type default)
		)
		(layer "In3.Cu")
	)
	(gr_line
		(start 171.480988 -9.796272)
		(end 170.287188 -9.796272)
		(stroke
			(width 0.1016)
			(type default)
		)
		(layer "In3.Cu")
	)
	(gr_line
		(start 171.480988 -9.796272)
		(end 171.480988 -12.463272)
		(stroke
			(width 0.1016)
			(type default)
		)
		(layer "In3.Cu")
	)
	(gr_line
		(start 171.480988 -8.363204)
		(end 171.074588 -8.363204)
		(stroke
			(width 0.1016)
			(type default)
		)
		(layer "In3.Cu")
	)
	(gr_line
		(start 171.480988 -8.363204)
		(end 171.480988 -5.696204)
		(stroke
			(width 0.1016)
			(type default)
		)
		(layer "In3.Cu")
	)
	(gr_line
		(start 171.480988 -8.263128)
		(end 171.074588 -8.263128)
		(stroke
			(width 0.1016)
			(type default)
		)
		(layer "In3.Cu")
	)
	(gr_line
		(start 171.480988 -8.263128)
		(end 171.480988 -5.596128)
		(stroke
			(width 0.1016)
			(type default)
		)
		(layer "In3.Cu")
	)
	(gr_line
		(start 171.480988 -5.696204)
		(end 170.287188 -5.696204)
		(stroke
			(width 0.1016)
			(type default)
		)
		(layer "In3.Cu")
	)
	(gr_line
		(start 171.480988 -5.696204)
		(end 171.480988 -8.363204)
		(stroke
			(width 0.1016)
			(type default)
		)
		(layer "In3.Cu")
	)
	(gr_line
		(start 171.480988 -5.596128)
		(end 170.287188 -5.596128)
		(stroke
			(width 0.1016)
			(type default)
		)
		(layer "In3.Cu")
	)
	(gr_line
		(start 171.480988 -5.596128)
		(end 171.480988 -8.263128)
		(stroke
			(width 0.1016)
			(type default)
		)
		(layer "In3.Cu")
	)
	(gr_line
		(start 171.720002 -31.98622)
		(end 170.450002 -31.98622)
		(stroke
			(width 0.7874)
			(type default)
		)
		(layer "In3.Cu")
	)
	(gr_line
		(start 172.120052 -23.69566)
		(end 170.850052 -23.69566)
		(stroke
			(width 0.7874)
			(type default)
		)
		(layer "In3.Cu")
	)
	(gr_line
		(start 172.287184 -13.8176)
		(end 173.074584 -13.8176)
		(stroke
			(width 0.1016)
			(type default)
		)
		(layer "In3.Cu")
	)
	(gr_line
		(start 172.287184 -13.7668)
		(end 172.287184 -11.1506)
		(stroke
			(width 0.1016)
			(type default)
		)
		(layer "In3.Cu")
	)
	(gr_line
		(start 172.287184 -11.1506)
		(end 172.287184 -13.8176)
		(stroke
			(width 0.1016)
			(type default)
		)
		(layer "In3.Cu")
	)
	(gr_line
		(start 172.287184 -11.1506)
		(end 173.480984 -11.1506)
		(stroke
			(width 0.1016)
			(type default)
		)
		(layer "In3.Cu")
	)
	(gr_line
		(start 172.287184 -9.617456)
		(end 173.074584 -9.617456)
		(stroke
			(width 0.1016)
			(type default)
		)
		(layer "In3.Cu")
	)
	(gr_line
		(start 172.287184 -9.566656)
		(end 172.287184 -6.950456)
		(stroke
			(width 0.1016)
			(type default)
		)
		(layer "In3.Cu")
	)
	(gr_line
		(start 172.287184 -6.950456)
		(end 172.287184 -9.617456)
		(stroke
			(width 0.1016)
			(type default)
		)
		(layer "In3.Cu")
	)
	(gr_line
		(start 172.287184 -6.950456)
		(end 173.480984 -6.950456)
		(stroke
			(width 0.1016)
			(type default)
		)
		(layer "In3.Cu")
	)
	(gr_line
		(start 172.287184 -5.417312)
		(end 173.074584 -5.417312)
		(stroke
			(width 0.1016)
			(type default)
		)
		(layer "In3.Cu")
	)
	(gr_line
		(start 172.287184 -5.366512)
		(end 172.287184 -2.750312)
		(stroke
			(width 0.1016)
			(type default)
		)
		(layer "In3.Cu")
	)
	(gr_line
		(start 172.287184 -2.750312)
		(end 172.287184 -5.417312)
		(stroke
			(width 0.1016)
			(type default)
		)
		(layer "In3.Cu")
	)
	(gr_line
		(start 172.287184 -2.750312)
		(end 173.480984 -2.750312)
		(stroke
			(width 0.1016)
			(type default)
		)
		(layer "In3.Cu")
	)
	(gr_line
		(start 172.312584 -13.7668)
		(end 172.312584 -11.176)
		(stroke
			(width 0.1016)
			(type default)
		)
		(layer "In3.Cu")
	)
	(gr_line
		(start 172.312584 -11.176)
		(end 173.455584 -11.176)
		(stroke
			(width 0.1016)
			(type default)
		)
		(layer "In3.Cu")
	)
	(gr_line
		(start 172.312584 -9.566656)
		(end 172.312584 -6.975856)
		(stroke
			(width 0.1016)
			(type default)
		)
		(layer "In3.Cu")
	)
	(gr_line
		(start 172.312584 -6.975856)
		(end 173.455584 -6.975856)
		(stroke
			(width 0.1016)
			(type default)
		)
		(layer "In3.Cu")
	)
	(gr_line
		(start 172.312584 -5.366512)
		(end 172.312584 -2.775712)
		(stroke
			(width 0.1016)
			(type default)
		)
		(layer "In3.Cu")
	)
	(gr_line
		(start 172.312584 -2.775712)
		(end 173.455584 -2.775712)
		(stroke
			(width 0.1016)
			(type default)
		)
		(layer "In3.Cu")
	)
	(gr_line
		(start 172.337984 -13.7668)
		(end 172.337984 -11.2014)
		(stroke
			(width 0.1016)
			(type default)
		)
		(layer "In3.Cu")
	)
	(gr_line
		(start 172.337984 -11.2014)
		(end 172.591984 -11.2014)
		(stroke
			(width 0.1016)
			(type default)
		)
		(layer "In3.Cu")
	)
	(gr_line
		(start 172.337984 -9.566656)
		(end 172.337984 -7.001256)
		(stroke
			(width 0.1016)
			(type default)
		)
		(layer "In3.Cu")
	)
	(gr_line
		(start 172.337984 -7.001256)
		(end 172.591984 -7.001256)
		(stroke
			(width 0.1016)
			(type default)
		)
		(layer "In3.Cu")
	)
	(gr_line
		(start 172.337984 -5.366512)
		(end 172.337984 -2.801112)
		(stroke
			(width 0.1016)
			(type default)
		)
		(layer "In3.Cu")
	)
	(gr_line
		(start 172.337984 -2.801112)
		(end 172.591984 -2.801112)
		(stroke
			(width 0.1016)
			(type default)
		)
		(layer "In3.Cu")
	)
	(gr_line
		(start 172.363384 -13.7668)
		(end 172.363384 -11.2014)
		(stroke
			(width 0.2032)
			(type default)
		)
		(layer "In3.Cu")
	)
	(gr_line
		(start 172.363384 -11.2014)
		(end 173.379384 -11.2014)
		(stroke
			(width 0.2032)
			(type default)
		)
		(layer "In3.Cu")
	)
	(gr_line
		(start 172.363384 -9.566656)
		(end 172.363384 -7.001256)
		(stroke
			(width 0.2032)
			(type default)
		)
		(layer "In3.Cu")
	)
	(gr_line
		(start 172.363384 -7.001256)
		(end 173.379384 -7.001256)
		(stroke
			(width 0.2032)
			(type default)
		)
		(layer "In3.Cu")
	)
	(gr_line
		(start 172.363384 -5.366512)
		(end 172.363384 -2.801112)
		(stroke
			(width 0.2032)
			(type default)
		)
		(layer "In3.Cu")
	)
	(gr_line
		(start 172.363384 -2.801112)
		(end 173.379384 -2.801112)
		(stroke
			(width 0.2032)
			(type default)
		)
		(layer "In3.Cu")
	)
	(gr_line
		(start 172.414184 -13.7414)
		(end 172.414184 -11.2522)
		(stroke
			(width 0.2032)
			(type default)
		)
		(layer "In3.Cu")
	)
	(gr_line
		(start 172.414184 -13.7414)
		(end 172.414184 -11.2522)
		(stroke
			(width 0.254)
			(type default)
		)
		(layer "In3.Cu")
	)
	(gr_line
		(start 172.414184 -11.2522)
		(end 172.617384 -11.2522)
		(stroke
			(width 0.2032)
			(type default)
		)
		(layer "In3.Cu")
	)
	(gr_line
		(start 172.414184 -11.2522)
		(end 173.303184 -11.2522)
		(stroke
			(width 0.254)
			(type default)
		)
		(layer "In3.Cu")
	)
	(gr_line
		(start 172.414184 -9.541256)
		(end 172.414184 -7.052056)
		(stroke
			(width 0.2032)
			(type default)
		)
		(layer "In3.Cu")
	)
	(gr_line
		(start 172.414184 -9.541256)
		(end 172.414184 -7.052056)
		(stroke
			(width 0.254)
			(type default)
		)
		(layer "In3.Cu")
	)
	(gr_line
		(start 172.414184 -7.052056)
		(end 172.617384 -7.052056)
		(stroke
			(width 0.2032)
			(type default)
		)
		(layer "In3.Cu")
	)
	(gr_line
		(start 172.414184 -7.052056)
		(end 173.303184 -7.052056)
		(stroke
			(width 0.254)
			(type default)
		)
		(layer "In3.Cu")
	)
	(gr_line
		(start 172.414184 -5.341112)
		(end 172.414184 -2.851912)
		(stroke
			(width 0.2032)
			(type default)
		)
		(layer "In3.Cu")
	)
	(gr_line
		(start 172.414184 -5.341112)
		(end 172.414184 -2.851912)
		(stroke
			(width 0.254)
			(type default)
		)
		(layer "In3.Cu")
	)
	(gr_line
		(start 172.414184 -2.851912)
		(end 172.617384 -2.851912)
		(stroke
			(width 0.2032)
			(type default)
		)
		(layer "In3.Cu")
	)
	(gr_line
		(start 172.414184 -2.851912)
		(end 173.303184 -2.851912)
		(stroke
			(width 0.254)
			(type default)
		)
		(layer "In3.Cu")
	)
	(gr_line
		(start 172.439584 -13.716)
		(end 172.439584 -11.2776)
		(stroke
			(width 0.254)
			(type default)
		)
		(layer "In3.Cu")
	)
	(gr_line
		(start 172.439584 -11.2776)
		(end 173.277784 -11.2776)
		(stroke
			(width 0.254)
			(type default)
		)
		(layer "In3.Cu")
	)
	(gr_line
		(start 172.439584 -9.515856)
		(end 172.439584 -7.077456)
		(stroke
			(width 0.254)
			(type default)
		)
		(layer "In3.Cu")
	)
	(gr_line
		(start 172.439584 -7.077456)
		(end 173.277784 -7.077456)
		(stroke
			(width 0.254)
			(type default)
		)
		(layer "In3.Cu")
	)
	(gr_line
		(start 172.439584 -5.315712)
		(end 172.439584 -2.877312)
		(stroke
			(width 0.254)
			(type default)
		)
		(layer "In3.Cu")
	)
	(gr_line
		(start 172.439584 -2.877312)
		(end 173.277784 -2.877312)
		(stroke
			(width 0.254)
			(type default)
		)
		(layer "In3.Cu")
	)
	(gr_line
		(start 172.464984 -13.6906)
		(end 172.464984 -11.303)
		(stroke
			(width 0.254)
			(type default)
		)
		(layer "In3.Cu")
	)
	(gr_line
		(start 172.464984 -11.303)
		(end 173.252384 -11.303)
		(stroke
			(width 0.254)
			(type default)
		)
		(layer "In3.Cu")
	)
	(gr_line
		(start 172.464984 -9.490456)
		(end 172.464984 -7.102856)
		(stroke
			(width 0.254)
			(type default)
		)
		(layer "In3.Cu")
	)
	(gr_line
		(start 172.464984 -7.102856)
		(end 173.252384 -7.102856)
		(stroke
			(width 0.254)
			(type default)
		)
		(layer "In3.Cu")
	)
	(gr_line
		(start 172.464984 -5.290312)
		(end 172.464984 -2.902712)
		(stroke
			(width 0.254)
			(type default)
		)
		(layer "In3.Cu")
	)
	(gr_line
		(start 172.464984 -2.902712)
		(end 173.252384 -2.902712)
		(stroke
			(width 0.254)
			(type default)
		)
		(layer "In3.Cu")
	)
	(gr_line
		(start 172.490384 -13.6144)
		(end 173.125384 -13.6144)
		(stroke
			(width 0.508)
			(type default)
		)
		(layer "In3.Cu")
	)
	(gr_line
		(start 172.490384 -11.43)
		(end 173.125384 -11.43)
		(stroke
			(width 0.508)
			(type default)
		)
		(layer "In3.Cu")
	)
	(gr_line
		(start 172.490384 -11.3792)
		(end 173.125384 -11.3792)
		(stroke
			(width 0.508)
			(type default)
		)
		(layer "In3.Cu")
	)
	(gr_line
		(start 172.490384 -9.414256)
		(end 173.125384 -9.414256)
		(stroke
			(width 0.508)
			(type default)
		)
		(layer "In3.Cu")
	)
	(gr_line
		(start 172.490384 -7.229856)
		(end 173.125384 -7.229856)
		(stroke
			(width 0.508)
			(type default)
		)
		(layer "In3.Cu")
	)
	(gr_line
		(start 172.490384 -7.179056)
		(end 173.125384 -7.179056)
		(stroke
			(width 0.508)
			(type default)
		)
		(layer "In3.Cu")
	)
	(gr_line
		(start 172.490384 -5.214112)
		(end 173.125384 -5.214112)
		(stroke
			(width 0.508)
			(type default)
		)
		(layer "In3.Cu")
	)
	(gr_line
		(start 172.490384 -3.029712)
		(end 173.125384 -3.029712)
		(stroke
			(width 0.508)
			(type default)
		)
		(layer "In3.Cu")
	)
	(gr_line
		(start 172.490384 -2.978912)
		(end 173.125384 -2.978912)
		(stroke
			(width 0.508)
			(type default)
		)
		(layer "In3.Cu")
	)
	(gr_line
		(start 172.515784 -11.684)
		(end 173.150784 -11.684)
		(stroke
			(width 0.508)
			(type default)
		)
		(layer "In3.Cu")
	)
	(gr_line
		(start 172.515784 -7.483856)
		(end 173.150784 -7.483856)
		(stroke
			(width 0.508)
			(type default)
		)
		(layer "In3.Cu")
	)
	(gr_line
		(start 172.515784 -3.283712)
		(end 173.150784 -3.283712)
		(stroke
			(width 0.508)
			(type default)
		)
		(layer "In3.Cu")
	)
	(gr_line
		(start 172.541184 -13.6398)
		(end 172.541184 -11.3792)
		(stroke
			(width 0.254)
			(type default)
		)
		(layer "In3.Cu")
	)
	(gr_line
		(start 172.541184 -13.4874)
		(end 173.176184 -13.4874)
		(stroke
			(width 0.508)
			(type default)
		)
		(layer "In3.Cu")
	)
	(gr_line
		(start 172.541184 -11.3792)
		(end 173.176184 -11.3792)
		(stroke
			(width 0.254)
			(type default)
		)
		(layer "In3.Cu")
	)
	(gr_line
		(start 172.541184 -9.439656)
		(end 172.541184 -7.179056)
		(stroke
			(width 0.254)
			(type default)
		)
		(layer "In3.Cu")
	)
	(gr_line
		(start 172.541184 -9.287256)
		(end 173.176184 -9.287256)
		(stroke
			(width 0.508)
			(type default)
		)
		(layer "In3.Cu")
	)
	(gr_line
		(start 172.541184 -7.179056)
		(end 173.176184 -7.179056)
		(stroke
			(width 0.254)
			(type default)
		)
		(layer "In3.Cu")
	)
	(gr_line
		(start 172.541184 -5.239512)
		(end 172.541184 -2.978912)
		(stroke
			(width 0.254)
			(type default)
		)
		(layer "In3.Cu")
	)
	(gr_line
		(start 172.541184 -5.087112)
		(end 173.176184 -5.087112)
		(stroke
			(width 0.508)
			(type default)
		)
		(layer "In3.Cu")
	)
	(gr_line
		(start 172.541184 -2.978912)
		(end 173.176184 -2.978912)
		(stroke
			(width 0.254)
			(type default)
		)
		(layer "In3.Cu")
	)
	(gr_line
		(start 172.566584 -13.335)
		(end 173.201584 -13.335)
		(stroke
			(width 0.508)
			(type default)
		)
		(layer "In3.Cu")
	)
	(gr_line
		(start 172.566584 -9.134856)
		(end 173.201584 -9.134856)
		(stroke
			(width 0.508)
			(type default)
		)
		(layer "In3.Cu")
	)
	(gr_line
		(start 172.566584 -4.934712)
		(end 173.201584 -4.934712)
		(stroke
			(width 0.508)
			(type default)
		)
		(layer "In3.Cu")
	)
	(gr_line
		(start 172.591984 -13.6144)
		(end 173.226984 -13.6144)
		(stroke
			(width 0.508)
			(type default)
		)
		(layer "In3.Cu")
	)
	(gr_line
		(start 172.591984 -11.2014)
		(end 173.430184 -11.2014)
		(stroke
			(width 0.2032)
			(type default)
		)
		(layer "In3.Cu")
	)
	(gr_line
		(start 172.591984 -9.414256)
		(end 173.226984 -9.414256)
		(stroke
			(width 0.508)
			(type default)
		)
		(layer "In3.Cu")
	)
	(gr_line
		(start 172.591984 -7.001256)
		(end 173.430184 -7.001256)
		(stroke
			(width 0.2032)
			(type default)
		)
		(layer "In3.Cu")
	)
	(gr_line
		(start 172.591984 -5.214112)
		(end 173.226984 -5.214112)
		(stroke
			(width 0.508)
			(type default)
		)
		(layer "In3.Cu")
	)
	(gr_line
		(start 172.591984 -2.801112)
		(end 173.430184 -2.801112)
		(stroke
			(width 0.2032)
			(type default)
		)
		(layer "In3.Cu")
	)
	(gr_line
		(start 172.617384 -13.6144)
		(end 172.617384 -11.43)
		(stroke
			(width 0.254)
			(type default)
		)
		(layer "In3.Cu")
	)
	(gr_line
		(start 172.617384 -11.43)
		(end 173.099984 -11.43)
		(stroke
			(width 0.254)
			(type default)
		)
		(layer "In3.Cu")
	)
	(gr_line
		(start 172.617384 -11.2522)
		(end 173.353984 -11.2522)
		(stroke
			(width 0.254)
			(type default)
		)
		(layer "In3.Cu")
	)
	(gr_line
		(start 172.617384 -9.414256)
		(end 172.617384 -7.229856)
		(stroke
			(width 0.254)
			(type default)
		)
		(layer "In3.Cu")
	)
	(gr_line
		(start 172.617384 -7.229856)
		(end 173.099984 -7.229856)
		(stroke
			(width 0.254)
			(type default)
		)
		(layer "In3.Cu")
	)
	(gr_line
		(start 172.617384 -7.052056)
		(end 173.353984 -7.052056)
		(stroke
			(width 0.254)
			(type default)
		)
		(layer "In3.Cu")
	)
	(gr_line
		(start 172.617384 -5.214112)
		(end 172.617384 -3.029712)
		(stroke
			(width 0.254)
			(type default)
		)
		(layer "In3.Cu")
	)
	(gr_line
		(start 172.617384 -3.029712)
		(end 173.099984 -3.029712)
		(stroke
			(width 0.254)
			(type default)
		)
		(layer "In3.Cu")
	)
	(gr_line
		(start 172.617384 -2.851912)
		(end 173.353984 -2.851912)
		(stroke
			(width 0.254)
			(type default)
		)
		(layer "In3.Cu")
	)
	(gr_line
		(start 172.635926 -11.36523)
		(end 173.270926 -11.36523)
		(stroke
			(width 0.508)
			(type default)
		)
		(layer "In3.Cu")
	)
	(gr_line
		(start 172.635926 -7.165086)
		(end 173.270926 -7.165086)
		(stroke
			(width 0.508)
			(type default)
		)
		(layer "In3.Cu")
	)
	(gr_line
		(start 172.635926 -2.964942)
		(end 173.270926 -2.964942)
		(stroke
			(width 0.508)
			(type default)
		)
		(layer "In3.Cu")
	)
	(gr_line
		(start 172.642784 -13.6144)
		(end 173.277784 -13.6144)
		(stroke
			(width 0.508)
			(type default)
		)
		(layer "In3.Cu")
	)
	(gr_line
		(start 172.642784 -13.4874)
		(end 172.642784 -11.5062)
		(stroke
			(width 0.762)
			(type default)
		)
		(layer "In3.Cu")
	)
	(gr_line
		(start 172.642784 -11.5062)
		(end 173.277784 -11.5062)
		(stroke
			(width 0.508)
			(type default)
		)
		(layer "In3.Cu")
	)
	(gr_line
		(start 172.642784 -9.414256)
		(end 173.277784 -9.414256)
		(stroke
			(width 0.508)
			(type default)
		)
		(layer "In3.Cu")
	)
	(gr_line
		(start 172.642784 -9.287256)
		(end 172.642784 -7.306056)
		(stroke
			(width 0.762)
			(type default)
		)
		(layer "In3.Cu")
	)
	(gr_line
		(start 172.642784 -7.306056)
		(end 173.277784 -7.306056)
		(stroke
			(width 0.508)
			(type default)
		)
		(layer "In3.Cu")
	)
	(gr_line
		(start 172.642784 -5.214112)
		(end 173.277784 -5.214112)
		(stroke
			(width 0.508)
			(type default)
		)
		(layer "In3.Cu")
	)
	(gr_line
		(start 172.642784 -5.087112)
		(end 172.642784 -3.105912)
		(stroke
			(width 0.762)
			(type default)
		)
		(layer "In3.Cu")
	)
	(gr_line
		(start 172.642784 -3.105912)
		(end 173.277784 -3.105912)
		(stroke
			(width 0.508)
			(type default)
		)
		(layer "In3.Cu")
	)
	(gr_line
		(start 172.693584 -13.5382)
		(end 172.693584 -11.5062)
		(stroke
			(width 0.254)
			(type default)
		)
		(layer "In3.Cu")
	)
	(gr_line
		(start 172.693584 -11.5062)
		(end 173.023784 -11.5062)
		(stroke
			(width 0.254)
			(type default)
		)
		(layer "In3.Cu")
	)
	(gr_line
		(start 172.693584 -9.338056)
		(end 172.693584 -7.306056)
		(stroke
			(width 0.254)
			(type default)
		)
		(layer "In3.Cu")
	)
	(gr_line
		(start 172.693584 -7.306056)
		(end 173.023784 -7.306056)
		(stroke
			(width 0.254)
			(type default)
		)
		(layer "In3.Cu")
	)
	(gr_line
		(start 172.693584 -5.137912)
		(end 172.693584 -3.105912)
		(stroke
			(width 0.254)
			(type default)
		)
		(layer "In3.Cu")
	)
	(gr_line
		(start 172.693584 -3.105912)
		(end 173.023784 -3.105912)
		(stroke
			(width 0.254)
			(type default)
		)
		(layer "In3.Cu")
	)
	(gr_line
		(start 172.795184 -13.462)
		(end 172.795184 -11.6586)
		(stroke
			(width 0.254)
			(type default)
		)
		(layer "In3.Cu")
	)
	(gr_line
		(start 172.795184 -13.462)
		(end 172.795184 -11.4808)
		(stroke
			(width 0.762)
			(type default)
		)
		(layer "In3.Cu")
	)
	(gr_line
		(start 172.795184 -11.6586)
		(end 172.896784 -11.6586)
		(stroke
			(width 0.254)
			(type default)
		)
		(layer "In3.Cu")
	)
	(gr_line
		(start 172.795184 -9.261856)
		(end 172.795184 -7.458456)
		(stroke
			(width 0.254)
			(type default)
		)
		(layer "In3.Cu")
	)
	(gr_line
		(start 172.795184 -9.261856)
		(end 172.795184 -7.280656)
		(stroke
			(width 0.762)
			(type default)
		)
		(layer "In3.Cu")
	)
	(gr_line
		(start 172.795184 -7.458456)
		(end 172.896784 -7.458456)
		(stroke
			(width 0.254)
			(type default)
		)
		(layer "In3.Cu")
	)
	(gr_line
		(start 172.795184 -5.061712)
		(end 172.795184 -3.258312)
		(stroke
			(width 0.254)
			(type default)
		)
		(layer "In3.Cu")
	)
	(gr_line
		(start 172.795184 -5.061712)
		(end 172.795184 -3.080512)
		(stroke
			(width 0.762)
			(type default)
		)
		(layer "In3.Cu")
	)
	(gr_line
		(start 172.795184 -3.258312)
		(end 172.896784 -3.258312)
		(stroke
			(width 0.254)
			(type default)
		)
		(layer "In3.Cu")
	)
	(gr_line
		(start 172.896784 -13.5636)
		(end 172.845984 -13.5636)
		(stroke
			(width 0.254)
			(type default)
		)
		(layer "In3.Cu")
	)
	(gr_line
		(start 172.896784 -11.6586)
		(end 172.896784 -13.5636)
		(stroke
			(width 0.254)
			(type default)
		)
		(layer "In3.Cu")
	)
	(gr_line
		(start 172.896784 -9.363456)
		(end 172.845984 -9.363456)
		(stroke
			(width 0.254)
			(type default)
		)
		(layer "In3.Cu")
	)
	(gr_line
		(start 172.896784 -7.458456)
		(end 172.896784 -9.363456)
		(stroke
			(width 0.254)
			(type default)
		)
		(layer "In3.Cu")
	)
	(gr_line
		(start 172.896784 -5.163312)
		(end 172.845984 -5.163312)
		(stroke
			(width 0.254)
			(type default)
		)
		(layer "In3.Cu")
	)
	(gr_line
		(start 172.896784 -3.258312)
		(end 172.896784 -5.163312)
		(stroke
			(width 0.254)
			(type default)
		)
		(layer "In3.Cu")
	)
	(gr_line
		(start 172.947584 -13.4874)
		(end 172.947584 -11.5062)
		(stroke
			(width 0.762)
			(type default)
		)
		(layer "In3.Cu")
	)
	(gr_line
		(start 172.947584 -9.287256)
		(end 172.947584 -7.306056)
		(stroke
			(width 0.762)
			(type default)
		)
		(layer "In3.Cu")
	)
	(gr_line
		(start 172.947584 -5.087112)
		(end 172.947584 -3.105912)
		(stroke
			(width 0.762)
			(type default)
		)
		(layer "In3.Cu")
	)
	(gr_line
		(start 173.023784 -13.462)
		(end 172.795184 -13.462)
		(stroke
			(width 0.254)
			(type default)
		)
		(layer "In3.Cu")
	)
	(gr_line
		(start 173.023784 -11.5062)
		(end 173.023784 -13.462)
		(stroke
			(width 0.254)
			(type default)
		)
		(layer "In3.Cu")
	)
	(gr_line
		(start 173.023784 -9.261856)
		(end 172.795184 -9.261856)
		(stroke
			(width 0.254)
			(type default)
		)
		(layer "In3.Cu")
	)
	(gr_line
		(start 173.023784 -7.306056)
		(end 173.023784 -9.261856)
		(stroke
			(width 0.254)
			(type default)
		)
		(layer "In3.Cu")
	)
	(gr_line
		(start 173.023784 -5.061712)
		(end 172.795184 -5.061712)
		(stroke
			(width 0.254)
			(type default)
		)
		(layer "In3.Cu")
	)
	(gr_line
		(start 173.023784 -3.105912)
		(end 173.023784 -5.061712)
		(stroke
			(width 0.254)
			(type default)
		)
		(layer "In3.Cu")
	)
	(gr_line
		(start 173.074584 -13.8176)
		(end 173.074584 -13.7668)
		(stroke
			(width 0.1016)
			(type default)
		)
		(layer "In3.Cu")
	)
	(gr_line
		(start 173.074584 -13.8176)
		(end 173.480984 -13.8176)
		(stroke
			(width 0.1016)
			(type default)
		)
		(layer "In3.Cu")
	)
	(gr_line
		(start 173.074584 -13.7668)
		(end 172.312584 -13.7668)
		(stroke
			(width 0.1016)
			(type default)
		)
		(layer "In3.Cu")
	)
	(gr_line
		(start 173.074584 -13.4874)
		(end 173.074584 -11.5062)
		(stroke
			(width 0.762)
			(type default)
		)
		(layer "In3.Cu")
	)
	(gr_line
		(start 173.074584 -9.617456)
		(end 173.074584 -9.566656)
		(stroke
			(width 0.1016)
			(type default)
		)
		(layer "In3.Cu")
	)
	(gr_line
		(start 173.074584 -9.617456)
		(end 173.480984 -9.617456)
		(stroke
			(width 0.1016)
			(type default)
		)
		(layer "In3.Cu")
	)
	(gr_line
		(start 173.074584 -9.566656)
		(end 172.312584 -9.566656)
		(stroke
			(width 0.1016)
			(type default)
		)
		(layer "In3.Cu")
	)
	(gr_line
		(start 173.074584 -9.287256)
		(end 173.074584 -7.306056)
		(stroke
			(width 0.762)
			(type default)
		)
		(layer "In3.Cu")
	)
	(gr_line
		(start 173.074584 -5.417312)
		(end 173.074584 -5.366512)
		(stroke
			(width 0.1016)
			(type default)
		)
		(layer "In3.Cu")
	)
	(gr_line
		(start 173.074584 -5.417312)
		(end 173.480984 -5.417312)
		(stroke
			(width 0.1016)
			(type default)
		)
		(layer "In3.Cu")
	)
	(gr_line
		(start 173.074584 -5.366512)
		(end 172.312584 -5.366512)
		(stroke
			(width 0.1016)
			(type default)
		)
		(layer "In3.Cu")
	)
	(gr_line
		(start 173.074584 -5.087112)
		(end 173.074584 -3.105912)
		(stroke
			(width 0.762)
			(type default)
		)
		(layer "In3.Cu")
	)
	(gr_line
		(start 173.099984 -13.5382)
		(end 172.693584 -13.5382)
		(stroke
			(width 0.254)
			(type default)
		)
		(layer "In3.Cu")
	)
	(gr_line
		(start 173.099984 -11.43)
		(end 173.099984 -13.5382)
		(stroke
			(width 0.254)
			(type default)
		)
		(layer "In3.Cu")
	)
	(gr_line
		(start 173.099984 -9.338056)
		(end 172.693584 -9.338056)
		(stroke
			(width 0.254)
			(type default)
		)
		(layer "In3.Cu")
	)
	(gr_line
		(start 173.099984 -7.229856)
		(end 173.099984 -9.338056)
		(stroke
			(width 0.254)
			(type default)
		)
		(layer "In3.Cu")
	)
	(gr_line
		(start 173.099984 -5.137912)
		(end 172.693584 -5.137912)
		(stroke
			(width 0.254)
			(type default)
		)
		(layer "In3.Cu")
	)
	(gr_line
		(start 173.099984 -3.029712)
		(end 173.099984 -5.137912)
		(stroke
			(width 0.254)
			(type default)
		)
		(layer "In3.Cu")
	)
	(gr_line
		(start 173.150784 -13.4874)
		(end 173.150784 -11.5062)
		(stroke
			(width 0.762)
			(type default)
		)
		(layer "In3.Cu")
	)
	(gr_line
		(start 173.150784 -9.287256)
		(end 173.150784 -7.306056)
		(stroke
			(width 0.762)
			(type default)
		)
		(layer "In3.Cu")
	)
	(gr_line
		(start 173.150784 -5.087112)
		(end 173.150784 -3.105912)
		(stroke
			(width 0.762)
			(type default)
		)
		(layer "In3.Cu")
	)
	(gr_line
		(start 173.176184 -13.6144)
		(end 172.617384 -13.6144)
		(stroke
			(width 0.254)
			(type default)
		)
		(layer "In3.Cu")
	)
	(gr_line
		(start 173.176184 -11.3792)
		(end 173.176184 -13.6144)
		(stroke
			(width 0.254)
			(type default)
		)
		(layer "In3.Cu")
	)
	(gr_line
		(start 173.176184 -9.414256)
		(end 172.617384 -9.414256)
		(stroke
			(width 0.254)
			(type default)
		)
		(layer "In3.Cu")
	)
	(gr_line
		(start 173.176184 -7.179056)
		(end 173.176184 -9.414256)
		(stroke
			(width 0.254)
			(type default)
		)
		(layer "In3.Cu")
	)
	(gr_line
		(start 173.176184 -5.214112)
		(end 172.617384 -5.214112)
		(stroke
			(width 0.254)
			(type default)
		)
		(layer "In3.Cu")
	)
	(gr_line
		(start 173.176184 -2.978912)
		(end 173.176184 -5.214112)
		(stroke
			(width 0.254)
			(type default)
		)
		(layer "In3.Cu")
	)
	(gr_line
		(start 173.252384 -13.6398)
		(end 172.541184 -13.6398)
		(stroke
			(width 0.254)
			(type default)
		)
		(layer "In3.Cu")
	)
	(gr_line
		(start 173.252384 -11.303)
		(end 173.252384 -13.6398)
		(stroke
			(width 0.254)
			(type default)
		)
		(layer "In3.Cu")
	)
	(gr_line
		(start 173.252384 -9.439656)
		(end 172.541184 -9.439656)
		(stroke
			(width 0.254)
			(type default)
		)
		(layer "In3.Cu")
	)
	(gr_line
		(start 173.252384 -7.102856)
		(end 173.252384 -9.439656)
		(stroke
			(width 0.254)
			(type default)
		)
		(layer "In3.Cu")
	)
	(gr_line
		(start 173.252384 -5.239512)
		(end 172.541184 -5.239512)
		(stroke
			(width 0.254)
			(type default)
		)
		(layer "In3.Cu")
	)
	(gr_line
		(start 173.252384 -2.902712)
		(end 173.252384 -5.239512)
		(stroke
			(width 0.254)
			(type default)
		)
		(layer "In3.Cu")
	)
	(gr_line
		(start 173.277784 -13.7668)
		(end 172.287184 -13.7668)
		(stroke
			(width 0.1016)
			(type default)
		)
		(layer "In3.Cu")
	)
	(gr_line
		(start 173.277784 -13.6906)
		(end 172.464984 -13.6906)
		(stroke
			(width 0.254)
			(type default)
		)
		(layer "In3.Cu")
	)
	(gr_line
		(start 173.277784 -11.2776)
		(end 173.277784 -13.6906)
		(stroke
			(width 0.254)
			(type default)
		)
		(layer "In3.Cu")
	)
	(gr_line
		(start 173.277784 -9.566656)
		(end 172.287184 -9.566656)
		(stroke
			(width 0.1016)
			(type default)
		)
		(layer "In3.Cu")
	)
	(gr_line
		(start 173.277784 -9.490456)
		(end 172.464984 -9.490456)
		(stroke
			(width 0.254)
			(type default)
		)
		(layer "In3.Cu")
	)
	(gr_line
		(start 173.277784 -7.077456)
		(end 173.277784 -9.490456)
		(stroke
			(width 0.254)
			(type default)
		)
		(layer "In3.Cu")
	)
	(gr_line
		(start 173.277784 -5.366512)
		(end 172.287184 -5.366512)
		(stroke
			(width 0.1016)
			(type default)
		)
		(layer "In3.Cu")
	)
	(gr_line
		(start 173.277784 -5.290312)
		(end 172.464984 -5.290312)
		(stroke
			(width 0.254)
			(type default)
		)
		(layer "In3.Cu")
	)
	(gr_line
		(start 173.277784 -2.877312)
		(end 173.277784 -5.290312)
		(stroke
			(width 0.254)
			(type default)
		)
		(layer "In3.Cu")
	)
	(gr_line
		(start 173.303184 -13.716)
		(end 172.439584 -13.716)
		(stroke
			(width 0.254)
			(type default)
		)
		(layer "In3.Cu")
	)
	(gr_line
		(start 173.303184 -11.2522)
		(end 173.303184 -13.716)
		(stroke
			(width 0.254)
			(type default)
		)
		(layer "In3.Cu")
	)
	(gr_line
		(start 173.303184 -9.515856)
		(end 172.439584 -9.515856)
		(stroke
			(width 0.254)
			(type default)
		)
		(layer "In3.Cu")
	)
	(gr_line
		(start 173.303184 -7.052056)
		(end 173.303184 -9.515856)
		(stroke
			(width 0.254)
			(type default)
		)
		(layer "In3.Cu")
	)
	(gr_line
		(start 173.303184 -5.315712)
		(end 172.439584 -5.315712)
		(stroke
			(width 0.254)
			(type default)
		)
		(layer "In3.Cu")
	)
	(gr_line
		(start 173.303184 -2.851912)
		(end 173.303184 -5.315712)
		(stroke
			(width 0.254)
			(type default)
		)
		(layer "In3.Cu")
	)
	(gr_line
		(start 173.353984 -13.7414)
		(end 172.414184 -13.7414)
		(stroke
			(width 0.254)
			(type default)
		)
		(layer "In3.Cu")
	)
	(gr_line
		(start 173.353984 -11.2522)
		(end 173.353984 -13.7414)
		(stroke
			(width 0.254)
			(type default)
		)
		(layer "In3.Cu")
	)
	(gr_line
		(start 173.353984 -9.541256)
		(end 172.414184 -9.541256)
		(stroke
			(width 0.254)
			(type default)
		)
		(layer "In3.Cu")
	)
	(gr_line
		(start 173.353984 -7.052056)
		(end 173.353984 -9.541256)
		(stroke
			(width 0.254)
			(type default)
		)
		(layer "In3.Cu")
	)
	(gr_line
		(start 173.353984 -5.341112)
		(end 172.414184 -5.341112)
		(stroke
			(width 0.254)
			(type default)
		)
		(layer "In3.Cu")
	)
	(gr_line
		(start 173.353984 -2.851912)
		(end 173.353984 -5.341112)
		(stroke
			(width 0.254)
			(type default)
		)
		(layer "In3.Cu")
	)
	(gr_line
		(start 173.379384 -13.7414)
		(end 172.414184 -13.7414)
		(stroke
			(width 0.2032)
			(type default)
		)
		(layer "In3.Cu")
	)
	(gr_line
		(start 173.379384 -11.2014)
		(end 173.379384 -13.7414)
		(stroke
			(width 0.2032)
			(type default)
		)
		(layer "In3.Cu")
	)
	(gr_line
		(start 173.379384 -9.541256)
		(end 172.414184 -9.541256)
		(stroke
			(width 0.2032)
			(type default)
		)
		(layer "In3.Cu")
	)
	(gr_line
		(start 173.379384 -7.001256)
		(end 173.379384 -9.541256)
		(stroke
			(width 0.2032)
			(type default)
		)
		(layer "In3.Cu")
	)
	(gr_line
		(start 173.379384 -5.341112)
		(end 172.414184 -5.341112)
		(stroke
			(width 0.2032)
			(type default)
		)
		(layer "In3.Cu")
	)
	(gr_line
		(start 173.379384 -2.801112)
		(end 173.379384 -5.341112)
		(stroke
			(width 0.2032)
			(type default)
		)
		(layer "In3.Cu")
	)
	(gr_line
		(start 173.430184 -13.7668)
		(end 172.363384 -13.7668)
		(stroke
			(width 0.2032)
			(type default)
		)
		(layer "In3.Cu")
	)
	(gr_line
		(start 173.430184 -11.2014)
		(end 173.430184 -13.7668)
		(stroke
			(width 0.2032)
			(type default)
		)
		(layer "In3.Cu")
	)
	(gr_line
		(start 173.430184 -9.566656)
		(end 172.363384 -9.566656)
		(stroke
			(width 0.2032)
			(type default)
		)
		(layer "In3.Cu")
	)
	(gr_line
		(start 173.430184 -7.001256)
		(end 173.430184 -9.566656)
		(stroke
			(width 0.2032)
			(type default)
		)
		(layer "In3.Cu")
	)
	(gr_line
		(start 173.430184 -5.366512)
		(end 172.363384 -5.366512)
		(stroke
			(width 0.2032)
			(type default)
		)
		(layer "In3.Cu")
	)
	(gr_line
		(start 173.430184 -2.801112)
		(end 173.430184 -5.366512)
		(stroke
			(width 0.2032)
			(type default)
		)
		(layer "In3.Cu")
	)
	(gr_line
		(start 173.455584 -13.7668)
		(end 172.337984 -13.7668)
		(stroke
			(width 0.1016)
			(type default)
		)
		(layer "In3.Cu")
	)
	(gr_line
		(start 173.455584 -11.176)
		(end 173.455584 -13.7668)
		(stroke
			(width 0.1016)
			(type default)
		)
		(layer "In3.Cu")
	)
	(gr_line
		(start 173.455584 -9.566656)
		(end 172.337984 -9.566656)
		(stroke
			(width 0.1016)
			(type default)
		)
		(layer "In3.Cu")
	)
	(gr_line
		(start 173.455584 -6.975856)
		(end 173.455584 -9.566656)
		(stroke
			(width 0.1016)
			(type default)
		)
		(layer "In3.Cu")
	)
	(gr_line
		(start 173.455584 -5.366512)
		(end 172.337984 -5.366512)
		(stroke
			(width 0.1016)
			(type default)
		)
		(layer "In3.Cu")
	)
	(gr_line
		(start 173.455584 -2.775712)
		(end 173.455584 -5.366512)
		(stroke
			(width 0.1016)
			(type default)
		)
		(layer "In3.Cu")
	)
	(gr_line
		(start 173.480984 -13.8176)
		(end 173.074584 -13.8176)
		(stroke
			(width 0.1016)
			(type default)
		)
		(layer "In3.Cu")
	)
	(gr_line
		(start 173.480984 -13.8176)
		(end 173.480984 -11.1506)
		(stroke
			(width 0.1016)
			(type default)
		)
		(layer "In3.Cu")
	)
	(gr_line
		(start 173.480984 -11.1506)
		(end 172.287184 -11.1506)
		(stroke
			(width 0.1016)
			(type default)
		)
		(layer "In3.Cu")
	)
	(gr_line
		(start 173.480984 -11.1506)
		(end 173.480984 -13.8176)
		(stroke
			(width 0.1016)
			(type default)
		)
		(layer "In3.Cu")
	)
	(gr_line
		(start 173.480984 -9.617456)
		(end 173.074584 -9.617456)
		(stroke
			(width 0.1016)
			(type default)
		)
		(layer "In3.Cu")
	)
	(gr_line
		(start 173.480984 -9.617456)
		(end 173.480984 -6.950456)
		(stroke
			(width 0.1016)
			(type default)
		)
		(layer "In3.Cu")
	)
	(gr_line
		(start 173.480984 -6.950456)
		(end 172.287184 -6.950456)
		(stroke
			(width 0.1016)
			(type default)
		)
		(layer "In3.Cu")
	)
	(gr_line
		(start 173.480984 -6.950456)
		(end 173.480984 -9.617456)
		(stroke
			(width 0.1016)
			(type default)
		)
		(layer "In3.Cu")
	)
	(gr_line
		(start 173.480984 -5.417312)
		(end 173.074584 -5.417312)
		(stroke
			(width 0.1016)
			(type default)
		)
		(layer "In3.Cu")
	)
	(gr_line
		(start 173.480984 -5.417312)
		(end 173.480984 -2.750312)
		(stroke
			(width 0.1016)
			(type default)
		)
		(layer "In3.Cu")
	)
	(gr_line
		(start 173.480984 -2.750312)
		(end 172.287184 -2.750312)
		(stroke
			(width 0.1016)
			(type default)
		)
		(layer "In3.Cu")
	)
	(gr_line
		(start 173.480984 -2.750312)
		(end 173.480984 -5.417312)
		(stroke
			(width 0.1016)
			(type default)
		)
		(layer "In3.Cu")
	)
	(gr_line
		(start 174.145448 -32.9184)
		(end 172.875448 -32.9184)
		(stroke
			(width 0.7874)
			(type default)
		)
		(layer "In3.Cu")
	)
	(gr_line
		(start 174.28718 -12.563348)
		(end 175.07458 -12.563348)
		(stroke
			(width 0.1016)
			(type default)
		)
		(layer "In3.Cu")
	)
	(gr_line
		(start 174.28718 -12.512548)
		(end 174.28718 -9.896348)
		(stroke
			(width 0.1016)
			(type default)
		)
		(layer "In3.Cu")
	)
	(gr_line
		(start 174.28718 -12.463272)
		(end 175.07458 -12.463272)
		(stroke
			(width 0.1016)
			(type default)
		)
		(layer "In3.Cu")
	)
	(gr_line
		(start 174.28718 -12.412472)
		(end 174.28718 -9.796272)
		(stroke
			(width 0.1016)
			(type default)
		)
		(layer "In3.Cu")
	)
	(gr_line
		(start 174.28718 -9.896348)
		(end 174.28718 -12.563348)
		(stroke
			(width 0.1016)
			(type default)
		)
		(layer "In3.Cu")
	)
	(gr_line
		(start 174.28718 -9.896348)
		(end 175.48098 -9.896348)
		(stroke
			(width 0.1016)
			(type default)
		)
		(layer "In3.Cu")
	)
	(gr_line
		(start 174.28718 -9.796272)
		(end 174.28718 -12.463272)
		(stroke
			(width 0.1016)
			(type default)
		)
		(layer "In3.Cu")
	)
	(gr_line
		(start 174.28718 -9.796272)
		(end 175.48098 -9.796272)
		(stroke
			(width 0.1016)
			(type default)
		)
		(layer "In3.Cu")
	)
	(gr_line
		(start 174.28718 -8.363204)
		(end 175.07458 -8.363204)
		(stroke
			(width 0.1016)
			(type default)
		)
		(layer "In3.Cu")
	)
	(gr_line
		(start 174.28718 -8.312404)
		(end 174.28718 -5.696204)
		(stroke
			(width 0.1016)
			(type default)
		)
		(layer "In3.Cu")
	)
	(gr_line
		(start 174.28718 -8.263128)
		(end 175.07458 -8.263128)
		(stroke
			(width 0.1016)
			(type default)
		)
		(layer "In3.Cu")
	)
	(gr_line
		(start 174.28718 -8.212328)
		(end 174.28718 -5.596128)
		(stroke
			(width 0.1016)
			(type default)
		)
		(layer "In3.Cu")
	)
	(gr_line
		(start 174.28718 -5.696204)
		(end 174.28718 -8.363204)
		(stroke
			(width 0.1016)
			(type default)
		)
		(layer "In3.Cu")
	)
	(gr_line
		(start 174.28718 -5.696204)
		(end 175.48098 -5.696204)
		(stroke
			(width 0.1016)
			(type default)
		)
		(layer "In3.Cu")
	)
	(gr_line
		(start 174.28718 -5.596128)
		(end 174.28718 -8.263128)
		(stroke
			(width 0.1016)
			(type default)
		)
		(layer "In3.Cu")
	)
	(gr_line
		(start 174.28718 -5.596128)
		(end 175.48098 -5.596128)
		(stroke
			(width 0.1016)
			(type default)
		)
		(layer "In3.Cu")
	)
	(gr_line
		(start 174.28718 -4.16306)
		(end 175.07458 -4.16306)
		(stroke
			(width 0.1016)
			(type default)
		)
		(layer "In3.Cu")
	)
	(gr_line
		(start 174.28718 -4.11226)
		(end 174.28718 -1.49606)
		(stroke
			(width 0.1016)
			(type default)
		)
		(layer "In3.Cu")
	)
	(gr_line
		(start 174.28718 -4.062984)
		(end 175.07458 -4.062984)
		(stroke
			(width 0.1016)
			(type default)
		)
		(layer "In3.Cu")
	)
	(gr_line
		(start 174.28718 -4.012184)
		(end 174.28718 -1.395984)
		(stroke
			(width 0.1016)
			(type default)
		)
		(layer "In3.Cu")
	)
	(gr_line
		(start 174.28718 -1.49606)
		(end 174.28718 -4.16306)
		(stroke
			(width 0.1016)
			(type default)
		)
		(layer "In3.Cu")
	)
	(gr_line
		(start 174.28718 -1.49606)
		(end 175.48098 -1.49606)
		(stroke
			(width 0.1016)
			(type default)
		)
		(layer "In3.Cu")
	)
	(gr_line
		(start 174.28718 -1.395984)
		(end 174.28718 -4.062984)
		(stroke
			(width 0.1016)
			(type default)
		)
		(layer "In3.Cu")
	)
	(gr_line
		(start 174.28718 -1.395984)
		(end 175.48098 -1.395984)
		(stroke
			(width 0.1016)
			(type default)
		)
		(layer "In3.Cu")
	)
	(gr_line
		(start 174.31258 -12.512548)
		(end 174.31258 -9.921748)
		(stroke
			(width 0.1016)
			(type default)
		)
		(layer "In3.Cu")
	)
	(gr_line
		(start 174.31258 -12.412472)
		(end 174.31258 -9.821672)
		(stroke
			(width 0.1016)
			(type default)
		)
		(layer "In3.Cu")
	)
	(gr_line
		(start 174.31258 -9.921748)
		(end 175.45558 -9.921748)
		(stroke
			(width 0.1016)
			(type default)
		)
		(layer "In3.Cu")
	)
	(gr_line
		(start 174.31258 -9.821672)
		(end 175.45558 -9.821672)
		(stroke
			(width 0.1016)
			(type default)
		)
		(layer "In3.Cu")
	)
	(gr_line
		(start 174.31258 -8.312404)
		(end 174.31258 -5.721604)
		(stroke
			(width 0.1016)
			(type default)
		)
		(layer "In3.Cu")
	)
	(gr_line
		(start 174.31258 -8.212328)
		(end 174.31258 -5.621528)
		(stroke
			(width 0.1016)
			(type default)
		)
		(layer "In3.Cu")
	)
	(gr_line
		(start 174.31258 -5.721604)
		(end 175.45558 -5.721604)
		(stroke
			(width 0.1016)
			(type default)
		)
		(layer "In3.Cu")
	)
	(gr_line
		(start 174.31258 -5.621528)
		(end 175.45558 -5.621528)
		(stroke
			(width 0.1016)
			(type default)
		)
		(layer "In3.Cu")
	)
	(gr_line
		(start 174.31258 -4.11226)
		(end 174.31258 -1.52146)
		(stroke
			(width 0.1016)
			(type default)
		)
		(layer "In3.Cu")
	)
	(gr_line
		(start 174.31258 -4.012184)
		(end 174.31258 -1.421384)
		(stroke
			(width 0.1016)
			(type default)
		)
		(layer "In3.Cu")
	)
	(gr_line
		(start 174.31258 -1.52146)
		(end 175.45558 -1.52146)
		(stroke
			(width 0.1016)
			(type default)
		)
		(layer "In3.Cu")
	)
	(gr_line
		(start 174.31258 -1.421384)
		(end 175.45558 -1.421384)
		(stroke
			(width 0.1016)
			(type default)
		)
		(layer "In3.Cu")
	)
	(gr_line
		(start 174.33798 -12.512548)
		(end 174.33798 -9.947148)
		(stroke
			(width 0.1016)
			(type default)
		)
		(layer "In3.Cu")
	)
	(gr_line
		(start 174.33798 -12.412472)
		(end 174.33798 -9.847072)
		(stroke
			(width 0.1016)
			(type default)
		)
		(layer "In3.Cu")
	)
	(gr_line
		(start 174.33798 -9.947148)
		(end 174.59198 -9.947148)
		(stroke
			(width 0.1016)
			(type default)
		)
		(layer "In3.Cu")
	)
	(gr_line
		(start 174.33798 -9.847072)
		(end 174.59198 -9.847072)
		(stroke
			(width 0.1016)
			(type default)
		)
		(layer "In3.Cu")
	)
	(gr_line
		(start 174.33798 -8.312404)
		(end 174.33798 -5.747004)
		(stroke
			(width 0.1016)
			(type default)
		)
		(layer "In3.Cu")
	)
	(gr_line
		(start 174.33798 -8.212328)
		(end 174.33798 -5.646928)
		(stroke
			(width 0.1016)
			(type default)
		)
		(layer "In3.Cu")
	)
	(gr_line
		(start 174.33798 -5.747004)
		(end 174.59198 -5.747004)
		(stroke
			(width 0.1016)
			(type default)
		)
		(layer "In3.Cu")
	)
	(gr_line
		(start 174.33798 -5.646928)
		(end 174.59198 -5.646928)
		(stroke
			(width 0.1016)
			(type default)
		)
		(layer "In3.Cu")
	)
	(gr_line
		(start 174.33798 -4.11226)
		(end 174.33798 -1.54686)
		(stroke
			(width 0.1016)
			(type default)
		)
		(layer "In3.Cu")
	)
	(gr_line
		(start 174.33798 -4.012184)
		(end 174.33798 -1.446784)
		(stroke
			(width 0.1016)
			(type default)
		)
		(layer "In3.Cu")
	)
	(gr_line
		(start 174.33798 -1.54686)
		(end 174.59198 -1.54686)
		(stroke
			(width 0.1016)
			(type default)
		)
		(layer "In3.Cu")
	)
	(gr_line
		(start 174.33798 -1.446784)
		(end 174.59198 -1.446784)
		(stroke
			(width 0.1016)
			(type default)
		)
		(layer "In3.Cu")
	)
	(gr_line
		(start 174.36338 -12.512548)
		(end 174.36338 -9.947148)
		(stroke
			(width 0.2032)
			(type default)
		)
		(layer "In3.Cu")
	)
	(gr_line
		(start 174.36338 -12.412472)
		(end 174.36338 -9.847072)
		(stroke
			(width 0.2032)
			(type default)
		)
		(layer "In3.Cu")
	)
	(gr_line
		(start 174.36338 -9.947148)
		(end 175.37938 -9.947148)
		(stroke
			(width 0.2032)
			(type default)
		)
		(layer "In3.Cu")
	)
	(gr_line
		(start 174.36338 -9.847072)
		(end 175.37938 -9.847072)
		(stroke
			(width 0.2032)
			(type default)
		)
		(layer "In3.Cu")
	)
	(gr_line
		(start 174.36338 -8.312404)
		(end 174.36338 -5.747004)
		(stroke
			(width 0.2032)
			(type default)
		)
		(layer "In3.Cu")
	)
	(gr_line
		(start 174.36338 -8.212328)
		(end 174.36338 -5.646928)
		(stroke
			(width 0.2032)
			(type default)
		)
		(layer "In3.Cu")
	)
	(gr_line
		(start 174.36338 -5.747004)
		(end 175.37938 -5.747004)
		(stroke
			(width 0.2032)
			(type default)
		)
		(layer "In3.Cu")
	)
	(gr_line
		(start 174.36338 -5.646928)
		(end 175.37938 -5.646928)
		(stroke
			(width 0.2032)
			(type default)
		)
		(layer "In3.Cu")
	)
	(gr_line
		(start 174.36338 -4.11226)
		(end 174.36338 -1.54686)
		(stroke
			(width 0.2032)
			(type default)
		)
		(layer "In3.Cu")
	)
	(gr_line
		(start 174.36338 -4.012184)
		(end 174.36338 -1.446784)
		(stroke
			(width 0.2032)
			(type default)
		)
		(layer "In3.Cu")
	)
	(gr_line
		(start 174.36338 -1.54686)
		(end 175.37938 -1.54686)
		(stroke
			(width 0.2032)
			(type default)
		)
		(layer "In3.Cu")
	)
	(gr_line
		(start 174.36338 -1.446784)
		(end 175.37938 -1.446784)
		(stroke
			(width 0.2032)
			(type default)
		)
		(layer "In3.Cu")
	)
	(gr_line
		(start 174.41418 -12.487148)
		(end 174.41418 -9.997948)
		(stroke
			(width 0.2032)
			(type default)
		)
		(layer "In3.Cu")
	)
	(gr_line
		(start 174.41418 -12.487148)
		(end 174.41418 -9.997948)
		(stroke
			(width 0.254)
			(type default)
		)
		(layer "In3.Cu")
	)
	(gr_line
		(start 174.41418 -12.387072)
		(end 174.41418 -9.897872)
		(stroke
			(width 0.2032)
			(type default)
		)
		(layer "In3.Cu")
	)
	(gr_line
		(start 174.41418 -12.387072)
		(end 174.41418 -9.897872)
		(stroke
			(width 0.254)
			(type default)
		)
		(layer "In3.Cu")
	)
	(gr_line
		(start 174.41418 -9.997948)
		(end 174.61738 -9.997948)
		(stroke
			(width 0.2032)
			(type default)
		)
		(layer "In3.Cu")
	)
	(gr_line
		(start 174.41418 -9.997948)
		(end 175.30318 -9.997948)
		(stroke
			(width 0.254)
			(type default)
		)
		(layer "In3.Cu")
	)
	(gr_line
		(start 174.41418 -9.897872)
		(end 174.61738 -9.897872)
		(stroke
			(width 0.2032)
			(type default)
		)
		(layer "In3.Cu")
	)
	(gr_line
		(start 174.41418 -9.897872)
		(end 175.30318 -9.897872)
		(stroke
			(width 0.254)
			(type default)
		)
		(layer "In3.Cu")
	)
	(gr_line
		(start 174.41418 -8.287004)
		(end 174.41418 -5.797804)
		(stroke
			(width 0.2032)
			(type default)
		)
		(layer "In3.Cu")
	)
	(gr_line
		(start 174.41418 -8.287004)
		(end 174.41418 -5.797804)
		(stroke
			(width 0.254)
			(type default)
		)
		(layer "In3.Cu")
	)
	(gr_line
		(start 174.41418 -8.186928)
		(end 174.41418 -5.697728)
		(stroke
			(width 0.2032)
			(type default)
		)
		(layer "In3.Cu")
	)
	(gr_line
		(start 174.41418 -8.186928)
		(end 174.41418 -5.697728)
		(stroke
			(width 0.254)
			(type default)
		)
		(layer "In3.Cu")
	)
	(gr_line
		(start 174.41418 -5.797804)
		(end 174.61738 -5.797804)
		(stroke
			(width 0.2032)
			(type default)
		)
		(layer "In3.Cu")
	)
	(gr_line
		(start 174.41418 -5.797804)
		(end 175.30318 -5.797804)
		(stroke
			(width 0.254)
			(type default)
		)
		(layer "In3.Cu")
	)
	(gr_line
		(start 174.41418 -5.697728)
		(end 174.61738 -5.697728)
		(stroke
			(width 0.2032)
			(type default)
		)
		(layer "In3.Cu")
	)
	(gr_line
		(start 174.41418 -5.697728)
		(end 175.30318 -5.697728)
		(stroke
			(width 0.254)
			(type default)
		)
		(layer "In3.Cu")
	)
	(gr_line
		(start 174.41418 -4.08686)
		(end 174.41418 -1.59766)
		(stroke
			(width 0.2032)
			(type default)
		)
		(layer "In3.Cu")
	)
	(gr_line
		(start 174.41418 -4.08686)
		(end 174.41418 -1.59766)
		(stroke
			(width 0.254)
			(type default)
		)
		(layer "In3.Cu")
	)
	(gr_line
		(start 174.41418 -3.986784)
		(end 174.41418 -1.497584)
		(stroke
			(width 0.2032)
			(type default)
		)
		(layer "In3.Cu")
	)
	(gr_line
		(start 174.41418 -3.986784)
		(end 174.41418 -1.497584)
		(stroke
			(width 0.254)
			(type default)
		)
		(layer "In3.Cu")
	)
	(gr_line
		(start 174.41418 -1.59766)
		(end 174.61738 -1.59766)
		(stroke
			(width 0.2032)
			(type default)
		)
		(layer "In3.Cu")
	)
	(gr_line
		(start 174.41418 -1.59766)
		(end 175.30318 -1.59766)
		(stroke
			(width 0.254)
			(type default)
		)
		(layer "In3.Cu")
	)
	(gr_line
		(start 174.41418 -1.497584)
		(end 174.61738 -1.497584)
		(stroke
			(width 0.2032)
			(type default)
		)
		(layer "In3.Cu")
	)
	(gr_line
		(start 174.41418 -1.497584)
		(end 175.30318 -1.497584)
		(stroke
			(width 0.254)
			(type default)
		)
		(layer "In3.Cu")
	)
	(gr_line
		(start 174.43958 -12.461748)
		(end 174.43958 -10.023348)
		(stroke
			(width 0.254)
			(type default)
		)
		(layer "In3.Cu")
	)
	(gr_line
		(start 174.43958 -12.361672)
		(end 174.43958 -9.923272)
		(stroke
			(width 0.254)
			(type default)
		)
		(layer "In3.Cu")
	)
	(gr_line
		(start 174.43958 -10.023348)
		(end 175.27778 -10.023348)
		(stroke
			(width 0.254)
			(type default)
		)
		(layer "In3.Cu")
	)
	(gr_line
		(start 174.43958 -9.923272)
		(end 175.27778 -9.923272)
		(stroke
			(width 0.254)
			(type default)
		)
		(layer "In3.Cu")
	)
	(gr_line
		(start 174.43958 -8.261604)
		(end 174.43958 -5.823204)
		(stroke
			(width 0.254)
			(type default)
		)
		(layer "In3.Cu")
	)
	(gr_line
		(start 174.43958 -8.161528)
		(end 174.43958 -5.723128)
		(stroke
			(width 0.254)
			(type default)
		)
		(layer "In3.Cu")
	)
	(gr_line
		(start 174.43958 -5.823204)
		(end 175.27778 -5.823204)
		(stroke
			(width 0.254)
			(type default)
		)
		(layer "In3.Cu")
	)
	(gr_line
		(start 174.43958 -5.723128)
		(end 175.27778 -5.723128)
		(stroke
			(width 0.254)
			(type default)
		)
		(layer "In3.Cu")
	)
	(gr_line
		(start 174.43958 -4.06146)
		(end 174.43958 -1.62306)
		(stroke
			(width 0.254)
			(type default)
		)
		(layer "In3.Cu")
	)
	(gr_line
		(start 174.43958 -3.961384)
		(end 174.43958 -1.522984)
		(stroke
			(width 0.254)
			(type default)
		)
		(layer "In3.Cu")
	)
	(gr_line
		(start 174.43958 -1.62306)
		(end 175.27778 -1.62306)
		(stroke
			(width 0.254)
			(type default)
		)
		(layer "In3.Cu")
	)
	(gr_line
		(start 174.43958 -1.522984)
		(end 175.27778 -1.522984)
		(stroke
			(width 0.254)
			(type default)
		)
		(layer "In3.Cu")
	)
	(gr_line
		(start 174.46498 -12.436348)
		(end 174.46498 -10.048748)
		(stroke
			(width 0.254)
			(type default)
		)
		(layer "In3.Cu")
	)
	(gr_line
		(start 174.46498 -12.336272)
		(end 174.46498 -9.948672)
		(stroke
			(width 0.254)
			(type default)
		)
		(layer "In3.Cu")
	)
	(gr_line
		(start 174.46498 -10.048748)
		(end 175.25238 -10.048748)
		(stroke
			(width 0.254)
			(type default)
		)
		(layer "In3.Cu")
	)
	(gr_line
		(start 174.46498 -9.948672)
		(end 175.25238 -9.948672)
		(stroke
			(width 0.254)
			(type default)
		)
		(layer "In3.Cu")
	)
	(gr_line
		(start 174.46498 -8.236204)
		(end 174.46498 -5.848604)
		(stroke
			(width 0.254)
			(type default)
		)
		(layer "In3.Cu")
	)
	(gr_line
		(start 174.46498 -8.136128)
		(end 174.46498 -5.748528)
		(stroke
			(width 0.254)
			(type default)
		)
		(layer "In3.Cu")
	)
	(gr_line
		(start 174.46498 -5.848604)
		(end 175.25238 -5.848604)
		(stroke
			(width 0.254)
			(type default)
		)
		(layer "In3.Cu")
	)
	(gr_line
		(start 174.46498 -5.748528)
		(end 175.25238 -5.748528)
		(stroke
			(width 0.254)
			(type default)
		)
		(layer "In3.Cu")
	)
	(gr_line
		(start 174.46498 -4.03606)
		(end 174.46498 -1.64846)
		(stroke
			(width 0.254)
			(type default)
		)
		(layer "In3.Cu")
	)
	(gr_line
		(start 174.46498 -3.935984)
		(end 174.46498 -1.548384)
		(stroke
			(width 0.254)
			(type default)
		)
		(layer "In3.Cu")
	)
	(gr_line
		(start 174.46498 -1.64846)
		(end 175.25238 -1.64846)
		(stroke
			(width 0.254)
			(type default)
		)
		(layer "In3.Cu")
	)
	(gr_line
		(start 174.46498 -1.548384)
		(end 175.25238 -1.548384)
		(stroke
			(width 0.254)
			(type default)
		)
		(layer "In3.Cu")
	)
	(gr_line
		(start 174.49038 -12.360148)
		(end 175.12538 -12.360148)
		(stroke
			(width 0.508)
			(type default)
		)
		(layer "In3.Cu")
	)
	(gr_line
		(start 174.49038 -12.260072)
		(end 175.12538 -12.260072)
		(stroke
			(width 0.508)
			(type default)
		)
		(layer "In3.Cu")
	)
	(gr_line
		(start 174.49038 -10.175748)
		(end 175.12538 -10.175748)
		(stroke
			(width 0.508)
			(type default)
		)
		(layer "In3.Cu")
	)
	(gr_line
		(start 174.49038 -10.124948)
		(end 175.12538 -10.124948)
		(stroke
			(width 0.508)
			(type default)
		)
		(layer "In3.Cu")
	)
	(gr_line
		(start 174.49038 -10.075672)
		(end 175.12538 -10.075672)
		(stroke
			(width 0.508)
			(type default)
		)
		(layer "In3.Cu")
	)
	(gr_line
		(start 174.49038 -10.024872)
		(end 175.12538 -10.024872)
		(stroke
			(width 0.508)
			(type default)
		)
		(layer "In3.Cu")
	)
	(gr_line
		(start 174.49038 -8.160004)
		(end 175.12538 -8.160004)
		(stroke
			(width 0.508)
			(type default)
		)
		(layer "In3.Cu")
	)
	(gr_line
		(start 174.49038 -8.059928)
		(end 175.12538 -8.059928)
		(stroke
			(width 0.508)
			(type default)
		)
		(layer "In3.Cu")
	)
	(gr_line
		(start 174.49038 -5.975604)
		(end 175.12538 -5.975604)
		(stroke
			(width 0.508)
			(type default)
		)
		(layer "In3.Cu")
	)
	(gr_line
		(start 174.49038 -5.924804)
		(end 175.12538 -5.924804)
		(stroke
			(width 0.508)
			(type default)
		)
		(layer "In3.Cu")
	)
	(gr_line
		(start 174.49038 -5.875528)
		(end 175.12538 -5.875528)
		(stroke
			(width 0.508)
			(type default)
		)
		(layer "In3.Cu")
	)
	(gr_line
		(start 174.49038 -5.824728)
		(end 175.12538 -5.824728)
		(stroke
			(width 0.508)
			(type default)
		)
		(layer "In3.Cu")
	)
	(gr_line
		(start 174.49038 -3.95986)
		(end 175.12538 -3.95986)
		(stroke
			(width 0.508)
			(type default)
		)
		(layer "In3.Cu")
	)
	(gr_line
		(start 174.49038 -3.859784)
		(end 175.12538 -3.859784)
		(stroke
			(width 0.508)
			(type default)
		)
		(layer "In3.Cu")
	)
	(gr_line
		(start 174.49038 -1.77546)
		(end 175.12538 -1.77546)
		(stroke
			(width 0.508)
			(type default)
		)
		(layer "In3.Cu")
	)
	(gr_line
		(start 174.49038 -1.72466)
		(end 175.12538 -1.72466)
		(stroke
			(width 0.508)
			(type default)
		)
		(layer "In3.Cu")
	)
	(gr_line
		(start 174.49038 -1.675384)
		(end 175.12538 -1.675384)
		(stroke
			(width 0.508)
			(type default)
		)
		(layer "In3.Cu")
	)
	(gr_line
		(start 174.49038 -1.624584)
		(end 175.12538 -1.624584)
		(stroke
			(width 0.508)
			(type default)
		)
		(layer "In3.Cu")
	)
	(gr_line
		(start 174.51578 -10.429748)
		(end 175.15078 -10.429748)
		(stroke
			(width 0.508)
			(type default)
		)
		(layer "In3.Cu")
	)
	(gr_line
		(start 174.51578 -10.329672)
		(end 175.15078 -10.329672)
		(stroke
			(width 0.508)
			(type default)
		)
		(layer "In3.Cu")
	)
	(gr_line
		(start 174.51578 -6.229604)
		(end 175.15078 -6.229604)
		(stroke
			(width 0.508)
			(type default)
		)
		(layer "In3.Cu")
	)
	(gr_line
		(start 174.51578 -6.129528)
		(end 175.15078 -6.129528)
		(stroke
			(width 0.508)
			(type default)
		)
		(layer "In3.Cu")
	)
	(gr_line
		(start 174.51578 -2.02946)
		(end 175.15078 -2.02946)
		(stroke
			(width 0.508)
			(type default)
		)
		(layer "In3.Cu")
	)
	(gr_line
		(start 174.51578 -1.929384)
		(end 175.15078 -1.929384)
		(stroke
			(width 0.508)
			(type default)
		)
		(layer "In3.Cu")
	)
	(gr_line
		(start 174.54118 -12.385548)
		(end 174.54118 -10.124948)
		(stroke
			(width 0.254)
			(type default)
		)
		(layer "In3.Cu")
	)
	(gr_line
		(start 174.54118 -12.285472)
		(end 174.54118 -10.024872)
		(stroke
			(width 0.254)
			(type default)
		)
		(layer "In3.Cu")
	)
	(gr_line
		(start 174.54118 -12.233148)
		(end 175.17618 -12.233148)
		(stroke
			(width 0.508)
			(type default)
		)
		(layer "In3.Cu")
	)
	(gr_line
		(start 174.54118 -12.133072)
		(end 175.17618 -12.133072)
		(stroke
			(width 0.508)
			(type default)
		)
		(layer "In3.Cu")
	)
	(gr_line
		(start 174.54118 -10.124948)
		(end 175.17618 -10.124948)
		(stroke
			(width 0.254)
			(type default)
		)
		(layer "In3.Cu")
	)
	(gr_line
		(start 174.54118 -10.024872)
		(end 175.17618 -10.024872)
		(stroke
			(width 0.254)
			(type default)
		)
		(layer "In3.Cu")
	)
	(gr_line
		(start 174.54118 -8.185404)
		(end 174.54118 -5.924804)
		(stroke
			(width 0.254)
			(type default)
		)
		(layer "In3.Cu")
	)
	(gr_line
		(start 174.54118 -8.085328)
		(end 174.54118 -5.824728)
		(stroke
			(width 0.254)
			(type default)
		)
		(layer "In3.Cu")
	)
	(gr_line
		(start 174.54118 -8.033004)
		(end 175.17618 -8.033004)
		(stroke
			(width 0.508)
			(type default)
		)
		(layer "In3.Cu")
	)
	(gr_line
		(start 174.54118 -7.932928)
		(end 175.17618 -7.932928)
		(stroke
			(width 0.508)
			(type default)
		)
		(layer "In3.Cu")
	)
	(gr_line
		(start 174.54118 -5.924804)
		(end 175.17618 -5.924804)
		(stroke
			(width 0.254)
			(type default)
		)
		(layer "In3.Cu")
	)
	(gr_line
		(start 174.54118 -5.824728)
		(end 175.17618 -5.824728)
		(stroke
			(width 0.254)
			(type default)
		)
		(layer "In3.Cu")
	)
	(gr_line
		(start 174.54118 -3.98526)
		(end 174.54118 -1.72466)
		(stroke
			(width 0.254)
			(type default)
		)
		(layer "In3.Cu")
	)
	(gr_line
		(start 174.54118 -3.885184)
		(end 174.54118 -1.624584)
		(stroke
			(width 0.254)
			(type default)
		)
		(layer "In3.Cu")
	)
	(gr_line
		(start 174.54118 -3.83286)
		(end 175.17618 -3.83286)
		(stroke
			(width 0.508)
			(type default)
		)
		(layer "In3.Cu")
	)
	(gr_line
		(start 174.54118 -3.732784)
		(end 175.17618 -3.732784)
		(stroke
			(width 0.508)
			(type default)
		)
		(layer "In3.Cu")
	)
	(gr_line
		(start 174.54118 -1.72466)
		(end 175.17618 -1.72466)
		(stroke
			(width 0.254)
			(type default)
		)
		(layer "In3.Cu")
	)
	(gr_line
		(start 174.54118 -1.624584)
		(end 175.17618 -1.624584)
		(stroke
			(width 0.254)
			(type default)
		)
		(layer "In3.Cu")
	)
	(gr_line
		(start 174.56658 -12.080748)
		(end 175.20158 -12.080748)
		(stroke
			(width 0.508)
			(type default)
		)
		(layer "In3.Cu")
	)
	(gr_line
		(start 174.56658 -11.980672)
		(end 175.20158 -11.980672)
		(stroke
			(width 0.508)
			(type default)
		)
		(layer "In3.Cu")
	)
	(gr_line
		(start 174.56658 -7.880604)
		(end 175.20158 -7.880604)
		(stroke
			(width 0.508)
			(type default)
		)
		(layer "In3.Cu")
	)
	(gr_line
		(start 174.56658 -7.780528)
		(end 175.20158 -7.780528)
		(stroke
			(width 0.508)
			(type default)
		)
		(layer "In3.Cu")
	)
	(gr_line
		(start 174.56658 -3.68046)
		(end 175.20158 -3.68046)
		(stroke
			(width 0.508)
			(type default)
		)
		(layer "In3.Cu")
	)
	(gr_line
		(start 174.56658 -3.580384)
		(end 175.20158 -3.580384)
		(stroke
			(width 0.508)
			(type default)
		)
		(layer "In3.Cu")
	)
	(gr_line
		(start 174.59198 -12.360148)
		(end 175.22698 -12.360148)
		(stroke
			(width 0.508)
			(type default)
		)
		(layer "In3.Cu")
	)
	(gr_line
		(start 174.59198 -12.260072)
		(end 175.22698 -12.260072)
		(stroke
			(width 0.508)
			(type default)
		)
		(layer "In3.Cu")
	)
	(gr_line
		(start 174.59198 -9.947148)
		(end 175.43018 -9.947148)
		(stroke
			(width 0.2032)
			(type default)
		)
		(layer "In3.Cu")
	)
	(gr_line
		(start 174.59198 -9.847072)
		(end 175.43018 -9.847072)
		(stroke
			(width 0.2032)
			(type default)
		)
		(layer "In3.Cu")
	)
	(gr_line
		(start 174.59198 -8.160004)
		(end 175.22698 -8.160004)
		(stroke
			(width 0.508)
			(type default)
		)
		(layer "In3.Cu")
	)
	(gr_line
		(start 174.59198 -8.059928)
		(end 175.22698 -8.059928)
		(stroke
			(width 0.508)
			(type default)
		)
		(layer "In3.Cu")
	)
	(gr_line
		(start 174.59198 -5.747004)
		(end 175.43018 -5.747004)
		(stroke
			(width 0.2032)
			(type default)
		)
		(layer "In3.Cu")
	)
	(gr_line
		(start 174.59198 -5.646928)
		(end 175.43018 -5.646928)
		(stroke
			(width 0.2032)
			(type default)
		)
		(layer "In3.Cu")
	)
	(gr_line
		(start 174.59198 -3.95986)
		(end 175.22698 -3.95986)
		(stroke
			(width 0.508)
			(type default)
		)
		(layer "In3.Cu")
	)
	(gr_line
		(start 174.59198 -3.859784)
		(end 175.22698 -3.859784)
		(stroke
			(width 0.508)
			(type default)
		)
		(layer "In3.Cu")
	)
	(gr_line
		(start 174.59198 -1.54686)
		(end 175.43018 -1.54686)
		(stroke
			(width 0.2032)
			(type default)
		)
		(layer "In3.Cu")
	)
	(gr_line
		(start 174.59198 -1.446784)
		(end 175.43018 -1.446784)
		(stroke
			(width 0.2032)
			(type default)
		)
		(layer "In3.Cu")
	)
	(gr_line
		(start 174.61738 -12.360148)
		(end 174.61738 -10.175748)
		(stroke
			(width 0.254)
			(type default)
		)
		(layer "In3.Cu")
	)
	(gr_line
		(start 174.61738 -12.260072)
		(end 174.61738 -10.075672)
		(stroke
			(width 0.254)
			(type default)
		)
		(layer "In3.Cu")
	)
	(gr_line
		(start 174.61738 -10.175748)
		(end 175.09998 -10.175748)
		(stroke
			(width 0.254)
			(type default)
		)
		(layer "In3.Cu")
	)
	(gr_line
		(start 174.61738 -10.075672)
		(end 175.09998 -10.075672)
		(stroke
			(width 0.254)
			(type default)
		)
		(layer "In3.Cu")
	)
	(gr_line
		(start 174.61738 -9.997948)
		(end 175.35398 -9.997948)
		(stroke
			(width 0.254)
			(type default)
		)
		(layer "In3.Cu")
	)
	(gr_line
		(start 174.61738 -9.897872)
		(end 175.35398 -9.897872)
		(stroke
			(width 0.254)
			(type default)
		)
		(layer "In3.Cu")
	)
	(gr_line
		(start 174.61738 -8.160004)
		(end 174.61738 -5.975604)
		(stroke
			(width 0.254)
			(type default)
		)
		(layer "In3.Cu")
	)
	(gr_line
		(start 174.61738 -8.059928)
		(end 174.61738 -5.875528)
		(stroke
			(width 0.254)
			(type default)
		)
		(layer "In3.Cu")
	)
	(gr_line
		(start 174.61738 -5.975604)
		(end 175.09998 -5.975604)
		(stroke
			(width 0.254)
			(type default)
		)
		(layer "In3.Cu")
	)
	(gr_line
		(start 174.61738 -5.875528)
		(end 175.09998 -5.875528)
		(stroke
			(width 0.254)
			(type default)
		)
		(layer "In3.Cu")
	)
	(gr_line
		(start 174.61738 -5.797804)
		(end 175.35398 -5.797804)
		(stroke
			(width 0.254)
			(type default)
		)
		(layer "In3.Cu")
	)
	(gr_line
		(start 174.61738 -5.697728)
		(end 175.35398 -5.697728)
		(stroke
			(width 0.254)
			(type default)
		)
		(layer "In3.Cu")
	)
	(gr_line
		(start 174.61738 -3.95986)
		(end 174.61738 -1.77546)
		(stroke
			(width 0.254)
			(type default)
		)
		(layer "In3.Cu")
	)
	(gr_line
		(start 174.61738 -3.859784)
		(end 174.61738 -1.675384)
		(stroke
			(width 0.254)
			(type default)
		)
		(layer "In3.Cu")
	)
	(gr_line
		(start 174.61738 -1.77546)
		(end 175.09998 -1.77546)
		(stroke
			(width 0.254)
			(type default)
		)
		(layer "In3.Cu")
	)
	(gr_line
		(start 174.61738 -1.675384)
		(end 175.09998 -1.675384)
		(stroke
			(width 0.254)
			(type default)
		)
		(layer "In3.Cu")
	)
	(gr_line
		(start 174.61738 -1.59766)
		(end 175.35398 -1.59766)
		(stroke
			(width 0.254)
			(type default)
		)
		(layer "In3.Cu")
	)
	(gr_line
		(start 174.61738 -1.497584)
		(end 175.35398 -1.497584)
		(stroke
			(width 0.254)
			(type default)
		)
		(layer "In3.Cu")
	)
	(gr_line
		(start 174.635922 -10.110978)
		(end 175.270922 -10.110978)
		(stroke
			(width 0.508)
			(type default)
		)
		(layer "In3.Cu")
	)
	(gr_line
		(start 174.635922 -10.010902)
		(end 175.270922 -10.010902)
		(stroke
			(width 0.508)
			(type default)
		)
		(layer "In3.Cu")
	)
	(gr_line
		(start 174.635922 -5.910834)
		(end 175.270922 -5.910834)
		(stroke
			(width 0.508)
			(type default)
		)
		(layer "In3.Cu")
	)
	(gr_line
		(start 174.635922 -5.810758)
		(end 175.270922 -5.810758)
		(stroke
			(width 0.508)
			(type default)
		)
		(layer "In3.Cu")
	)
	(gr_line
		(start 174.635922 -1.71069)
		(end 175.270922 -1.71069)
		(stroke
			(width 0.508)
			(type default)
		)
		(layer "In3.Cu")
	)
	(gr_line
		(start 174.635922 -1.610614)
		(end 175.270922 -1.610614)
		(stroke
			(width 0.508)
			(type default)
		)
		(layer "In3.Cu")
	)
	(gr_line
		(start 174.64278 -12.360148)
		(end 175.27778 -12.360148)
		(stroke
			(width 0.508)
			(type default)
		)
		(layer "In3.Cu")
	)
	(gr_line
		(start 174.64278 -12.260072)
		(end 175.27778 -12.260072)
		(stroke
			(width 0.508)
			(type default)
		)
		(layer "In3.Cu")
	)
	(gr_line
		(start 174.64278 -12.233148)
		(end 174.64278 -10.251948)
		(stroke
			(width 0.762)
			(type default)
		)
		(layer "In3.Cu")
	)
	(gr_line
		(start 174.64278 -12.133072)
		(end 174.64278 -10.151872)
		(stroke
			(width 0.762)
			(type default)
		)
		(layer "In3.Cu")
	)
	(gr_line
		(start 174.64278 -10.251948)
		(end 175.27778 -10.251948)
		(stroke
			(width 0.508)
			(type default)
		)
		(layer "In3.Cu")
	)
	(gr_line
		(start 174.64278 -10.151872)
		(end 175.27778 -10.151872)
		(stroke
			(width 0.508)
			(type default)
		)
		(layer "In3.Cu")
	)
	(gr_line
		(start 174.64278 -8.160004)
		(end 175.27778 -8.160004)
		(stroke
			(width 0.508)
			(type default)
		)
		(layer "In3.Cu")
	)
	(gr_line
		(start 174.64278 -8.059928)
		(end 175.27778 -8.059928)
		(stroke
			(width 0.508)
			(type default)
		)
		(layer "In3.Cu")
	)
	(gr_line
		(start 174.64278 -8.033004)
		(end 174.64278 -6.051804)
		(stroke
			(width 0.762)
			(type default)
		)
		(layer "In3.Cu")
	)
	(gr_line
		(start 174.64278 -7.932928)
		(end 174.64278 -5.951728)
		(stroke
			(width 0.762)
			(type default)
		)
		(layer "In3.Cu")
	)
	(gr_line
		(start 174.64278 -6.051804)
		(end 175.27778 -6.051804)
		(stroke
			(width 0.508)
			(type default)
		)
		(layer "In3.Cu")
	)
	(gr_line
		(start 174.64278 -5.951728)
		(end 175.27778 -5.951728)
		(stroke
			(width 0.508)
			(type default)
		)
		(layer "In3.Cu")
	)
	(gr_line
		(start 174.64278 -3.95986)
		(end 175.27778 -3.95986)
		(stroke
			(width 0.508)
			(type default)
		)
		(layer "In3.Cu")
	)
	(gr_line
		(start 174.64278 -3.859784)
		(end 175.27778 -3.859784)
		(stroke
			(width 0.508)
			(type default)
		)
		(layer "In3.Cu")
	)
	(gr_line
		(start 174.64278 -3.83286)
		(end 174.64278 -1.85166)
		(stroke
			(width 0.762)
			(type default)
		)
		(layer "In3.Cu")
	)
	(gr_line
		(start 174.64278 -3.732784)
		(end 174.64278 -1.751584)
		(stroke
			(width 0.762)
			(type default)
		)
		(layer "In3.Cu")
	)
	(gr_line
		(start 174.64278 -1.85166)
		(end 175.27778 -1.85166)
		(stroke
			(width 0.508)
			(type default)
		)
		(layer "In3.Cu")
	)
	(gr_line
		(start 174.64278 -1.751584)
		(end 175.27778 -1.751584)
		(stroke
			(width 0.508)
			(type default)
		)
		(layer "In3.Cu")
	)
	(gr_line
		(start 174.69358 -12.283948)
		(end 174.69358 -10.251948)
		(stroke
			(width 0.254)
			(type default)
		)
		(layer "In3.Cu")
	)
	(gr_line
		(start 174.69358 -12.183872)
		(end 174.69358 -10.151872)
		(stroke
			(width 0.254)
			(type default)
		)
		(layer "In3.Cu")
	)
	(gr_line
		(start 174.69358 -10.251948)
		(end 175.02378 -10.251948)
		(stroke
			(width 0.254)
			(type default)
		)
		(layer "In3.Cu")
	)
	(gr_line
		(start 174.69358 -10.151872)
		(end 175.02378 -10.151872)
		(stroke
			(width 0.254)
			(type default)
		)
		(layer "In3.Cu")
	)
	(gr_line
		(start 174.69358 -8.083804)
		(end 174.69358 -6.051804)
		(stroke
			(width 0.254)
			(type default)
		)
		(layer "In3.Cu")
	)
	(gr_line
		(start 174.69358 -7.983728)
		(end 174.69358 -5.951728)
		(stroke
			(width 0.254)
			(type default)
		)
		(layer "In3.Cu")
	)
	(gr_line
		(start 174.69358 -6.051804)
		(end 175.02378 -6.051804)
		(stroke
			(width 0.254)
			(type default)
		)
		(layer "In3.Cu")
	)
	(gr_line
		(start 174.69358 -5.951728)
		(end 175.02378 -5.951728)
		(stroke
			(width 0.254)
			(type default)
		)
		(layer "In3.Cu")
	)
	(gr_line
		(start 174.69358 -3.88366)
		(end 174.69358 -1.85166)
		(stroke
			(width 0.254)
			(type default)
		)
		(layer "In3.Cu")
	)
	(gr_line
		(start 174.69358 -3.783584)
		(end 174.69358 -1.751584)
		(stroke
			(width 0.254)
			(type default)
		)
		(layer "In3.Cu")
	)
	(gr_line
		(start 174.69358 -1.85166)
		(end 175.02378 -1.85166)
		(stroke
			(width 0.254)
			(type default)
		)
		(layer "In3.Cu")
	)
	(gr_line
		(start 174.69358 -1.751584)
		(end 175.02378 -1.751584)
		(stroke
			(width 0.254)
			(type default)
		)
		(layer "In3.Cu")
	)
	(gr_line
		(start 174.79518 -12.207748)
		(end 174.79518 -10.404348)
		(stroke
			(width 0.254)
			(type default)
		)
		(layer "In3.Cu")
	)
	(gr_line
		(start 174.79518 -12.207748)
		(end 174.79518 -10.226548)
		(stroke
			(width 0.762)
			(type default)
		)
		(layer "In3.Cu")
	)
	(gr_line
		(start 174.79518 -12.107672)
		(end 174.79518 -10.304272)
		(stroke
			(width 0.254)
			(type default)
		)
		(layer "In3.Cu")
	)
	(gr_line
		(start 174.79518 -12.107672)
		(end 174.79518 -10.126472)
		(stroke
			(width 0.762)
			(type default)
		)
		(layer "In3.Cu")
	)
	(gr_line
		(start 174.79518 -10.404348)
		(end 174.89678 -10.404348)
		(stroke
			(width 0.254)
			(type default)
		)
		(layer "In3.Cu")
	)
	(gr_line
		(start 174.79518 -10.304272)
		(end 174.89678 -10.304272)
		(stroke
			(width 0.254)
			(type default)
		)
		(layer "In3.Cu")
	)
	(gr_line
		(start 174.79518 -8.007604)
		(end 174.79518 -6.204204)
		(stroke
			(width 0.254)
			(type default)
		)
		(layer "In3.Cu")
	)
	(gr_line
		(start 174.79518 -8.007604)
		(end 174.79518 -6.026404)
		(stroke
			(width 0.762)
			(type default)
		)
		(layer "In3.Cu")
	)
	(gr_line
		(start 174.79518 -7.907528)
		(end 174.79518 -6.104128)
		(stroke
			(width 0.254)
			(type default)
		)
		(layer "In3.Cu")
	)
	(gr_line
		(start 174.79518 -7.907528)
		(end 174.79518 -5.926328)
		(stroke
			(width 0.762)
			(type default)
		)
		(layer "In3.Cu")
	)
	(gr_line
		(start 174.79518 -6.204204)
		(end 174.89678 -6.204204)
		(stroke
			(width 0.254)
			(type default)
		)
		(layer "In3.Cu")
	)
	(gr_line
		(start 174.79518 -6.104128)
		(end 174.89678 -6.104128)
		(stroke
			(width 0.254)
			(type default)
		)
		(layer "In3.Cu")
	)
	(gr_line
		(start 174.79518 -3.80746)
		(end 174.79518 -2.00406)
		(stroke
			(width 0.254)
			(type default)
		)
		(layer "In3.Cu")
	)
	(gr_line
		(start 174.79518 -3.80746)
		(end 174.79518 -1.82626)
		(stroke
			(width 0.762)
			(type default)
		)
		(layer "In3.Cu")
	)
	(gr_line
		(start 174.79518 -3.707384)
		(end 174.79518 -1.903984)
		(stroke
			(width 0.254)
			(type default)
		)
		(layer "In3.Cu")
	)
	(gr_line
		(start 174.79518 -3.707384)
		(end 174.79518 -1.726184)
		(stroke
			(width 0.762)
			(type default)
		)
		(layer "In3.Cu")
	)
	(gr_line
		(start 174.79518 -2.00406)
		(end 174.89678 -2.00406)
		(stroke
			(width 0.254)
			(type default)
		)
		(layer "In3.Cu")
	)
	(gr_line
		(start 174.79518 -1.903984)
		(end 174.89678 -1.903984)
		(stroke
			(width 0.254)
			(type default)
		)
		(layer "In3.Cu")
	)
	(gr_line
		(start 174.89678 -12.309348)
		(end 174.84598 -12.309348)
		(stroke
			(width 0.254)
			(type default)
		)
		(layer "In3.Cu")
	)
	(gr_line
		(start 174.89678 -12.209272)
		(end 174.84598 -12.209272)
		(stroke
			(width 0.254)
			(type default)
		)
		(layer "In3.Cu")
	)
	(gr_line
		(start 174.89678 -10.404348)
		(end 174.89678 -12.309348)
		(stroke
			(width 0.254)
			(type default)
		)
		(layer "In3.Cu")
	)
	(gr_line
		(start 174.89678 -10.304272)
		(end 174.89678 -12.209272)
		(stroke
			(width 0.254)
			(type default)
		)
		(layer "In3.Cu")
	)
	(gr_line
		(start 174.89678 -8.109204)
		(end 174.84598 -8.109204)
		(stroke
			(width 0.254)
			(type default)
		)
		(layer "In3.Cu")
	)
	(gr_line
		(start 174.89678 -8.009128)
		(end 174.84598 -8.009128)
		(stroke
			(width 0.254)
			(type default)
		)
		(layer "In3.Cu")
	)
	(gr_line
		(start 174.89678 -6.204204)
		(end 174.89678 -8.109204)
		(stroke
			(width 0.254)
			(type default)
		)
		(layer "In3.Cu")
	)
	(gr_line
		(start 174.89678 -6.104128)
		(end 174.89678 -8.009128)
		(stroke
			(width 0.254)
			(type default)
		)
		(layer "In3.Cu")
	)
	(gr_line
		(start 174.89678 -3.90906)
		(end 174.84598 -3.90906)
		(stroke
			(width 0.254)
			(type default)
		)
		(layer "In3.Cu")
	)
	(gr_line
		(start 174.89678 -3.808984)
		(end 174.84598 -3.808984)
		(stroke
			(width 0.254)
			(type default)
		)
		(layer "In3.Cu")
	)
	(gr_line
		(start 174.89678 -2.00406)
		(end 174.89678 -3.90906)
		(stroke
			(width 0.254)
			(type default)
		)
		(layer "In3.Cu")
	)
	(gr_line
		(start 174.89678 -1.903984)
		(end 174.89678 -3.808984)
		(stroke
			(width 0.254)
			(type default)
		)
		(layer "In3.Cu")
	)
	(gr_line
		(start 174.94758 -12.233148)
		(end 174.94758 -10.251948)
		(stroke
			(width 0.762)
			(type default)
		)
		(layer "In3.Cu")
	)
	(gr_line
		(start 174.94758 -12.133072)
		(end 174.94758 -10.151872)
		(stroke
			(width 0.762)
			(type default)
		)
		(layer "In3.Cu")
	)
	(gr_line
		(start 174.94758 -8.033004)
		(end 174.94758 -6.051804)
		(stroke
			(width 0.762)
			(type default)
		)
		(layer "In3.Cu")
	)
	(gr_line
		(start 174.94758 -7.932928)
		(end 174.94758 -5.951728)
		(stroke
			(width 0.762)
			(type default)
		)
		(layer "In3.Cu")
	)
	(gr_line
		(start 174.94758 -3.83286)
		(end 174.94758 -1.85166)
		(stroke
			(width 0.762)
			(type default)
		)
		(layer "In3.Cu")
	)
	(gr_line
		(start 174.94758 -3.732784)
		(end 174.94758 -1.751584)
		(stroke
			(width 0.762)
			(type default)
		)
		(layer "In3.Cu")
	)
	(gr_line
		(start 175.02378 -12.207748)
		(end 174.79518 -12.207748)
		(stroke
			(width 0.254)
			(type default)
		)
		(layer "In3.Cu")
	)
	(gr_line
		(start 175.02378 -12.107672)
		(end 174.79518 -12.107672)
		(stroke
			(width 0.254)
			(type default)
		)
		(layer "In3.Cu")
	)
	(gr_line
		(start 175.02378 -10.251948)
		(end 175.02378 -12.207748)
		(stroke
			(width 0.254)
			(type default)
		)
		(layer "In3.Cu")
	)
	(gr_line
		(start 175.02378 -10.151872)
		(end 175.02378 -12.107672)
		(stroke
			(width 0.254)
			(type default)
		)
		(layer "In3.Cu")
	)
	(gr_line
		(start 175.02378 -8.007604)
		(end 174.79518 -8.007604)
		(stroke
			(width 0.254)
			(type default)
		)
		(layer "In3.Cu")
	)
	(gr_line
		(start 175.02378 -7.907528)
		(end 174.79518 -7.907528)
		(stroke
			(width 0.254)
			(type default)
		)
		(layer "In3.Cu")
	)
	(gr_line
		(start 175.02378 -6.051804)
		(end 175.02378 -8.007604)
		(stroke
			(width 0.254)
			(type default)
		)
		(layer "In3.Cu")
	)
	(gr_line
		(start 175.02378 -5.951728)
		(end 175.02378 -7.907528)
		(stroke
			(width 0.254)
			(type default)
		)
		(layer "In3.Cu")
	)
	(gr_line
		(start 175.02378 -3.80746)
		(end 174.79518 -3.80746)
		(stroke
			(width 0.254)
			(type default)
		)
		(layer "In3.Cu")
	)
	(gr_line
		(start 175.02378 -3.707384)
		(end 174.79518 -3.707384)
		(stroke
			(width 0.254)
			(type default)
		)
		(layer "In3.Cu")
	)
	(gr_line
		(start 175.02378 -1.85166)
		(end 175.02378 -3.80746)
		(stroke
			(width 0.254)
			(type default)
		)
		(layer "In3.Cu")
	)
	(gr_line
		(start 175.02378 -1.751584)
		(end 175.02378 -3.707384)
		(stroke
			(width 0.254)
			(type default)
		)
		(layer "In3.Cu")
	)
	(gr_line
		(start 175.07458 -12.563348)
		(end 175.07458 -12.512548)
		(stroke
			(width 0.1016)
			(type default)
		)
		(layer "In3.Cu")
	)
	(gr_line
		(start 175.07458 -12.563348)
		(end 175.48098 -12.563348)
		(stroke
			(width 0.1016)
			(type default)
		)
		(layer "In3.Cu")
	)
	(gr_line
		(start 175.07458 -12.512548)
		(end 174.31258 -12.512548)
		(stroke
			(width 0.1016)
			(type default)
		)
		(layer "In3.Cu")
	)
	(gr_line
		(start 175.07458 -12.463272)
		(end 175.07458 -12.412472)
		(stroke
			(width 0.1016)
			(type default)
		)
		(layer "In3.Cu")
	)
	(gr_line
		(start 175.07458 -12.463272)
		(end 175.48098 -12.463272)
		(stroke
			(width 0.1016)
			(type default)
		)
		(layer "In3.Cu")
	)
	(gr_line
		(start 175.07458 -12.412472)
		(end 174.31258 -12.412472)
		(stroke
			(width 0.1016)
			(type default)
		)
		(layer "In3.Cu")
	)
	(gr_line
		(start 175.07458 -12.233148)
		(end 175.07458 -10.251948)
		(stroke
			(width 0.762)
			(type default)
		)
		(layer "In3.Cu")
	)
	(gr_line
		(start 175.07458 -12.133072)
		(end 175.07458 -10.151872)
		(stroke
			(width 0.762)
			(type default)
		)
		(layer "In3.Cu")
	)
	(gr_line
		(start 175.07458 -8.363204)
		(end 175.07458 -8.312404)
		(stroke
			(width 0.1016)
			(type default)
		)
		(layer "In3.Cu")
	)
	(gr_line
		(start 175.07458 -8.363204)
		(end 175.48098 -8.363204)
		(stroke
			(width 0.1016)
			(type default)
		)
		(layer "In3.Cu")
	)
	(gr_line
		(start 175.07458 -8.312404)
		(end 174.31258 -8.312404)
		(stroke
			(width 0.1016)
			(type default)
		)
		(layer "In3.Cu")
	)
	(gr_line
		(start 175.07458 -8.263128)
		(end 175.07458 -8.212328)
		(stroke
			(width 0.1016)
			(type default)
		)
		(layer "In3.Cu")
	)
	(gr_line
		(start 175.07458 -8.263128)
		(end 175.48098 -8.263128)
		(stroke
			(width 0.1016)
			(type default)
		)
		(layer "In3.Cu")
	)
	(gr_line
		(start 175.07458 -8.212328)
		(end 174.31258 -8.212328)
		(stroke
			(width 0.1016)
			(type default)
		)
		(layer "In3.Cu")
	)
	(gr_line
		(start 175.07458 -8.033004)
		(end 175.07458 -6.051804)
		(stroke
			(width 0.762)
			(type default)
		)
		(layer "In3.Cu")
	)
	(gr_line
		(start 175.07458 -7.932928)
		(end 175.07458 -5.951728)
		(stroke
			(width 0.762)
			(type default)
		)
		(layer "In3.Cu")
	)
	(gr_line
		(start 175.07458 -4.16306)
		(end 175.07458 -4.11226)
		(stroke
			(width 0.1016)
			(type default)
		)
		(layer "In3.Cu")
	)
	(gr_line
		(start 175.07458 -4.16306)
		(end 175.48098 -4.16306)
		(stroke
			(width 0.1016)
			(type default)
		)
		(layer "In3.Cu")
	)
	(gr_line
		(start 175.07458 -4.11226)
		(end 174.31258 -4.11226)
		(stroke
			(width 0.1016)
			(type default)
		)
		(layer "In3.Cu")
	)
	(gr_line
		(start 175.07458 -4.062984)
		(end 175.07458 -4.012184)
		(stroke
			(width 0.1016)
			(type default)
		)
		(layer "In3.Cu")
	)
	(gr_line
		(start 175.07458 -4.062984)
		(end 175.48098 -4.062984)
		(stroke
			(width 0.1016)
			(type default)
		)
		(layer "In3.Cu")
	)
	(gr_line
		(start 175.07458 -4.012184)
		(end 174.31258 -4.012184)
		(stroke
			(width 0.1016)
			(type default)
		)
		(layer "In3.Cu")
	)
	(gr_line
		(start 175.07458 -3.83286)
		(end 175.07458 -1.85166)
		(stroke
			(width 0.762)
			(type default)
		)
		(layer "In3.Cu")
	)
	(gr_line
		(start 175.07458 -3.732784)
		(end 175.07458 -1.751584)
		(stroke
			(width 0.762)
			(type default)
		)
		(layer "In3.Cu")
	)
	(gr_line
		(start 175.09998 -12.283948)
		(end 174.69358 -12.283948)
		(stroke
			(width 0.254)
			(type default)
		)
		(layer "In3.Cu")
	)
	(gr_line
		(start 175.09998 -12.183872)
		(end 174.69358 -12.183872)
		(stroke
			(width 0.254)
			(type default)
		)
		(layer "In3.Cu")
	)
	(gr_line
		(start 175.09998 -10.175748)
		(end 175.09998 -12.283948)
		(stroke
			(width 0.254)
			(type default)
		)
		(layer "In3.Cu")
	)
	(gr_line
		(start 175.09998 -10.075672)
		(end 175.09998 -12.183872)
		(stroke
			(width 0.254)
			(type default)
		)
		(layer "In3.Cu")
	)
	(gr_line
		(start 175.09998 -8.083804)
		(end 174.69358 -8.083804)
		(stroke
			(width 0.254)
			(type default)
		)
		(layer "In3.Cu")
	)
	(gr_line
		(start 175.09998 -7.983728)
		(end 174.69358 -7.983728)
		(stroke
			(width 0.254)
			(type default)
		)
		(layer "In3.Cu")
	)
	(gr_line
		(start 175.09998 -5.975604)
		(end 175.09998 -8.083804)
		(stroke
			(width 0.254)
			(type default)
		)
		(layer "In3.Cu")
	)
	(gr_line
		(start 175.09998 -5.875528)
		(end 175.09998 -7.983728)
		(stroke
			(width 0.254)
			(type default)
		)
		(layer "In3.Cu")
	)
	(gr_line
		(start 175.09998 -3.88366)
		(end 174.69358 -3.88366)
		(stroke
			(width 0.254)
			(type default)
		)
		(layer "In3.Cu")
	)
	(gr_line
		(start 175.09998 -3.783584)
		(end 174.69358 -3.783584)
		(stroke
			(width 0.254)
			(type default)
		)
		(layer "In3.Cu")
	)
	(gr_line
		(start 175.09998 -1.77546)
		(end 175.09998 -3.88366)
		(stroke
			(width 0.254)
			(type default)
		)
		(layer "In3.Cu")
	)
	(gr_line
		(start 175.09998 -1.675384)
		(end 175.09998 -3.783584)
		(stroke
			(width 0.254)
			(type default)
		)
		(layer "In3.Cu")
	)
	(gr_line
		(start 175.15078 -12.233148)
		(end 175.15078 -10.251948)
		(stroke
			(width 0.762)
			(type default)
		)
		(layer "In3.Cu")
	)
	(gr_line
		(start 175.15078 -12.133072)
		(end 175.15078 -10.151872)
		(stroke
			(width 0.762)
			(type default)
		)
		(layer "In3.Cu")
	)
	(gr_line
		(start 175.15078 -8.033004)
		(end 175.15078 -6.051804)
		(stroke
			(width 0.762)
			(type default)
		)
		(layer "In3.Cu")
	)
	(gr_line
		(start 175.15078 -7.932928)
		(end 175.15078 -5.951728)
		(stroke
			(width 0.762)
			(type default)
		)
		(layer "In3.Cu")
	)
	(gr_line
		(start 175.15078 -3.83286)
		(end 175.15078 -1.85166)
		(stroke
			(width 0.762)
			(type default)
		)
		(layer "In3.Cu")
	)
	(gr_line
		(start 175.15078 -3.732784)
		(end 175.15078 -1.751584)
		(stroke
			(width 0.762)
			(type default)
		)
		(layer "In3.Cu")
	)
	(gr_line
		(start 175.17618 -12.360148)
		(end 174.61738 -12.360148)
		(stroke
			(width 0.254)
			(type default)
		)
		(layer "In3.Cu")
	)
	(gr_line
		(start 175.17618 -12.260072)
		(end 174.61738 -12.260072)
		(stroke
			(width 0.254)
			(type default)
		)
		(layer "In3.Cu")
	)
	(gr_line
		(start 175.17618 -10.124948)
		(end 175.17618 -12.360148)
		(stroke
			(width 0.254)
			(type default)
		)
		(layer "In3.Cu")
	)
	(gr_line
		(start 175.17618 -10.024872)
		(end 175.17618 -12.260072)
		(stroke
			(width 0.254)
			(type default)
		)
		(layer "In3.Cu")
	)
	(gr_line
		(start 175.17618 -8.160004)
		(end 174.61738 -8.160004)
		(stroke
			(width 0.254)
			(type default)
		)
		(layer "In3.Cu")
	)
	(gr_line
		(start 175.17618 -8.059928)
		(end 174.61738 -8.059928)
		(stroke
			(width 0.254)
			(type default)
		)
		(layer "In3.Cu")
	)
	(gr_line
		(start 175.17618 -5.924804)
		(end 175.17618 -8.160004)
		(stroke
			(width 0.254)
			(type default)
		)
		(layer "In3.Cu")
	)
	(gr_line
		(start 175.17618 -5.824728)
		(end 175.17618 -8.059928)
		(stroke
			(width 0.254)
			(type default)
		)
		(layer "In3.Cu")
	)
	(gr_line
		(start 175.17618 -3.95986)
		(end 174.61738 -3.95986)
		(stroke
			(width 0.254)
			(type default)
		)
		(layer "In3.Cu")
	)
	(gr_line
		(start 175.17618 -3.859784)
		(end 174.61738 -3.859784)
		(stroke
			(width 0.254)
			(type default)
		)
		(layer "In3.Cu")
	)
	(gr_line
		(start 175.17618 -1.72466)
		(end 175.17618 -3.95986)
		(stroke
			(width 0.254)
			(type default)
		)
		(layer "In3.Cu")
	)
	(gr_line
		(start 175.17618 -1.624584)
		(end 175.17618 -3.859784)
		(stroke
			(width 0.254)
			(type default)
		)
		(layer "In3.Cu")
	)
	(gr_line
		(start 175.25238 -12.385548)
		(end 174.54118 -12.385548)
		(stroke
			(width 0.254)
			(type default)
		)
		(layer "In3.Cu")
	)
	(gr_line
		(start 175.25238 -12.285472)
		(end 174.54118 -12.285472)
		(stroke
			(width 0.254)
			(type default)
		)
		(layer "In3.Cu")
	)
	(gr_line
		(start 175.25238 -10.048748)
		(end 175.25238 -12.385548)
		(stroke
			(width 0.254)
			(type default)
		)
		(layer "In3.Cu")
	)
	(gr_line
		(start 175.25238 -9.948672)
		(end 175.25238 -12.285472)
		(stroke
			(width 0.254)
			(type default)
		)
		(layer "In3.Cu")
	)
	(gr_line
		(start 175.25238 -8.185404)
		(end 174.54118 -8.185404)
		(stroke
			(width 0.254)
			(type default)
		)
		(layer "In3.Cu")
	)
	(gr_line
		(start 175.25238 -8.085328)
		(end 174.54118 -8.085328)
		(stroke
			(width 0.254)
			(type default)
		)
		(layer "In3.Cu")
	)
	(gr_line
		(start 175.25238 -5.848604)
		(end 175.25238 -8.185404)
		(stroke
			(width 0.254)
			(type default)
		)
		(layer "In3.Cu")
	)
	(gr_line
		(start 175.25238 -5.748528)
		(end 175.25238 -8.085328)
		(stroke
			(width 0.254)
			(type default)
		)
		(layer "In3.Cu")
	)
	(gr_line
		(start 175.25238 -3.98526)
		(end 174.54118 -3.98526)
		(stroke
			(width 0.254)
			(type default)
		)
		(layer "In3.Cu")
	)
	(gr_line
		(start 175.25238 -3.885184)
		(end 174.54118 -3.885184)
		(stroke
			(width 0.254)
			(type default)
		)
		(layer "In3.Cu")
	)
	(gr_line
		(start 175.25238 -1.64846)
		(end 175.25238 -3.98526)
		(stroke
			(width 0.254)
			(type default)
		)
		(layer "In3.Cu")
	)
	(gr_line
		(start 175.25238 -1.548384)
		(end 175.25238 -3.885184)
		(stroke
			(width 0.254)
			(type default)
		)
		(layer "In3.Cu")
	)
	(gr_line
		(start 175.27778 -12.512548)
		(end 174.28718 -12.512548)
		(stroke
			(width 0.1016)
			(type default)
		)
		(layer "In3.Cu")
	)
	(gr_line
		(start 175.27778 -12.436348)
		(end 174.46498 -12.436348)
		(stroke
			(width 0.254)
			(type default)
		)
		(layer "In3.Cu")
	)
	(gr_line
		(start 175.27778 -12.412472)
		(end 174.28718 -12.412472)
		(stroke
			(width 0.1016)
			(type default)
		)
		(layer "In3.Cu")
	)
	(gr_line
		(start 175.27778 -12.336272)
		(end 174.46498 -12.336272)
		(stroke
			(width 0.254)
			(type default)
		)
		(layer "In3.Cu")
	)
	(gr_line
		(start 175.27778 -10.023348)
		(end 175.27778 -12.436348)
		(stroke
			(width 0.254)
			(type default)
		)
		(layer "In3.Cu")
	)
	(gr_line
		(start 175.27778 -9.923272)
		(end 175.27778 -12.336272)
		(stroke
			(width 0.254)
			(type default)
		)
		(layer "In3.Cu")
	)
	(gr_line
		(start 175.27778 -8.312404)
		(end 174.28718 -8.312404)
		(stroke
			(width 0.1016)
			(type default)
		)
		(layer "In3.Cu")
	)
	(gr_line
		(start 175.27778 -8.236204)
		(end 174.46498 -8.236204)
		(stroke
			(width 0.254)
			(type default)
		)
		(layer "In3.Cu")
	)
	(gr_line
		(start 175.27778 -8.212328)
		(end 174.28718 -8.212328)
		(stroke
			(width 0.1016)
			(type default)
		)
		(layer "In3.Cu")
	)
	(gr_line
		(start 175.27778 -8.136128)
		(end 174.46498 -8.136128)
		(stroke
			(width 0.254)
			(type default)
		)
		(layer "In3.Cu")
	)
	(gr_line
		(start 175.27778 -5.823204)
		(end 175.27778 -8.236204)
		(stroke
			(width 0.254)
			(type default)
		)
		(layer "In3.Cu")
	)
	(gr_line
		(start 175.27778 -5.723128)
		(end 175.27778 -8.136128)
		(stroke
			(width 0.254)
			(type default)
		)
		(layer "In3.Cu")
	)
	(gr_line
		(start 175.27778 -4.11226)
		(end 174.28718 -4.11226)
		(stroke
			(width 0.1016)
			(type default)
		)
		(layer "In3.Cu")
	)
	(gr_line
		(start 175.27778 -4.03606)
		(end 174.46498 -4.03606)
		(stroke
			(width 0.254)
			(type default)
		)
		(layer "In3.Cu")
	)
	(gr_line
		(start 175.27778 -4.012184)
		(end 174.28718 -4.012184)
		(stroke
			(width 0.1016)
			(type default)
		)
		(layer "In3.Cu")
	)
	(gr_line
		(start 175.27778 -3.935984)
		(end 174.46498 -3.935984)
		(stroke
			(width 0.254)
			(type default)
		)
		(layer "In3.Cu")
	)
	(gr_line
		(start 175.27778 -1.62306)
		(end 175.27778 -4.03606)
		(stroke
			(width 0.254)
			(type default)
		)
		(layer "In3.Cu")
	)
	(gr_line
		(start 175.27778 -1.522984)
		(end 175.27778 -3.935984)
		(stroke
			(width 0.254)
			(type default)
		)
		(layer "In3.Cu")
	)
	(gr_line
		(start 175.30318 -12.461748)
		(end 174.43958 -12.461748)
		(stroke
			(width 0.254)
			(type default)
		)
		(layer "In3.Cu")
	)
	(gr_line
		(start 175.30318 -12.361672)
		(end 174.43958 -12.361672)
		(stroke
			(width 0.254)
			(type default)
		)
		(layer "In3.Cu")
	)
	(gr_line
		(start 175.30318 -9.997948)
		(end 175.30318 -12.461748)
		(stroke
			(width 0.254)
			(type default)
		)
		(layer "In3.Cu")
	)
	(gr_line
		(start 175.30318 -9.897872)
		(end 175.30318 -12.361672)
		(stroke
			(width 0.254)
			(type default)
		)
		(layer "In3.Cu")
	)
	(gr_line
		(start 175.30318 -8.261604)
		(end 174.43958 -8.261604)
		(stroke
			(width 0.254)
			(type default)
		)
		(layer "In3.Cu")
	)
	(gr_line
		(start 175.30318 -8.161528)
		(end 174.43958 -8.161528)
		(stroke
			(width 0.254)
			(type default)
		)
		(layer "In3.Cu")
	)
	(gr_line
		(start 175.30318 -5.797804)
		(end 175.30318 -8.261604)
		(stroke
			(width 0.254)
			(type default)
		)
		(layer "In3.Cu")
	)
	(gr_line
		(start 175.30318 -5.697728)
		(end 175.30318 -8.161528)
		(stroke
			(width 0.254)
			(type default)
		)
		(layer "In3.Cu")
	)
	(gr_line
		(start 175.30318 -4.06146)
		(end 174.43958 -4.06146)
		(stroke
			(width 0.254)
			(type default)
		)
		(layer "In3.Cu")
	)
	(gr_line
		(start 175.30318 -3.961384)
		(end 174.43958 -3.961384)
		(stroke
			(width 0.254)
			(type default)
		)
		(layer "In3.Cu")
	)
	(gr_line
		(start 175.30318 -1.59766)
		(end 175.30318 -4.06146)
		(stroke
			(width 0.254)
			(type default)
		)
		(layer "In3.Cu")
	)
	(gr_line
		(start 175.30318 -1.497584)
		(end 175.30318 -3.961384)
		(stroke
			(width 0.254)
			(type default)
		)
		(layer "In3.Cu")
	)
	(gr_line
		(start 175.35398 -12.487148)
		(end 174.41418 -12.487148)
		(stroke
			(width 0.254)
			(type default)
		)
		(layer "In3.Cu")
	)
	(gr_line
		(start 175.35398 -12.387072)
		(end 174.41418 -12.387072)
		(stroke
			(width 0.254)
			(type default)
		)
		(layer "In3.Cu")
	)
	(gr_line
		(start 175.35398 -9.997948)
		(end 175.35398 -12.487148)
		(stroke
			(width 0.254)
			(type default)
		)
		(layer "In3.Cu")
	)
	(gr_line
		(start 175.35398 -9.897872)
		(end 175.35398 -12.387072)
		(stroke
			(width 0.254)
			(type default)
		)
		(layer "In3.Cu")
	)
	(gr_line
		(start 175.35398 -8.287004)
		(end 174.41418 -8.287004)
		(stroke
			(width 0.254)
			(type default)
		)
		(layer "In3.Cu")
	)
	(gr_line
		(start 175.35398 -8.186928)
		(end 174.41418 -8.186928)
		(stroke
			(width 0.254)
			(type default)
		)
		(layer "In3.Cu")
	)
	(gr_line
		(start 175.35398 -5.797804)
		(end 175.35398 -8.287004)
		(stroke
			(width 0.254)
			(type default)
		)
		(layer "In3.Cu")
	)
	(gr_line
		(start 175.35398 -5.697728)
		(end 175.35398 -8.186928)
		(stroke
			(width 0.254)
			(type default)
		)
		(layer "In3.Cu")
	)
	(gr_line
		(start 175.35398 -4.08686)
		(end 174.41418 -4.08686)
		(stroke
			(width 0.254)
			(type default)
		)
		(layer "In3.Cu")
	)
	(gr_line
		(start 175.35398 -3.986784)
		(end 174.41418 -3.986784)
		(stroke
			(width 0.254)
			(type default)
		)
		(layer "In3.Cu")
	)
	(gr_line
		(start 175.35398 -1.59766)
		(end 175.35398 -4.08686)
		(stroke
			(width 0.254)
			(type default)
		)
		(layer "In3.Cu")
	)
	(gr_line
		(start 175.35398 -1.497584)
		(end 175.35398 -3.986784)
		(stroke
			(width 0.254)
			(type default)
		)
		(layer "In3.Cu")
	)
	(gr_line
		(start 175.37938 -12.487148)
		(end 174.41418 -12.487148)
		(stroke
			(width 0.2032)
			(type default)
		)
		(layer "In3.Cu")
	)
	(gr_line
		(start 175.37938 -12.387072)
		(end 174.41418 -12.387072)
		(stroke
			(width 0.2032)
			(type default)
		)
		(layer "In3.Cu")
	)
	(gr_line
		(start 175.37938 -9.947148)
		(end 175.37938 -12.487148)
		(stroke
			(width 0.2032)
			(type default)
		)
		(layer "In3.Cu")
	)
	(gr_line
		(start 175.37938 -9.847072)
		(end 175.37938 -12.387072)
		(stroke
			(width 0.2032)
			(type default)
		)
		(layer "In3.Cu")
	)
	(gr_line
		(start 175.37938 -8.287004)
		(end 174.41418 -8.287004)
		(stroke
			(width 0.2032)
			(type default)
		)
		(layer "In3.Cu")
	)
	(gr_line
		(start 175.37938 -8.186928)
		(end 174.41418 -8.186928)
		(stroke
			(width 0.2032)
			(type default)
		)
		(layer "In3.Cu")
	)
	(gr_line
		(start 175.37938 -5.747004)
		(end 175.37938 -8.287004)
		(stroke
			(width 0.2032)
			(type default)
		)
		(layer "In3.Cu")
	)
	(gr_line
		(start 175.37938 -5.646928)
		(end 175.37938 -8.186928)
		(stroke
			(width 0.2032)
			(type default)
		)
		(layer "In3.Cu")
	)
	(gr_line
		(start 175.37938 -4.08686)
		(end 174.41418 -4.08686)
		(stroke
			(width 0.2032)
			(type default)
		)
		(layer "In3.Cu")
	)
	(gr_line
		(start 175.37938 -3.986784)
		(end 174.41418 -3.986784)
		(stroke
			(width 0.2032)
			(type default)
		)
		(layer "In3.Cu")
	)
	(gr_line
		(start 175.37938 -1.54686)
		(end 175.37938 -4.08686)
		(stroke
			(width 0.2032)
			(type default)
		)
		(layer "In3.Cu")
	)
	(gr_line
		(start 175.37938 -1.446784)
		(end 175.37938 -3.986784)
		(stroke
			(width 0.2032)
			(type default)
		)
		(layer "In3.Cu")
	)
	(gr_line
		(start 175.43018 -12.512548)
		(end 174.36338 -12.512548)
		(stroke
			(width 0.2032)
			(type default)
		)
		(layer "In3.Cu")
	)
	(gr_line
		(start 175.43018 -12.412472)
		(end 174.36338 -12.412472)
		(stroke
			(width 0.2032)
			(type default)
		)
		(layer "In3.Cu")
	)
	(gr_line
		(start 175.43018 -9.947148)
		(end 175.43018 -12.512548)
		(stroke
			(width 0.2032)
			(type default)
		)
		(layer "In3.Cu")
	)
	(gr_line
		(start 175.43018 -9.847072)
		(end 175.43018 -12.412472)
		(stroke
			(width 0.2032)
			(type default)
		)
		(layer "In3.Cu")
	)
	(gr_line
		(start 175.43018 -8.312404)
		(end 174.36338 -8.312404)
		(stroke
			(width 0.2032)
			(type default)
		)
		(layer "In3.Cu")
	)
	(gr_line
		(start 175.43018 -8.212328)
		(end 174.36338 -8.212328)
		(stroke
			(width 0.2032)
			(type default)
		)
		(layer "In3.Cu")
	)
	(gr_line
		(start 175.43018 -5.747004)
		(end 175.43018 -8.312404)
		(stroke
			(width 0.2032)
			(type default)
		)
		(layer "In3.Cu")
	)
	(gr_line
		(start 175.43018 -5.646928)
		(end 175.43018 -8.212328)
		(stroke
			(width 0.2032)
			(type default)
		)
		(layer "In3.Cu")
	)
	(gr_line
		(start 175.43018 -4.11226)
		(end 174.36338 -4.11226)
		(stroke
			(width 0.2032)
			(type default)
		)
		(layer "In3.Cu")
	)
	(gr_line
		(start 175.43018 -4.012184)
		(end 174.36338 -4.012184)
		(stroke
			(width 0.2032)
			(type default)
		)
		(layer "In3.Cu")
	)
	(gr_line
		(start 175.43018 -1.54686)
		(end 175.43018 -4.11226)
		(stroke
			(width 0.2032)
			(type default)
		)
		(layer "In3.Cu")
	)
	(gr_line
		(start 175.43018 -1.446784)
		(end 175.43018 -4.012184)
		(stroke
			(width 0.2032)
			(type default)
		)
		(layer "In3.Cu")
	)
	(gr_line
		(start 175.45558 -12.512548)
		(end 174.33798 -12.512548)
		(stroke
			(width 0.1016)
			(type default)
		)
		(layer "In3.Cu")
	)
	(gr_line
		(start 175.45558 -12.412472)
		(end 174.33798 -12.412472)
		(stroke
			(width 0.1016)
			(type default)
		)
		(layer "In3.Cu")
	)
	(gr_line
		(start 175.45558 -9.921748)
		(end 175.45558 -12.512548)
		(stroke
			(width 0.1016)
			(type default)
		)
		(layer "In3.Cu")
	)
	(gr_line
		(start 175.45558 -9.821672)
		(end 175.45558 -12.412472)
		(stroke
			(width 0.1016)
			(type default)
		)
		(layer "In3.Cu")
	)
	(gr_line
		(start 175.45558 -8.312404)
		(end 174.33798 -8.312404)
		(stroke
			(width 0.1016)
			(type default)
		)
		(layer "In3.Cu")
	)
	(gr_line
		(start 175.45558 -8.212328)
		(end 174.33798 -8.212328)
		(stroke
			(width 0.1016)
			(type default)
		)
		(layer "In3.Cu")
	)
	(gr_line
		(start 175.45558 -5.721604)
		(end 175.45558 -8.312404)
		(stroke
			(width 0.1016)
			(type default)
		)
		(layer "In3.Cu")
	)
	(gr_line
		(start 175.45558 -5.621528)
		(end 175.45558 -8.212328)
		(stroke
			(width 0.1016)
			(type default)
		)
		(layer "In3.Cu")
	)
	(gr_line
		(start 175.45558 -4.11226)
		(end 174.33798 -4.11226)
		(stroke
			(width 0.1016)
			(type default)
		)
		(layer "In3.Cu")
	)
	(gr_line
		(start 175.45558 -4.012184)
		(end 174.33798 -4.012184)
		(stroke
			(width 0.1016)
			(type default)
		)
		(layer "In3.Cu")
	)
	(gr_line
		(start 175.45558 -1.52146)
		(end 175.45558 -4.11226)
		(stroke
			(width 0.1016)
			(type default)
		)
		(layer "In3.Cu")
	)
	(gr_line
		(start 175.45558 -1.421384)
		(end 175.45558 -4.012184)
		(stroke
			(width 0.1016)
			(type default)
		)
		(layer "In3.Cu")
	)
	(gr_line
		(start 175.48098 -12.563348)
		(end 175.07458 -12.563348)
		(stroke
			(width 0.1016)
			(type default)
		)
		(layer "In3.Cu")
	)
	(gr_line
		(start 175.48098 -12.563348)
		(end 175.48098 -9.896348)
		(stroke
			(width 0.1016)
			(type default)
		)
		(layer "In3.Cu")
	)
	(gr_line
		(start 175.48098 -12.463272)
		(end 175.07458 -12.463272)
		(stroke
			(width 0.1016)
			(type default)
		)
		(layer "In3.Cu")
	)
	(gr_line
		(start 175.48098 -12.463272)
		(end 175.48098 -9.796272)
		(stroke
			(width 0.1016)
			(type default)
		)
		(layer "In3.Cu")
	)
	(gr_line
		(start 175.48098 -9.896348)
		(end 174.28718 -9.896348)
		(stroke
			(width 0.1016)
			(type default)
		)
		(layer "In3.Cu")
	)
	(gr_line
		(start 175.48098 -9.896348)
		(end 175.48098 -12.563348)
		(stroke
			(width 0.1016)
			(type default)
		)
		(layer "In3.Cu")
	)
	(gr_line
		(start 175.48098 -9.796272)
		(end 174.28718 -9.796272)
		(stroke
			(width 0.1016)
			(type default)
		)
		(layer "In3.Cu")
	)
	(gr_line
		(start 175.48098 -9.796272)
		(end 175.48098 -12.463272)
		(stroke
			(width 0.1016)
			(type default)
		)
		(layer "In3.Cu")
	)
	(gr_line
		(start 175.48098 -8.363204)
		(end 175.07458 -8.363204)
		(stroke
			(width 0.1016)
			(type default)
		)
		(layer "In3.Cu")
	)
	(gr_line
		(start 175.48098 -8.363204)
		(end 175.48098 -5.696204)
		(stroke
			(width 0.1016)
			(type default)
		)
		(layer "In3.Cu")
	)
	(gr_line
		(start 175.48098 -8.263128)
		(end 175.07458 -8.263128)
		(stroke
			(width 0.1016)
			(type default)
		)
		(layer "In3.Cu")
	)
	(gr_line
		(start 175.48098 -8.263128)
		(end 175.48098 -5.596128)
		(stroke
			(width 0.1016)
			(type default)
		)
		(layer "In3.Cu")
	)
	(gr_line
		(start 175.48098 -5.696204)
		(end 174.28718 -5.696204)
		(stroke
			(width 0.1016)
			(type default)
		)
		(layer "In3.Cu")
	)
	(gr_line
		(start 175.48098 -5.696204)
		(end 175.48098 -8.363204)
		(stroke
			(width 0.1016)
			(type default)
		)
		(layer "In3.Cu")
	)
	(gr_line
		(start 175.48098 -5.596128)
		(end 174.28718 -5.596128)
		(stroke
			(width 0.1016)
			(type default)
		)
		(layer "In3.Cu")
	)
	(gr_line
		(start 175.48098 -5.596128)
		(end 175.48098 -8.263128)
		(stroke
			(width 0.1016)
			(type default)
		)
		(layer "In3.Cu")
	)
	(gr_line
		(start 175.48098 -4.16306)
		(end 175.07458 -4.16306)
		(stroke
			(width 0.1016)
			(type default)
		)
		(layer "In3.Cu")
	)
	(gr_line
		(start 175.48098 -4.16306)
		(end 175.48098 -1.49606)
		(stroke
			(width 0.1016)
			(type default)
		)
		(layer "In3.Cu")
	)
	(gr_line
		(start 175.48098 -4.062984)
		(end 175.07458 -4.062984)
		(stroke
			(width 0.1016)
			(type default)
		)
		(layer "In3.Cu")
	)
	(gr_line
		(start 175.48098 -4.062984)
		(end 175.48098 -1.395984)
		(stroke
			(width 0.1016)
			(type default)
		)
		(layer "In3.Cu")
	)
	(gr_line
		(start 175.48098 -1.49606)
		(end 174.28718 -1.49606)
		(stroke
			(width 0.1016)
			(type default)
		)
		(layer "In3.Cu")
	)
	(gr_line
		(start 175.48098 -1.49606)
		(end 175.48098 -4.16306)
		(stroke
			(width 0.1016)
			(type default)
		)
		(layer "In3.Cu")
	)
	(gr_line
		(start 175.48098 -1.494028)
		(end 174.26178 -1.494028)
		(stroke
			(width 0.1016)
			(type default)
		)
		(layer "In3.Cu")
	)
	(gr_line
		(start 175.48098 -1.494028)
		(end 174.28718 -1.494028)
		(stroke
			(width 0.1016)
			(type default)
		)
		(layer "In3.Cu")
	)
	(gr_line
		(start 175.48098 -1.395984)
		(end 174.28718 -1.395984)
		(stroke
			(width 0.1016)
			(type default)
		)
		(layer "In3.Cu")
	)
	(gr_line
		(start 175.48098 -1.395984)
		(end 175.48098 -4.062984)
		(stroke
			(width 0.1016)
			(type default)
		)
		(layer "In3.Cu")
	)
	(gr_line
		(start 175.50638 -1.468628)
		(end 174.26178 -1.468628)
		(stroke
			(width 0.1016)
			(type default)
		)
		(layer "In3.Cu")
	)
	(gr_line
		(start 176.520094 -30.99562)
		(end 175.250094 -30.99562)
		(stroke
			(width 0.7874)
			(type default)
		)
		(layer "In3.Cu")
	)
	(gr_line
		(start 178.22418 -24.6634)
		(end 178.22418 -23.3934)
		(stroke
			(width 0.7874)
			(type default)
		)
		(layer "In3.Cu")
	)
	(gr_line
		(start 183.9976 -26.8224)
		(end 185.2676 -26.8224)
		(stroke
			(width 0.7874)
			(type default)
		)
		(layer "In3.Cu")
	)
	(gr_line
		(start 184.22874 -29.30906)
		(end 185.49874 -29.30906)
		(stroke
			(width 0.7874)
			(type default)
		)
		(layer "In3.Cu")
	)
	(gr_line
		(start 189.45987 -30.594808)
		(end 190.72987 -30.594808)
		(stroke
			(width 0.7874)
			(type default)
		)
		(layer "In3.Cu")
	)
	(gr_line
		(start 191.12992 -23.57882)
		(end 189.85992 -23.57882)
		(stroke
			(width 0.7874)
			(type default)
		)
		(layer "In3.Cu")
	)
	(gr_line
		(start 191.87414 -31.68142)
		(end 193.14414 -31.68142)
		(stroke
			(width 0.7874)
			(type default)
		)
		(layer "In3.Cu")
	)
	(gr_line
		(start 193.529966 -18.5166)
		(end 192.259966 -18.5166)
		(stroke
			(width 0.7874)
			(type default)
		)
		(layer "In3.Cu")
	)
	(gr_line
		(start 194.259962 -30.56382)
		(end 195.529962 -30.56382)
		(stroke
			(width 0.7874)
			(type default)
		)
		(layer "In3.Cu")
	)
	(gr_arc
		(start 197.300088 -8.263382)
		(mid 198.922885 -13.697276)
		(end 201.00036 -8.420608)
		(stroke
			(width 2.032)
			(type default)
		)
		(layer "In3.Cu")
	)
	(gr_line
		(start 197.300088 -4.907788)
		(end 197.300088 -8.263382)
		(stroke
			(width 2.032)
			(type default)
		)
		(layer "In3.Cu")
	)
	(gr_line
		(start 197.310756 -4.89712)
		(end 197.300088 -4.907788)
		(stroke
			(width 2.032)
			(type default)
		)
		(layer "In3.Cu")
	)
	(gr_line
		(start 197.6628 -24.67102)
		(end 197.6628 -23.40102)
		(stroke
			(width 0.7874)
			(type default)
		)
		(layer "In3.Cu")
	)
	(gr_line
		(start 199.04964 -10.700004)
		(end 199.049894 -10.700258)
		(stroke
			(width 4.064)
			(type default)
		)
		(layer "In3.Cu")
	)
	(gr_line
		(start 199.04964 -4.699762)
		(end 199.04964 -10.700004)
		(stroke
			(width 4.064)
			(type default)
		)
		(layer "In3.Cu")
	)
	(gr_line
		(start 199.049894 -10.700258)
		(end 199.049894 -10.700004)
		(stroke
			(width 6.604)
			(type default)
		)
		(layer "In3.Cu")
	)
	(gr_line
		(start 200.799954 -8.220202)
		(end 200.799954 -4.700016)
		(stroke
			(width 2.032)
			(type default)
		)
		(layer "In3.Cu")
	)
	(gr_arc
		(start 200.799954 -4.700016)
		(mid 198.951198 -2.952487)
		(end 197.310756 -4.89712)
		(stroke
			(width 2.032)
			(type default)
		)
		(layer "In3.Cu")
	)
	(gr_line
		(start 201.00036 -8.420608)
		(end 200.799954 -8.220202)
		(stroke
			(width 2.032)
			(type default)
		)
		(layer "In3.Cu")
	)
	(gr_line
		(start 202.989942 -50.390044)
		(end 203.36891 -50.464466)
		(stroke
			(width 2.032)
			(type default)
		)
		(layer "In3.Cu")
	)
	(gr_line
		(start 203.36891 -50.464466)
		(end 203.691236 -50.677064)
		(stroke
			(width 2.032)
			(type default)
		)
		(layer "In3.Cu")
	)
	(gr_line
		(start 203.691236 -50.677064)
		(end 203.909168 -50.996088)
		(stroke
			(width 2.032)
			(type default)
		)
		(layer "In3.Cu")
	)
	(gr_line
		(start 203.909168 -50.996088)
		(end 203.997814 -51.376072)
		(stroke
			(width 2.032)
			(type default)
		)
		(layer "In3.Cu")
	)
	(gr_line
		(start 203.997814 -51.376072)
		(end 204.06614 -51.702716)
		(stroke
			(width 2.032)
			(type default)
		)
		(layer "In3.Cu")
	)
	(gr_line
		(start 204.06614 -51.702716)
		(end 204.282802 -52.027074)
		(stroke
			(width 2.032)
			(type default)
		)
		(layer "In3.Cu")
	)
	(gr_line
		(start 204.282802 -52.027074)
		(end 204.607414 -52.24399)
		(stroke
			(width 2.032)
			(type default)
		)
		(layer "In3.Cu")
	)
	(gr_line
		(start 204.68336 -52.319936)
		(end 204.607414 -52.24399)
		(stroke
			(width 2.032)
			(type default)
		)
		(layer "In3.Cu")
	)
	(gr_arc
		(start 208.060036 -45.06341)
		(mid 209.682833 -50.497304)
		(end 211.760308 -45.220636)
		(stroke
			(width 2.032)
			(type default)
		)
		(layer "In3.Cu")
	)
	(gr_line
		(start 208.060036 -41.707816)
		(end 208.060036 -45.06341)
		(stroke
			(width 2.032)
			(type default)
		)
		(layer "In3.Cu")
	)
	(gr_line
		(start 208.070704 -41.697148)
		(end 208.060036 -41.707816)
		(stroke
			(width 2.032)
			(type default)
		)
		(layer "In3.Cu")
	)
	(gr_line
		(start 209.809588 -47.500032)
		(end 209.809842 -47.500286)
		(stroke
			(width 4.064)
			(type default)
		)
		(layer "In3.Cu")
	)
	(gr_line
		(start 209.809588 -41.49979)
		(end 209.809588 -47.500032)
		(stroke
			(width 4.064)
			(type default)
		)
		(layer "In3.Cu")
	)
	(gr_line
		(start 209.809842 -47.500286)
		(end 209.809842 -47.500032)
		(stroke
			(width 6.604)
			(type default)
		)
		(layer "In3.Cu")
	)
	(gr_line
		(start 211.559902 -45.02023)
		(end 211.559902 -41.500044)
		(stroke
			(width 2.032)
			(type default)
		)
		(layer "In3.Cu")
	)
	(gr_arc
		(start 211.559902 -41.500044)
		(mid 209.711146 -39.752515)
		(end 208.070704 -41.697148)
		(stroke
			(width 2.032)
			(type default)
		)
		(layer "In3.Cu")
	)
	(gr_line
		(start 211.760308 -45.220636)
		(end 211.559902 -45.02023)
		(stroke
			(width 2.032)
			(type default)
		)
		(layer "In3.Cu")
	)
	(gr_arc
		(start 278.06015 -8.263128)
		(mid 279.682947 -13.697022)
		(end 281.760422 -8.420354)
		(stroke
			(width 2.032)
			(type default)
		)
		(layer "In3.Cu")
	)
	(gr_line
		(start 278.06015 -4.907534)
		(end 278.06015 -8.263128)
		(stroke
			(width 2.032)
			(type default)
		)
		(layer "In3.Cu")
	)
	(gr_line
		(start 278.070818 -4.896866)
		(end 278.06015 -4.907534)
		(stroke
			(width 2.032)
			(type default)
		)
		(layer "In3.Cu")
	)
	(gr_line
		(start 279.809702 -10.69975)
		(end 279.809956 -10.700004)
		(stroke
			(width 4.064)
			(type default)
		)
		(layer "In3.Cu")
	)
	(gr_line
		(start 279.809702 -4.699508)
		(end 279.809702 -10.69975)
		(stroke
			(width 4.064)
			(type default)
		)
		(layer "In3.Cu")
	)
	(gr_line
		(start 279.809956 -10.700004)
		(end 279.809956 -10.69975)
		(stroke
			(width 6.604)
			(type default)
		)
		(layer "In3.Cu")
	)
	(gr_line
		(start 281.560016 -8.219948)
		(end 281.560016 -4.699762)
		(stroke
			(width 2.032)
			(type default)
		)
		(layer "In3.Cu")
	)
	(gr_arc
		(start 281.560016 -4.699762)
		(mid 279.71126 -2.952233)
		(end 278.070818 -4.896866)
		(stroke
			(width 2.032)
			(type default)
		)
		(layer "In3.Cu")
	)
	(gr_line
		(start 281.760422 -8.420354)
		(end 281.560016 -8.219948)
		(stroke
			(width 2.032)
			(type default)
		)
		(layer "In3.Cu")
	)
	(gr_arc
		(start 299.060108 -45.06341)
		(mid 300.682905 -50.497304)
		(end 302.76038 -45.220636)
		(stroke
			(width 2.032)
			(type default)
		)
		(layer "In3.Cu")
	)
	(gr_line
		(start 299.060108 -41.707816)
		(end 299.060108 -45.06341)
		(stroke
			(width 2.032)
			(type default)
		)
		(layer "In3.Cu")
	)
	(gr_line
		(start 299.070776 -41.697148)
		(end 299.060108 -41.707816)
		(stroke
			(width 2.032)
			(type default)
		)
		(layer "In3.Cu")
	)
	(gr_line
		(start 300.80966 -47.500032)
		(end 300.809914 -47.500286)
		(stroke
			(width 4.064)
			(type default)
		)
		(layer "In3.Cu")
	)
	(gr_line
		(start 300.80966 -41.49979)
		(end 300.80966 -47.500032)
		(stroke
			(width 4.064)
			(type default)
		)
		(layer "In3.Cu")
	)
	(gr_line
		(start 300.809914 -47.500286)
		(end 300.809914 -47.500032)
		(stroke
			(width 6.604)
			(type default)
		)
		(layer "In3.Cu")
	)
	(gr_line
		(start 302.559974 -45.02023)
		(end 302.559974 -41.500044)
		(stroke
			(width 2.032)
			(type default)
		)
		(layer "In3.Cu")
	)
	(gr_arc
		(start 302.559974 -41.500044)
		(mid 300.711218 -39.752515)
		(end 299.070776 -41.697148)
		(stroke
			(width 2.032)
			(type default)
		)
		(layer "In3.Cu")
	)
	(gr_line
		(start 302.76038 -45.220636)
		(end 302.559974 -45.02023)
		(stroke
			(width 2.032)
			(type default)
		)
		(layer "In3.Cu")
	)
	(gr_line
		(start 316.06998 -52.319936)
		(end 204.68336 -52.319936)
		(stroke
			(width 2.032)
			(type default)
		)
		(layer "In3.Cu")
	)
	(gr_arc
		(start 316.06998 -52.319936)
		(mid 316.777112 -52.027053)
		(end 317.069978 -51.319938)
		(stroke
			(width 2.032)
			(type default)
		)
		(layer "In3.Cu")
	)
	(gr_line
		(start 317.069978 -50.8)
		(end 317.069978 -51.319938)
		(stroke
			(width 2.032)
			(type default)
		)
		(layer "In3.Cu")
	)
	(gr_arc
		(start 318.069976 -49.800002)
		(mid 317.362871 -50.092895)
		(end 317.069978 -50.8)
		(stroke
			(width 2.032)
			(type default)
		)
		(layer "In3.Cu")
	)
	(gr_line
		(start 322.576698 -11.3792)
		(end 322.576698 -9.1948)
		(stroke
			(width 0.254)
			(type default)
		)
		(layer "In3.Cu")
	)
	(gr_line
		(start 322.576698 -9.1948)
		(end 324.151498 -9.1948)
		(stroke
			(width 0.254)
			(type default)
		)
		(layer "In3.Cu")
	)
	(gr_line
		(start 322.602098 -11.3792)
		(end 322.602098 -9.2456)
		(stroke
			(width 0.254)
			(type default)
		)
		(layer "In3.Cu")
	)
	(gr_line
		(start 322.602098 -9.2456)
		(end 324.126098 -9.2456)
		(stroke
			(width 0.254)
			(type default)
		)
		(layer "In3.Cu")
	)
	(gr_line
		(start 322.652898 -11.3538)
		(end 322.652898 -9.3726)
		(stroke
			(width 0.254)
			(type default)
		)
		(layer "In3.Cu")
	)
	(gr_line
		(start 322.652898 -9.3726)
		(end 324.100698 -9.3726)
		(stroke
			(width 0.254)
			(type default)
		)
		(layer "In3.Cu")
	)
	(gr_line
		(start 322.707 -11.303)
		(end 323.0118 -11.303)
		(stroke
			(width 0.1016)
			(type default)
		)
		(layer "In3.Cu")
	)
	(gr_line
		(start 322.707 -9.2964)
		(end 322.707 -11.303)
		(stroke
			(width 0.1016)
			(type default)
		)
		(layer "In3.Cu")
	)
	(gr_line
		(start 322.73494 -5.57784)
		(end 324.00494 -5.57784)
		(stroke
			(width 1.016)
			(type default)
		)
		(layer "In3.Cu")
	)
	(gr_line
		(start 322.7578 -11.2268)
		(end 323.85 -11.2268)
		(stroke
			(width 0.2032)
			(type default)
		)
		(layer "In3.Cu")
	)
	(gr_line
		(start 322.7578 -9.3726)
		(end 322.7578 -11.2268)
		(stroke
			(width 0.2032)
			(type default)
		)
		(layer "In3.Cu")
	)
	(gr_line
		(start 322.7832 -11.2268)
		(end 323.9516 -11.2268)
		(stroke
			(width 0.2032)
			(type default)
		)
		(layer "In3.Cu")
	)
	(gr_line
		(start 322.7832 -9.4234)
		(end 322.7832 -11.2268)
		(stroke
			(width 0.2032)
			(type default)
		)
		(layer "In3.Cu")
	)
	(gr_line
		(start 322.830698 -11.1252)
		(end 322.830698 -9.5758)
		(stroke
			(width 0.762)
			(type default)
		)
		(layer "In3.Cu")
	)
	(gr_line
		(start 322.830698 -11.1252)
		(end 323.745098 -11.1252)
		(stroke
			(width 0.762)
			(type default)
		)
		(layer "In3.Cu")
	)
	(gr_line
		(start 322.830698 -11.0998)
		(end 322.830698 -9.5504)
		(stroke
			(width 0.762)
			(type default)
		)
		(layer "In3.Cu")
	)
	(gr_line
		(start 322.830698 -10.9982)
		(end 322.830698 -9.4488)
		(stroke
			(width 0.762)
			(type default)
		)
		(layer "In3.Cu")
	)
	(gr_line
		(start 322.830698 -9.4488)
		(end 323.745098 -9.4488)
		(stroke
			(width 0.762)
			(type default)
		)
		(layer "In3.Cu")
	)
	(gr_line
		(start 322.834 -11.176)
		(end 323.9262 -11.176)
		(stroke
			(width 0.2032)
			(type default)
		)
		(layer "In3.Cu")
	)
	(gr_line
		(start 322.834 -9.4742)
		(end 322.834 -11.176)
		(stroke
			(width 0.2032)
			(type default)
		)
		(layer "In3.Cu")
	)
	(gr_line
		(start 322.856098 -10.9982)
		(end 323.770498 -10.9982)
		(stroke
			(width 0.762)
			(type default)
		)
		(layer "In3.Cu")
	)
	(gr_line
		(start 322.856098 -9.5758)
		(end 323.770498 -9.5758)
		(stroke
			(width 0.762)
			(type default)
		)
		(layer "In3.Cu")
	)
	(gr_line
		(start 322.9356 -11.0744)
		(end 323.723 -11.0744)
		(stroke
			(width 0.508)
			(type default)
		)
		(layer "In3.Cu")
	)
	(gr_line
		(start 322.9356 -11.049)
		(end 322.9356 -9.525)
		(stroke
			(width 0.508)
			(type default)
		)
		(layer "In3.Cu")
	)
	(gr_line
		(start 322.961 -11.0744)
		(end 322.961 -9.5504)
		(stroke
			(width 0.508)
			(type default)
		)
		(layer "In3.Cu")
	)
	(gr_line
		(start 322.983098 -11.1252)
		(end 323.897498 -11.1252)
		(stroke
			(width 0.762)
			(type default)
		)
		(layer "In3.Cu")
	)
	(gr_line
		(start 322.983098 -9.4488)
		(end 323.897498 -9.4488)
		(stroke
			(width 0.762)
			(type default)
		)
		(layer "In3.Cu")
	)
	(gr_line
		(start 322.9864 -9.525)
		(end 323.723 -9.525)
		(stroke
			(width 0.508)
			(type default)
		)
		(layer "In3.Cu")
	)
	(gr_line
		(start 323.0118 -11.303)
		(end 324.0024 -11.303)
		(stroke
			(width 0.1016)
			(type default)
		)
		(layer "In3.Cu")
	)
	(gr_line
		(start 323.0118 -11.0744)
		(end 323.0118 -9.5504)
		(stroke
			(width 0.508)
			(type default)
		)
		(layer "In3.Cu")
	)
	(gr_line
		(start 323.0372 -11.0744)
		(end 323.0372 -9.5504)
		(stroke
			(width 0.508)
			(type default)
		)
		(layer "In3.Cu")
	)
	(gr_line
		(start 323.0626 -11.0744)
		(end 323.0626 -9.5504)
		(stroke
			(width 0.508)
			(type default)
		)
		(layer "In3.Cu")
	)
	(gr_line
		(start 323.088 -11.0744)
		(end 323.088 -9.5504)
		(stroke
			(width 0.508)
			(type default)
		)
		(layer "In3.Cu")
	)
	(gr_line
		(start 323.088 -11.049)
		(end 323.088 -9.525)
		(stroke
			(width 0.508)
			(type default)
		)
		(layer "In3.Cu")
	)
	(gr_line
		(start 323.1134 -11.0744)
		(end 323.1134 -9.5504)
		(stroke
			(width 0.508)
			(type default)
		)
		(layer "In3.Cu")
	)
	(gr_line
		(start 323.1388 -11.0744)
		(end 323.1388 -9.5504)
		(stroke
			(width 0.508)
			(type default)
		)
		(layer "In3.Cu")
	)
	(gr_line
		(start 323.1896 -11.0744)
		(end 323.1896 -9.5504)
		(stroke
			(width 0.508)
			(type default)
		)
		(layer "In3.Cu")
	)
	(gr_line
		(start 323.1896 -11.049)
		(end 323.1896 -9.525)
		(stroke
			(width 0.508)
			(type default)
		)
		(layer "In3.Cu")
	)
	(gr_line
		(start 323.215 -11.0744)
		(end 323.215 -9.5504)
		(stroke
			(width 0.508)
			(type default)
		)
		(layer "In3.Cu")
	)
	(gr_line
		(start 323.2404 -11.0744)
		(end 323.2404 -9.5504)
		(stroke
			(width 0.508)
			(type default)
		)
		(layer "In3.Cu")
	)
	(gr_line
		(start 323.2658 -11.0744)
		(end 323.2658 -9.5504)
		(stroke
			(width 0.508)
			(type default)
		)
		(layer "In3.Cu")
	)
	(gr_line
		(start 323.3166 -11.0744)
		(end 323.3166 -9.5504)
		(stroke
			(width 0.508)
			(type default)
		)
		(layer "In3.Cu")
	)
	(gr_line
		(start 323.342 -11.0744)
		(end 323.342 -9.5504)
		(stroke
			(width 0.508)
			(type default)
		)
		(layer "In3.Cu")
	)
	(gr_line
		(start 323.342 -11.049)
		(end 323.342 -9.525)
		(stroke
			(width 0.508)
			(type default)
		)
		(layer "In3.Cu")
	)
	(gr_line
		(start 323.3674 -11.0744)
		(end 323.3674 -9.5504)
		(stroke
			(width 0.508)
			(type default)
		)
		(layer "In3.Cu")
	)
	(gr_line
		(start 323.3928 -11.0744)
		(end 323.3928 -9.5504)
		(stroke
			(width 0.508)
			(type default)
		)
		(layer "In3.Cu")
	)
	(gr_line
		(start 323.4182 -11.0744)
		(end 323.4182 -9.5504)
		(stroke
			(width 0.508)
			(type default)
		)
		(layer "In3.Cu")
	)
	(gr_line
		(start 323.4182 -11.049)
		(end 323.4182 -9.525)
		(stroke
			(width 0.508)
			(type default)
		)
		(layer "In3.Cu")
	)
	(gr_line
		(start 323.4436 -11.0744)
		(end 323.4436 -9.5504)
		(stroke
			(width 0.508)
			(type default)
		)
		(layer "In3.Cu")
	)
	(gr_line
		(start 323.469 -11.0744)
		(end 323.469 -9.5504)
		(stroke
			(width 0.508)
			(type default)
		)
		(layer "In3.Cu")
	)
	(gr_line
		(start 323.469 -11.049)
		(end 323.469 -9.525)
		(stroke
			(width 0.508)
			(type default)
		)
		(layer "In3.Cu")
	)
	(gr_line
		(start 323.4944 -11.0744)
		(end 323.4944 -9.5504)
		(stroke
			(width 0.508)
			(type default)
		)
		(layer "In3.Cu")
	)
	(gr_line
		(start 323.4944 -11.049)
		(end 323.4944 -9.525)
		(stroke
			(width 0.508)
			(type default)
		)
		(layer "In3.Cu")
	)
	(gr_line
		(start 323.5198 -11.049)
		(end 323.5198 -9.525)
		(stroke
			(width 0.508)
			(type default)
		)
		(layer "In3.Cu")
	)
	(gr_line
		(start 323.5452 -11.0744)
		(end 323.5452 -9.5504)
		(stroke
			(width 0.508)
			(type default)
		)
		(layer "In3.Cu")
	)
	(gr_line
		(start 323.567298 -11.3792)
		(end 322.576698 -11.3792)
		(stroke
			(width 0.254)
			(type default)
		)
		(layer "In3.Cu")
	)
	(gr_line
		(start 323.5706 -11.049)
		(end 323.5706 -9.525)
		(stroke
			(width 0.508)
			(type default)
		)
		(layer "In3.Cu")
	)
	(gr_line
		(start 323.596 -11.049)
		(end 323.596 -9.525)
		(stroke
			(width 0.508)
			(type default)
		)
		(layer "In3.Cu")
	)
	(gr_line
		(start 323.6214 -11.0744)
		(end 323.6214 -9.5504)
		(stroke
			(width 0.508)
			(type default)
		)
		(layer "In3.Cu")
	)
	(gr_line
		(start 323.6468 -11.0744)
		(end 323.6468 -9.5504)
		(stroke
			(width 0.508)
			(type default)
		)
		(layer "In3.Cu")
	)
	(gr_line
		(start 323.6468 -11.049)
		(end 323.6468 -9.525)
		(stroke
			(width 0.508)
			(type default)
		)
		(layer "In3.Cu")
	)
	(gr_line
		(start 323.6976 -11.0744)
		(end 323.6976 -9.5504)
		(stroke
			(width 0.508)
			(type default)
		)
		(layer "In3.Cu")
	)
	(gr_line
		(start 323.6976 -11.049)
		(end 323.6976 -9.525)
		(stroke
			(width 0.508)
			(type default)
		)
		(layer "In3.Cu")
	)
	(gr_line
		(start 323.7484 -11.0744)
		(end 323.7484 -9.5504)
		(stroke
			(width 0.508)
			(type default)
		)
		(layer "In3.Cu")
	)
	(gr_line
		(start 323.7484 -11.049)
		(end 323.7484 -9.525)
		(stroke
			(width 0.508)
			(type default)
		)
		(layer "In3.Cu")
	)
	(gr_line
		(start 323.770498 -11.0998)
		(end 323.770498 -9.5504)
		(stroke
			(width 0.762)
			(type default)
		)
		(layer "In3.Cu")
	)
	(gr_line
		(start 323.7738 -11.0744)
		(end 323.7738 -9.5504)
		(stroke
			(width 0.508)
			(type default)
		)
		(layer "In3.Cu")
	)
	(gr_line
		(start 323.7992 -11.0744)
		(end 323.7992 -9.5504)
		(stroke
			(width 0.508)
			(type default)
		)
		(layer "In3.Cu")
	)
	(gr_line
		(start 323.85 -11.2268)
		(end 323.8754 -11.2268)
		(stroke
			(width 0.2032)
			(type default)
		)
		(layer "In3.Cu")
	)
	(gr_line
		(start 323.8754 -11.2268)
		(end 323.8754 -9.4742)
		(stroke
			(width 0.2032)
			(type default)
		)
		(layer "In3.Cu")
	)
	(gr_line
		(start 323.8754 -9.4742)
		(end 322.834 -9.4742)
		(stroke
			(width 0.2032)
			(type default)
		)
		(layer "In3.Cu")
	)
	(gr_line
		(start 323.897498 -11.1252)
		(end 323.897498 -9.5758)
		(stroke
			(width 0.762)
			(type default)
		)
		(layer "In3.Cu")
	)
	(gr_line
		(start 323.897498 -11.0998)
		(end 323.897498 -9.6012)
		(stroke
			(width 0.762)
			(type default)
		)
		(layer "In3.Cu")
	)
	(gr_line
		(start 323.897498 -10.9982)
		(end 323.897498 -9.4488)
		(stroke
			(width 0.762)
			(type default)
		)
		(layer "In3.Cu")
	)
	(gr_line
		(start 323.9262 -11.176)
		(end 323.9262 -9.4234)
		(stroke
			(width 0.2032)
			(type default)
		)
		(layer "In3.Cu")
	)
	(gr_line
		(start 323.9262 -9.4234)
		(end 322.7832 -9.4234)
		(stroke
			(width 0.2032)
			(type default)
		)
		(layer "In3.Cu")
	)
	(gr_line
		(start 323.9516 -11.2268)
		(end 323.9516 -9.3726)
		(stroke
			(width 0.2032)
			(type default)
		)
		(layer "In3.Cu")
	)
	(gr_line
		(start 323.9516 -9.3726)
		(end 322.7578 -9.3726)
		(stroke
			(width 0.2032)
			(type default)
		)
		(layer "In3.Cu")
	)
	(gr_line
		(start 324.0024 -11.303)
		(end 324.0024 -9.2964)
		(stroke
			(width 0.1016)
			(type default)
		)
		(layer "In3.Cu")
	)
	(gr_line
		(start 324.0024 -9.2964)
		(end 322.707 -9.2964)
		(stroke
			(width 0.1016)
			(type default)
		)
		(layer "In3.Cu")
	)
	(gr_line
		(start 324.100698 -11.2268)
		(end 323.85 -11.2268)
		(stroke
			(width 0.254)
			(type default)
		)
		(layer "In3.Cu")
	)
	(gr_line
		(start 324.100698 -9.3726)
		(end 324.100698 -11.2268)
		(stroke
			(width 0.254)
			(type default)
		)
		(layer "In3.Cu")
	)
	(gr_line
		(start 324.126098 -11.3538)
		(end 322.652898 -11.3538)
		(stroke
			(width 0.254)
			(type default)
		)
		(layer "In3.Cu")
	)
	(gr_line
		(start 324.126098 -9.2456)
		(end 324.126098 -11.3538)
		(stroke
			(width 0.254)
			(type default)
		)
		(layer "In3.Cu")
	)
	(gr_line
		(start 324.151498 -11.3792)
		(end 322.602098 -11.3792)
		(stroke
			(width 0.254)
			(type default)
		)
		(layer "In3.Cu")
	)
	(gr_line
		(start 324.151498 -9.1948)
		(end 324.151498 -11.3792)
		(stroke
			(width 0.254)
			(type default)
		)
		(layer "In3.Cu")
	)
	(gr_line
		(start 327.37679 -11.3792)
		(end 327.37679 -9.1948)
		(stroke
			(width 0.254)
			(type default)
		)
		(layer "In3.Cu")
	)
	(gr_line
		(start 327.37679 -9.1948)
		(end 328.95159 -9.1948)
		(stroke
			(width 0.254)
			(type default)
		)
		(layer "In3.Cu")
	)
	(gr_line
		(start 327.40219 -11.3792)
		(end 327.40219 -9.2456)
		(stroke
			(width 0.254)
			(type default)
		)
		(layer "In3.Cu")
	)
	(gr_line
		(start 327.40219 -9.2456)
		(end 328.92619 -9.2456)
		(stroke
			(width 0.254)
			(type default)
		)
		(layer "In3.Cu")
	)
	(gr_line
		(start 327.45299 -11.3538)
		(end 327.45299 -9.3726)
		(stroke
			(width 0.254)
			(type default)
		)
		(layer "In3.Cu")
	)
	(gr_line
		(start 327.45299 -9.3726)
		(end 328.90079 -9.3726)
		(stroke
			(width 0.254)
			(type default)
		)
		(layer "In3.Cu")
	)
	(gr_line
		(start 327.507092 -11.303)
		(end 327.811892 -11.303)
		(stroke
			(width 0.1016)
			(type default)
		)
		(layer "In3.Cu")
	)
	(gr_line
		(start 327.507092 -9.2964)
		(end 327.507092 -11.303)
		(stroke
			(width 0.1016)
			(type default)
		)
		(layer "In3.Cu")
	)
	(gr_line
		(start 327.557892 -11.2268)
		(end 328.650092 -11.2268)
		(stroke
			(width 0.2032)
			(type default)
		)
		(layer "In3.Cu")
	)
	(gr_line
		(start 327.557892 -9.3726)
		(end 327.557892 -11.2268)
		(stroke
			(width 0.2032)
			(type default)
		)
		(layer "In3.Cu")
	)
	(gr_line
		(start 327.583292 -11.2268)
		(end 328.751692 -11.2268)
		(stroke
			(width 0.2032)
			(type default)
		)
		(layer "In3.Cu")
	)
	(gr_line
		(start 327.583292 -9.4234)
		(end 327.583292 -11.2268)
		(stroke
			(width 0.2032)
			(type default)
		)
		(layer "In3.Cu")
	)
	(gr_line
		(start 327.63079 -11.1252)
		(end 327.63079 -9.5758)
		(stroke
			(width 0.762)
			(type default)
		)
		(layer "In3.Cu")
	)
	(gr_line
		(start 327.63079 -11.1252)
		(end 328.54519 -11.1252)
		(stroke
			(width 0.762)
			(type default)
		)
		(layer "In3.Cu")
	)
	(gr_line
		(start 327.63079 -11.0998)
		(end 327.63079 -9.5504)
		(stroke
			(width 0.762)
			(type default)
		)
		(layer "In3.Cu")
	)
	(gr_line
		(start 327.63079 -10.9982)
		(end 327.63079 -9.4488)
		(stroke
			(width 0.762)
			(type default)
		)
		(layer "In3.Cu")
	)
	(gr_line
		(start 327.63079 -9.4488)
		(end 328.54519 -9.4488)
		(stroke
			(width 0.762)
			(type default)
		)
		(layer "In3.Cu")
	)
	(gr_line
		(start 327.634092 -11.176)
		(end 328.726292 -11.176)
		(stroke
			(width 0.2032)
			(type default)
		)
		(layer "In3.Cu")
	)
	(gr_line
		(start 327.634092 -9.4742)
		(end 327.634092 -11.176)
		(stroke
			(width 0.2032)
			(type default)
		)
		(layer "In3.Cu")
	)
	(gr_line
		(start 327.65619 -10.9982)
		(end 328.57059 -10.9982)
		(stroke
			(width 0.762)
			(type default)
		)
		(layer "In3.Cu")
	)
	(gr_line
		(start 327.65619 -9.5758)
		(end 328.57059 -9.5758)
		(stroke
			(width 0.762)
			(type default)
		)
		(layer "In3.Cu")
	)
	(gr_line
		(start 327.735692 -11.0744)
		(end 328.523092 -11.0744)
		(stroke
			(width 0.508)
			(type default)
		)
		(layer "In3.Cu")
	)
	(gr_line
		(start 327.735692 -11.049)
		(end 327.735692 -9.525)
		(stroke
			(width 0.508)
			(type default)
		)
		(layer "In3.Cu")
	)
	(gr_line
		(start 327.761092 -11.0744)
		(end 327.761092 -9.5504)
		(stroke
			(width 0.508)
			(type default)
		)
		(layer "In3.Cu")
	)
	(gr_line
		(start 327.78319 -11.1252)
		(end 328.69759 -11.1252)
		(stroke
			(width 0.762)
			(type default)
		)
		(layer "In3.Cu")
	)
	(gr_line
		(start 327.78319 -9.4488)
		(end 328.69759 -9.4488)
		(stroke
			(width 0.762)
			(type default)
		)
		(layer "In3.Cu")
	)
	(gr_line
		(start 327.786492 -9.525)
		(end 328.523092 -9.525)
		(stroke
			(width 0.508)
			(type default)
		)
		(layer "In3.Cu")
	)
	(gr_line
		(start 327.811892 -11.303)
		(end 328.802492 -11.303)
		(stroke
			(width 0.1016)
			(type default)
		)
		(layer "In3.Cu")
	)
	(gr_line
		(start 327.811892 -11.0744)
		(end 327.811892 -9.5504)
		(stroke
			(width 0.508)
			(type default)
		)
		(layer "In3.Cu")
	)
	(gr_line
		(start 327.837292 -11.0744)
		(end 327.837292 -9.5504)
		(stroke
			(width 0.508)
			(type default)
		)
		(layer "In3.Cu")
	)
	(gr_line
		(start 327.862692 -11.0744)
		(end 327.862692 -9.5504)
		(stroke
			(width 0.508)
			(type default)
		)
		(layer "In3.Cu")
	)
	(gr_line
		(start 327.888092 -11.0744)
		(end 327.888092 -9.5504)
		(stroke
			(width 0.508)
			(type default)
		)
		(layer "In3.Cu")
	)
	(gr_line
		(start 327.888092 -11.049)
		(end 327.888092 -9.525)
		(stroke
			(width 0.508)
			(type default)
		)
		(layer "In3.Cu")
	)
	(gr_line
		(start 327.913492 -11.0744)
		(end 327.913492 -9.5504)
		(stroke
			(width 0.508)
			(type default)
		)
		(layer "In3.Cu")
	)
	(gr_line
		(start 327.938892 -11.0744)
		(end 327.938892 -9.5504)
		(stroke
			(width 0.508)
			(type default)
		)
		(layer "In3.Cu")
	)
	(gr_line
		(start 327.989692 -11.0744)
		(end 327.989692 -9.5504)
		(stroke
			(width 0.508)
			(type default)
		)
		(layer "In3.Cu")
	)
	(gr_line
		(start 327.989692 -11.049)
		(end 327.989692 -9.525)
		(stroke
			(width 0.508)
			(type default)
		)
		(layer "In3.Cu")
	)
	(gr_line
		(start 328.015092 -11.0744)
		(end 328.015092 -9.5504)
		(stroke
			(width 0.508)
			(type default)
		)
		(layer "In3.Cu")
	)
	(gr_line
		(start 328.040492 -11.0744)
		(end 328.040492 -9.5504)
		(stroke
			(width 0.508)
			(type default)
		)
		(layer "In3.Cu")
	)
	(gr_line
		(start 328.065892 -11.0744)
		(end 328.065892 -9.5504)
		(stroke
			(width 0.508)
			(type default)
		)
		(layer "In3.Cu")
	)
	(gr_line
		(start 328.116692 -11.0744)
		(end 328.116692 -9.5504)
		(stroke
			(width 0.508)
			(type default)
		)
		(layer "In3.Cu")
	)
	(gr_line
		(start 328.142092 -11.0744)
		(end 328.142092 -9.5504)
		(stroke
			(width 0.508)
			(type default)
		)
		(layer "In3.Cu")
	)
	(gr_line
		(start 328.142092 -11.049)
		(end 328.142092 -9.525)
		(stroke
			(width 0.508)
			(type default)
		)
		(layer "In3.Cu")
	)
	(gr_line
		(start 328.167492 -11.0744)
		(end 328.167492 -9.5504)
		(stroke
			(width 0.508)
			(type default)
		)
		(layer "In3.Cu")
	)
	(gr_line
		(start 328.192892 -11.0744)
		(end 328.192892 -9.5504)
		(stroke
			(width 0.508)
			(type default)
		)
		(layer "In3.Cu")
	)
	(gr_line
		(start 328.218292 -11.0744)
		(end 328.218292 -9.5504)
		(stroke
			(width 0.508)
			(type default)
		)
		(layer "In3.Cu")
	)
	(gr_line
		(start 328.218292 -11.049)
		(end 328.218292 -9.525)
		(stroke
			(width 0.508)
			(type default)
		)
		(layer "In3.Cu")
	)
	(gr_line
		(start 328.243692 -11.0744)
		(end 328.243692 -9.5504)
		(stroke
			(width 0.508)
			(type default)
		)
		(layer "In3.Cu")
	)
	(gr_line
		(start 328.269092 -11.0744)
		(end 328.269092 -9.5504)
		(stroke
			(width 0.508)
			(type default)
		)
		(layer "In3.Cu")
	)
	(gr_line
		(start 328.269092 -11.049)
		(end 328.269092 -9.525)
		(stroke
			(width 0.508)
			(type default)
		)
		(layer "In3.Cu")
	)
	(gr_line
		(start 328.294492 -11.0744)
		(end 328.294492 -9.5504)
		(stroke
			(width 0.508)
			(type default)
		)
		(layer "In3.Cu")
	)
	(gr_line
		(start 328.294492 -11.049)
		(end 328.294492 -9.525)
		(stroke
			(width 0.508)
			(type default)
		)
		(layer "In3.Cu")
	)
	(gr_line
		(start 328.319892 -11.049)
		(end 328.319892 -9.525)
		(stroke
			(width 0.508)
			(type default)
		)
		(layer "In3.Cu")
	)
	(gr_line
		(start 328.345292 -11.0744)
		(end 328.345292 -9.5504)
		(stroke
			(width 0.508)
			(type default)
		)
		(layer "In3.Cu")
	)
	(gr_line
		(start 328.36739 -11.3792)
		(end 327.37679 -11.3792)
		(stroke
			(width 0.254)
			(type default)
		)
		(layer "In3.Cu")
	)
	(gr_line
		(start 328.370692 -11.049)
		(end 328.370692 -9.525)
		(stroke
			(width 0.508)
			(type default)
		)
		(layer "In3.Cu")
	)
	(gr_line
		(start 328.396092 -11.049)
		(end 328.396092 -9.525)
		(stroke
			(width 0.508)
			(type default)
		)
		(layer "In3.Cu")
	)
	(gr_line
		(start 328.421492 -11.0744)
		(end 328.421492 -9.5504)
		(stroke
			(width 0.508)
			(type default)
		)
		(layer "In3.Cu")
	)
	(gr_line
		(start 328.446892 -11.0744)
		(end 328.446892 -9.5504)
		(stroke
			(width 0.508)
			(type default)
		)
		(layer "In3.Cu")
	)
	(gr_line
		(start 328.446892 -11.049)
		(end 328.446892 -9.525)
		(stroke
			(width 0.508)
			(type default)
		)
		(layer "In3.Cu")
	)
	(gr_line
		(start 328.497692 -11.0744)
		(end 328.497692 -9.5504)
		(stroke
			(width 0.508)
			(type default)
		)
		(layer "In3.Cu")
	)
	(gr_line
		(start 328.497692 -11.049)
		(end 328.497692 -9.525)
		(stroke
			(width 0.508)
			(type default)
		)
		(layer "In3.Cu")
	)
	(gr_line
		(start 328.548492 -11.0744)
		(end 328.548492 -9.5504)
		(stroke
			(width 0.508)
			(type default)
		)
		(layer "In3.Cu")
	)
	(gr_line
		(start 328.548492 -11.049)
		(end 328.548492 -9.525)
		(stroke
			(width 0.508)
			(type default)
		)
		(layer "In3.Cu")
	)
	(gr_line
		(start 328.57059 -11.0998)
		(end 328.57059 -9.5504)
		(stroke
			(width 0.762)
			(type default)
		)
		(layer "In3.Cu")
	)
	(gr_line
		(start 328.573892 -11.0744)
		(end 328.573892 -9.5504)
		(stroke
			(width 0.508)
			(type default)
		)
		(layer "In3.Cu")
	)
	(gr_line
		(start 328.599292 -11.0744)
		(end 328.599292 -9.5504)
		(stroke
			(width 0.508)
			(type default)
		)
		(layer "In3.Cu")
	)
	(gr_line
		(start 328.650092 -11.2268)
		(end 328.675492 -11.2268)
		(stroke
			(width 0.2032)
			(type default)
		)
		(layer "In3.Cu")
	)
	(gr_line
		(start 328.675492 -11.2268)
		(end 328.675492 -9.4742)
		(stroke
			(width 0.2032)
			(type default)
		)
		(layer "In3.Cu")
	)
	(gr_line
		(start 328.675492 -9.4742)
		(end 327.634092 -9.4742)
		(stroke
			(width 0.2032)
			(type default)
		)
		(layer "In3.Cu")
	)
	(gr_line
		(start 328.69759 -11.1252)
		(end 328.69759 -9.5758)
		(stroke
			(width 0.762)
			(type default)
		)
		(layer "In3.Cu")
	)
	(gr_line
		(start 328.69759 -11.0998)
		(end 328.69759 -9.6012)
		(stroke
			(width 0.762)
			(type default)
		)
		(layer "In3.Cu")
	)
	(gr_line
		(start 328.69759 -10.9982)
		(end 328.69759 -9.4488)
		(stroke
			(width 0.762)
			(type default)
		)
		(layer "In3.Cu")
	)
	(gr_line
		(start 328.726292 -11.176)
		(end 328.726292 -9.4234)
		(stroke
			(width 0.2032)
			(type default)
		)
		(layer "In3.Cu")
	)
	(gr_line
		(start 328.726292 -9.4234)
		(end 327.583292 -9.4234)
		(stroke
			(width 0.2032)
			(type default)
		)
		(layer "In3.Cu")
	)
	(gr_line
		(start 328.751692 -11.2268)
		(end 328.751692 -9.3726)
		(stroke
			(width 0.2032)
			(type default)
		)
		(layer "In3.Cu")
	)
	(gr_line
		(start 328.751692 -9.3726)
		(end 327.557892 -9.3726)
		(stroke
			(width 0.2032)
			(type default)
		)
		(layer "In3.Cu")
	)
	(gr_line
		(start 328.802492 -11.303)
		(end 328.802492 -9.2964)
		(stroke
			(width 0.1016)
			(type default)
		)
		(layer "In3.Cu")
	)
	(gr_line
		(start 328.802492 -9.2964)
		(end 327.507092 -9.2964)
		(stroke
			(width 0.1016)
			(type default)
		)
		(layer "In3.Cu")
	)
	(gr_line
		(start 328.90079 -11.2268)
		(end 328.650092 -11.2268)
		(stroke
			(width 0.254)
			(type default)
		)
		(layer "In3.Cu")
	)
	(gr_line
		(start 328.90079 -9.3726)
		(end 328.90079 -11.2268)
		(stroke
			(width 0.254)
			(type default)
		)
		(layer "In3.Cu")
	)
	(gr_line
		(start 328.92619 -11.3538)
		(end 327.45299 -11.3538)
		(stroke
			(width 0.254)
			(type default)
		)
		(layer "In3.Cu")
	)
	(gr_line
		(start 328.92619 -9.2456)
		(end 328.92619 -11.3538)
		(stroke
			(width 0.254)
			(type default)
		)
		(layer "In3.Cu")
	)
	(gr_line
		(start 328.95159 -11.3792)
		(end 327.40219 -11.3792)
		(stroke
			(width 0.254)
			(type default)
		)
		(layer "In3.Cu")
	)
	(gr_line
		(start 328.95159 -9.1948)
		(end 328.95159 -11.3792)
		(stroke
			(width 0.254)
			(type default)
		)
		(layer "In3.Cu")
	)
	(gr_line
		(start 333.069946 -49.800002)
		(end 318.069976 -49.800002)
		(stroke
			(width 2.032)
			(type default)
		)
		(layer "In3.Cu")
	)
	(gr_line
		(start 334.069944 -51.319938)
		(end 334.069944 -50.8)
		(stroke
			(width 2.032)
			(type default)
		)
		(layer "In3.Cu")
	)
	(gr_arc
		(start 334.069944 -51.319938)
		(mid 334.362853 -52.027004)
		(end 335.069942 -52.319936)
		(stroke
			(width 2.032)
			(type default)
		)
		(layer "In3.Cu")
	)
	(gr_arc
		(start 334.069944 -50.8)
		(mid 333.777051 -50.092895)
		(end 333.069946 -49.800002)
		(stroke
			(width 2.032)
			(type default)
		)
		(layer "In3.Cu")
	)
	(gr_line
		(start 334.761586 -9.1948)
		(end 336.183986 -9.1948)
		(stroke
			(width 1.016)
			(type default)
		)
		(layer "In3.Cu")
	)
	(gr_line
		(start 338.856066 -13.843)
		(end 339.694266 -13.843)
		(stroke
			(width 0.1016)
			(type default)
		)
		(layer "In3.Cu")
	)
	(gr_line
		(start 338.856066 -11.1252)
		(end 338.856066 -13.843)
		(stroke
			(width 0.1016)
			(type default)
		)
		(layer "In3.Cu")
	)
	(gr_line
		(start 338.856066 -9.64311)
		(end 339.694266 -9.64311)
		(stroke
			(width 0.1016)
			(type default)
		)
		(layer "In3.Cu")
	)
	(gr_line
		(start 338.856066 -6.92531)
		(end 338.856066 -9.64311)
		(stroke
			(width 0.1016)
			(type default)
		)
		(layer "In3.Cu")
	)
	(gr_line
		(start 338.881466 -13.8176)
		(end 338.881466 -11.1506)
		(stroke
			(width 0.127)
			(type default)
		)
		(layer "In3.Cu")
	)
	(gr_line
		(start 338.881466 -11.1506)
		(end 340.176866 -11.1506)
		(stroke
			(width 0.127)
			(type default)
		)
		(layer "In3.Cu")
	)
	(gr_line
		(start 338.881466 -9.61771)
		(end 338.881466 -6.95071)
		(stroke
			(width 0.127)
			(type default)
		)
		(layer "In3.Cu")
	)
	(gr_line
		(start 338.881466 -6.95071)
		(end 340.176866 -6.95071)
		(stroke
			(width 0.127)
			(type default)
		)
		(layer "In3.Cu")
	)
	(gr_line
		(start 338.906866 -13.8176)
		(end 338.906866 -11.176)
		(stroke
			(width 0.127)
			(type default)
		)
		(layer "In3.Cu")
	)
	(gr_line
		(start 338.906866 -13.7922)
		(end 338.906866 -11.176)
		(stroke
			(width 0.1778)
			(type default)
		)
		(layer "In3.Cu")
	)
	(gr_line
		(start 338.906866 -11.176)
		(end 340.151466 -11.176)
		(stroke
			(width 0.127)
			(type default)
		)
		(layer "In3.Cu")
	)
	(gr_line
		(start 338.906866 -11.176)
		(end 340.151466 -11.176)
		(stroke
			(width 0.1778)
			(type default)
		)
		(layer "In3.Cu")
	)
	(gr_line
		(start 338.906866 -9.61771)
		(end 338.906866 -6.97611)
		(stroke
			(width 0.127)
			(type default)
		)
		(layer "In3.Cu")
	)
	(gr_line
		(start 338.906866 -9.59231)
		(end 338.906866 -6.97611)
		(stroke
			(width 0.1778)
			(type default)
		)
		(layer "In3.Cu")
	)
	(gr_line
		(start 338.906866 -6.97611)
		(end 340.151466 -6.97611)
		(stroke
			(width 0.127)
			(type default)
		)
		(layer "In3.Cu")
	)
	(gr_line
		(start 338.906866 -6.97611)
		(end 340.151466 -6.97611)
		(stroke
			(width 0.1778)
			(type default)
		)
		(layer "In3.Cu")
	)
	(gr_line
		(start 338.932266 -13.7922)
		(end 338.932266 -11.2014)
		(stroke
			(width 0.1778)
			(type default)
		)
		(layer "In3.Cu")
	)
	(gr_line
		(start 338.932266 -11.2014)
		(end 340.126066 -11.2014)
		(stroke
			(width 0.1778)
			(type default)
		)
		(layer "In3.Cu")
	)
	(gr_line
		(start 338.932266 -9.59231)
		(end 338.932266 -7.00151)
		(stroke
			(width 0.1778)
			(type default)
		)
		(layer "In3.Cu")
	)
	(gr_line
		(start 338.932266 -7.00151)
		(end 340.126066 -7.00151)
		(stroke
			(width 0.1778)
			(type default)
		)
		(layer "In3.Cu")
	)
	(gr_line
		(start 338.957666 -13.7668)
		(end 338.957666 -11.2268)
		(stroke
			(width 0.254)
			(type default)
		)
		(layer "In3.Cu")
	)
	(gr_line
		(start 338.957666 -11.2268)
		(end 340.126066 -11.2268)
		(stroke
			(width 0.254)
			(type default)
		)
		(layer "In3.Cu")
	)
	(gr_line
		(start 338.957666 -9.56691)
		(end 338.957666 -7.02691)
		(stroke
			(width 0.254)
			(type default)
		)
		(layer "In3.Cu")
	)
	(gr_line
		(start 338.957666 -7.02691)
		(end 340.126066 -7.02691)
		(stroke
			(width 0.254)
			(type default)
		)
		(layer "In3.Cu")
	)
	(gr_line
		(start 338.983066 -13.7668)
		(end 338.983066 -11.2522)
		(stroke
			(width 0.254)
			(type default)
		)
		(layer "In3.Cu")
	)
	(gr_line
		(start 338.983066 -11.2522)
		(end 340.100666 -11.2522)
		(stroke
			(width 0.254)
			(type default)
		)
		(layer "In3.Cu")
	)
	(gr_line
		(start 338.983066 -9.56691)
		(end 338.983066 -7.05231)
		(stroke
			(width 0.254)
			(type default)
		)
		(layer "In3.Cu")
	)
	(gr_line
		(start 338.983066 -7.05231)
		(end 340.100666 -7.05231)
		(stroke
			(width 0.254)
			(type default)
		)
		(layer "In3.Cu")
	)
	(gr_line
		(start 339.008466 -13.716)
		(end 339.008466 -11.2776)
		(stroke
			(width 0.3556)
			(type default)
		)
		(layer "In3.Cu")
	)
	(gr_line
		(start 339.008466 -11.2776)
		(end 340.049866 -11.2776)
		(stroke
			(width 0.3556)
			(type default)
		)
		(layer "In3.Cu")
	)
	(gr_line
		(start 339.008466 -9.51611)
		(end 339.008466 -7.07771)
		(stroke
			(width 0.3556)
			(type default)
		)
		(layer "In3.Cu")
	)
	(gr_line
		(start 339.008466 -7.07771)
		(end 340.049866 -7.07771)
		(stroke
			(width 0.3556)
			(type default)
		)
		(layer "In3.Cu")
	)
	(gr_line
		(start 339.059266 -13.6906)
		(end 339.059266 -11.3284)
		(stroke
			(width 0.381)
			(type default)
		)
		(layer "In3.Cu")
	)
	(gr_line
		(start 339.059266 -11.3284)
		(end 339.999066 -11.3284)
		(stroke
			(width 0.381)
			(type default)
		)
		(layer "In3.Cu")
	)
	(gr_line
		(start 339.059266 -9.49071)
		(end 339.059266 -7.12851)
		(stroke
			(width 0.381)
			(type default)
		)
		(layer "In3.Cu")
	)
	(gr_line
		(start 339.059266 -7.12851)
		(end 339.999066 -7.12851)
		(stroke
			(width 0.381)
			(type default)
		)
		(layer "In3.Cu")
	)
	(gr_line
		(start 339.135466 -13.6398)
		(end 339.135466 -11.3792)
		(stroke
			(width 0.381)
			(type default)
		)
		(layer "In3.Cu")
	)
	(gr_line
		(start 339.135466 -11.3792)
		(end 339.948266 -11.3792)
		(stroke
			(width 0.381)
			(type default)
		)
		(layer "In3.Cu")
	)
	(gr_line
		(start 339.135466 -9.43991)
		(end 339.135466 -7.17931)
		(stroke
			(width 0.381)
			(type default)
		)
		(layer "In3.Cu")
	)
	(gr_line
		(start 339.135466 -7.17931)
		(end 339.948266 -7.17931)
		(stroke
			(width 0.381)
			(type default)
		)
		(layer "In3.Cu")
	)
	(gr_line
		(start 339.160866 -13.5636)
		(end 339.160866 -11.3792)
		(stroke
			(width 0.508)
			(type default)
		)
		(layer "In3.Cu")
	)
	(gr_line
		(start 339.160866 -11.3792)
		(end 339.922866 -11.3792)
		(stroke
			(width 0.508)
			(type default)
		)
		(layer "In3.Cu")
	)
	(gr_line
		(start 339.160866 -9.36371)
		(end 339.160866 -7.17931)
		(stroke
			(width 0.508)
			(type default)
		)
		(layer "In3.Cu")
	)
	(gr_line
		(start 339.160866 -7.17931)
		(end 339.922866 -7.17931)
		(stroke
			(width 0.508)
			(type default)
		)
		(layer "In3.Cu")
	)
	(gr_line
		(start 339.186266 -13.4112)
		(end 339.770466 -13.4112)
		(stroke
			(width 0.762)
			(type default)
		)
		(layer "In3.Cu")
	)
	(gr_line
		(start 339.186266 -11.5824)
		(end 339.770466 -11.5824)
		(stroke
			(width 0.762)
			(type default)
		)
		(layer "In3.Cu")
	)
	(gr_line
		(start 339.186266 -9.21131)
		(end 339.770466 -9.21131)
		(stroke
			(width 0.762)
			(type default)
		)
		(layer "In3.Cu")
	)
	(gr_line
		(start 339.186266 -7.38251)
		(end 339.770466 -7.38251)
		(stroke
			(width 0.762)
			(type default)
		)
		(layer "In3.Cu")
	)
	(gr_line
		(start 339.211666 -13.5636)
		(end 339.211666 -11.43)
		(stroke
			(width 0.635)
			(type default)
		)
		(layer "In3.Cu")
	)
	(gr_line
		(start 339.211666 -13.5128)
		(end 339.211666 -11.4808)
		(stroke
			(width 0.762)
			(type default)
		)
		(layer "In3.Cu")
	)
	(gr_line
		(start 339.211666 -11.43)
		(end 339.897466 -11.43)
		(stroke
			(width 0.635)
			(type default)
		)
		(layer "In3.Cu")
	)
	(gr_line
		(start 339.211666 -9.36371)
		(end 339.211666 -7.23011)
		(stroke
			(width 0.635)
			(type default)
		)
		(layer "In3.Cu")
	)
	(gr_line
		(start 339.211666 -9.31291)
		(end 339.211666 -7.28091)
		(stroke
			(width 0.762)
			(type default)
		)
		(layer "In3.Cu")
	)
	(gr_line
		(start 339.211666 -7.23011)
		(end 339.897466 -7.23011)
		(stroke
			(width 0.635)
			(type default)
		)
		(layer "In3.Cu")
	)
	(gr_line
		(start 339.237066 -13.5128)
		(end 339.237066 -11.4808)
		(stroke
			(width 0.762)
			(type default)
		)
		(layer "In3.Cu")
	)
	(gr_line
		(start 339.237066 -11.4808)
		(end 339.821266 -11.4808)
		(stroke
			(width 0.762)
			(type default)
		)
		(layer "In3.Cu")
	)
	(gr_line
		(start 339.237066 -9.31291)
		(end 339.237066 -7.28091)
		(stroke
			(width 0.762)
			(type default)
		)
		(layer "In3.Cu")
	)
	(gr_line
		(start 339.237066 -7.28091)
		(end 339.821266 -7.28091)
		(stroke
			(width 0.762)
			(type default)
		)
		(layer "In3.Cu")
	)
	(gr_line
		(start 339.262466 -13.5128)
		(end 339.262466 -11.4808)
		(stroke
			(width 0.762)
			(type default)
		)
		(layer "In3.Cu")
	)
	(gr_line
		(start 339.262466 -13.5128)
		(end 339.846666 -13.5128)
		(stroke
			(width 0.762)
			(type default)
		)
		(layer "In3.Cu")
	)
	(gr_line
		(start 339.262466 -13.4874)
		(end 339.262466 -11.4554)
		(stroke
			(width 0.762)
			(type default)
		)
		(layer "In3.Cu")
	)
	(gr_line
		(start 339.262466 -9.31291)
		(end 339.262466 -7.28091)
		(stroke
			(width 0.762)
			(type default)
		)
		(layer "In3.Cu")
	)
	(gr_line
		(start 339.262466 -9.31291)
		(end 339.846666 -9.31291)
		(stroke
			(width 0.762)
			(type default)
		)
		(layer "In3.Cu")
	)
	(gr_line
		(start 339.262466 -9.28751)
		(end 339.262466 -7.25551)
		(stroke
			(width 0.762)
			(type default)
		)
		(layer "In3.Cu")
	)
	(gr_line
		(start 339.287866 -13.5128)
		(end 339.287866 -11.4808)
		(stroke
			(width 0.762)
			(type default)
		)
		(layer "In3.Cu")
	)
	(gr_line
		(start 339.287866 -9.31291)
		(end 339.287866 -7.28091)
		(stroke
			(width 0.762)
			(type default)
		)
		(layer "In3.Cu")
	)
	(gr_line
		(start 339.313266 -13.5128)
		(end 339.313266 -11.4808)
		(stroke
			(width 0.762)
			(type default)
		)
		(layer "In3.Cu")
	)
	(gr_line
		(start 339.313266 -9.31291)
		(end 339.313266 -7.28091)
		(stroke
			(width 0.762)
			(type default)
		)
		(layer "In3.Cu")
	)
	(gr_line
		(start 339.338666 -13.5128)
		(end 339.338666 -11.4808)
		(stroke
			(width 0.762)
			(type default)
		)
		(layer "In3.Cu")
	)
	(gr_line
		(start 339.338666 -9.31291)
		(end 339.338666 -7.28091)
		(stroke
			(width 0.762)
			(type default)
		)
		(layer "In3.Cu")
	)
	(gr_line
		(start 339.389466 -13.5128)
		(end 339.389466 -11.4808)
		(stroke
			(width 0.762)
			(type default)
		)
		(layer "In3.Cu")
	)
	(gr_line
		(start 339.389466 -9.31291)
		(end 339.389466 -7.28091)
		(stroke
			(width 0.762)
			(type default)
		)
		(layer "In3.Cu")
	)
	(gr_line
		(start 339.414866 -13.5128)
		(end 339.414866 -11.4808)
		(stroke
			(width 0.762)
			(type default)
		)
		(layer "In3.Cu")
	)
	(gr_line
		(start 339.414866 -9.31291)
		(end 339.414866 -7.28091)
		(stroke
			(width 0.762)
			(type default)
		)
		(layer "In3.Cu")
	)
	(gr_line
		(start 339.440266 -13.5128)
		(end 339.440266 -11.7094)
		(stroke
			(width 0.635)
			(type default)
		)
		(layer "In3.Cu")
	)
	(gr_line
		(start 339.440266 -11.7094)
		(end 339.541866 -11.7094)
		(stroke
			(width 0.635)
			(type default)
		)
		(layer "In3.Cu")
	)
	(gr_line
		(start 339.440266 -9.31291)
		(end 339.440266 -7.50951)
		(stroke
			(width 0.635)
			(type default)
		)
		(layer "In3.Cu")
	)
	(gr_line
		(start 339.440266 -7.50951)
		(end 339.541866 -7.50951)
		(stroke
			(width 0.635)
			(type default)
		)
		(layer "In3.Cu")
	)
	(gr_line
		(start 339.465666 -13.5128)
		(end 339.465666 -11.4808)
		(stroke
			(width 0.762)
			(type default)
		)
		(layer "In3.Cu")
	)
	(gr_line
		(start 339.465666 -13.4874)
		(end 339.465666 -11.4554)
		(stroke
			(width 0.762)
			(type default)
		)
		(layer "In3.Cu")
	)
	(gr_line
		(start 339.465666 -13.4366)
		(end 339.465666 -11.6586)
		(stroke
			(width 0.635)
			(type default)
		)
		(layer "In3.Cu")
	)
	(gr_line
		(start 339.465666 -9.31291)
		(end 339.465666 -7.28091)
		(stroke
			(width 0.762)
			(type default)
		)
		(layer "In3.Cu")
	)
	(gr_line
		(start 339.465666 -9.28751)
		(end 339.465666 -7.25551)
		(stroke
			(width 0.762)
			(type default)
		)
		(layer "In3.Cu")
	)
	(gr_line
		(start 339.465666 -9.23671)
		(end 339.465666 -7.45871)
		(stroke
			(width 0.635)
			(type default)
		)
		(layer "In3.Cu")
	)
	(gr_line
		(start 339.516466 -13.5128)
		(end 339.516466 -11.4808)
		(stroke
			(width 0.762)
			(type default)
		)
		(layer "In3.Cu")
	)
	(gr_line
		(start 339.516466 -9.31291)
		(end 339.516466 -7.28091)
		(stroke
			(width 0.762)
			(type default)
		)
		(layer "In3.Cu")
	)
	(gr_line
		(start 339.541866 -13.5128)
		(end 339.541866 -11.4808)
		(stroke
			(width 0.762)
			(type default)
		)
		(layer "In3.Cu")
	)
	(gr_line
		(start 339.541866 -13.4874)
		(end 339.541866 -11.4554)
		(stroke
			(width 0.762)
			(type default)
		)
		(layer "In3.Cu")
	)
	(gr_line
		(start 339.541866 -13.4366)
		(end 339.465666 -13.4366)
		(stroke
			(width 0.635)
			(type default)
		)
		(layer "In3.Cu")
	)
	(gr_line
		(start 339.541866 -11.7094)
		(end 339.541866 -13.4366)
		(stroke
			(width 0.635)
			(type default)
		)
		(layer "In3.Cu")
	)
	(gr_line
		(start 339.541866 -9.31291)
		(end 339.541866 -7.28091)
		(stroke
			(width 0.762)
			(type default)
		)
		(layer "In3.Cu")
	)
	(gr_line
		(start 339.541866 -9.28751)
		(end 339.541866 -7.25551)
		(stroke
			(width 0.762)
			(type default)
		)
		(layer "In3.Cu")
	)
	(gr_line
		(start 339.541866 -9.23671)
		(end 339.465666 -9.23671)
		(stroke
			(width 0.635)
			(type default)
		)
		(layer "In3.Cu")
	)
	(gr_line
		(start 339.541866 -7.50951)
		(end 339.541866 -9.23671)
		(stroke
			(width 0.635)
			(type default)
		)
		(layer "In3.Cu")
	)
	(gr_line
		(start 339.592666 -13.4874)
		(end 339.592666 -11.4554)
		(stroke
			(width 0.762)
			(type default)
		)
		(layer "In3.Cu")
	)
	(gr_line
		(start 339.592666 -9.28751)
		(end 339.592666 -7.25551)
		(stroke
			(width 0.762)
			(type default)
		)
		(layer "In3.Cu")
	)
	(gr_line
		(start 339.618066 -13.4874)
		(end 339.618066 -11.4554)
		(stroke
			(width 0.762)
			(type default)
		)
		(layer "In3.Cu")
	)
	(gr_line
		(start 339.618066 -9.28751)
		(end 339.618066 -7.25551)
		(stroke
			(width 0.762)
			(type default)
		)
		(layer "In3.Cu")
	)
	(gr_line
		(start 339.668866 -13.5128)
		(end 339.668866 -11.4808)
		(stroke
			(width 0.762)
			(type default)
		)
		(layer "In3.Cu")
	)
	(gr_line
		(start 339.668866 -9.31291)
		(end 339.668866 -7.28091)
		(stroke
			(width 0.762)
			(type default)
		)
		(layer "In3.Cu")
	)
	(gr_line
		(start 339.694266 -13.843)
		(end 340.202266 -13.843)
		(stroke
			(width 0.1016)
			(type default)
		)
		(layer "In3.Cu")
	)
	(gr_line
		(start 339.694266 -13.4874)
		(end 339.694266 -11.4554)
		(stroke
			(width 0.762)
			(type default)
		)
		(layer "In3.Cu")
	)
	(gr_line
		(start 339.694266 -9.64311)
		(end 340.202266 -9.64311)
		(stroke
			(width 0.1016)
			(type default)
		)
		(layer "In3.Cu")
	)
	(gr_line
		(start 339.694266 -9.28751)
		(end 339.694266 -7.25551)
		(stroke
			(width 0.762)
			(type default)
		)
		(layer "In3.Cu")
	)
	(gr_line
		(start 339.745066 -13.5128)
		(end 339.745066 -11.4808)
		(stroke
			(width 0.762)
			(type default)
		)
		(layer "In3.Cu")
	)
	(gr_line
		(start 339.745066 -13.4874)
		(end 339.745066 -11.4554)
		(stroke
			(width 0.762)
			(type default)
		)
		(layer "In3.Cu")
	)
	(gr_line
		(start 339.745066 -9.31291)
		(end 339.745066 -7.28091)
		(stroke
			(width 0.762)
			(type default)
		)
		(layer "In3.Cu")
	)
	(gr_line
		(start 339.745066 -9.28751)
		(end 339.745066 -7.25551)
		(stroke
			(width 0.762)
			(type default)
		)
		(layer "In3.Cu")
	)
	(gr_line
		(start 339.770466 -13.4874)
		(end 339.770466 -11.4554)
		(stroke
			(width 0.762)
			(type default)
		)
		(layer "In3.Cu")
	)
	(gr_line
		(start 339.770466 -9.28751)
		(end 339.770466 -7.25551)
		(stroke
			(width 0.762)
			(type default)
		)
		(layer "In3.Cu")
	)
	(gr_line
		(start 339.795866 -13.5636)
		(end 339.160866 -13.5636)
		(stroke
			(width 0.508)
			(type default)
		)
		(layer "In3.Cu")
	)
	(gr_line
		(start 339.795866 -13.5636)
		(end 339.211666 -13.5636)
		(stroke
			(width 0.635)
			(type default)
		)
		(layer "In3.Cu")
	)
	(gr_line
		(start 339.795866 -9.36371)
		(end 339.160866 -9.36371)
		(stroke
			(width 0.508)
			(type default)
		)
		(layer "In3.Cu")
	)
	(gr_line
		(start 339.795866 -9.36371)
		(end 339.211666 -9.36371)
		(stroke
			(width 0.635)
			(type default)
		)
		(layer "In3.Cu")
	)
	(gr_line
		(start 339.821266 -13.4874)
		(end 339.821266 -11.4554)
		(stroke
			(width 0.762)
			(type default)
		)
		(layer "In3.Cu")
	)
	(gr_line
		(start 339.821266 -9.28751)
		(end 339.821266 -7.25551)
		(stroke
			(width 0.762)
			(type default)
		)
		(layer "In3.Cu")
	)
	(gr_line
		(start 339.846666 -13.716)
		(end 339.008466 -13.716)
		(stroke
			(width 0.3556)
			(type default)
		)
		(layer "In3.Cu")
	)
	(gr_line
		(start 339.846666 -13.6906)
		(end 339.059266 -13.6906)
		(stroke
			(width 0.381)
			(type default)
		)
		(layer "In3.Cu")
	)
	(gr_line
		(start 339.846666 -9.51611)
		(end 339.008466 -9.51611)
		(stroke
			(width 0.3556)
			(type default)
		)
		(layer "In3.Cu")
	)
	(gr_line
		(start 339.846666 -9.49071)
		(end 339.059266 -9.49071)
		(stroke
			(width 0.381)
			(type default)
		)
		(layer "In3.Cu")
	)
	(gr_line
		(start 339.872066 -13.5128)
		(end 339.872066 -11.4808)
		(stroke
			(width 0.762)
			(type default)
		)
		(layer "In3.Cu")
	)
	(gr_line
		(start 339.872066 -9.31291)
		(end 339.872066 -7.28091)
		(stroke
			(width 0.762)
			(type default)
		)
		(layer "In3.Cu")
	)
	(gr_line
		(start 339.897466 -13.7668)
		(end 338.957666 -13.7668)
		(stroke
			(width 0.254)
			(type default)
		)
		(layer "In3.Cu")
	)
	(gr_line
		(start 339.897466 -13.5128)
		(end 339.440266 -13.5128)
		(stroke
			(width 0.635)
			(type default)
		)
		(layer "In3.Cu")
	)
	(gr_line
		(start 339.897466 -11.43)
		(end 339.897466 -13.5128)
		(stroke
			(width 0.635)
			(type default)
		)
		(layer "In3.Cu")
	)
	(gr_line
		(start 339.897466 -9.56691)
		(end 338.957666 -9.56691)
		(stroke
			(width 0.254)
			(type default)
		)
		(layer "In3.Cu")
	)
	(gr_line
		(start 339.897466 -9.31291)
		(end 339.440266 -9.31291)
		(stroke
			(width 0.635)
			(type default)
		)
		(layer "In3.Cu")
	)
	(gr_line
		(start 339.897466 -7.23011)
		(end 339.897466 -9.31291)
		(stroke
			(width 0.635)
			(type default)
		)
		(layer "In3.Cu")
	)
	(gr_line
		(start 339.922866 -13.7922)
		(end 338.906866 -13.7922)
		(stroke
			(width 0.1778)
			(type default)
		)
		(layer "In3.Cu")
	)
	(gr_line
		(start 339.922866 -13.5636)
		(end 339.795866 -13.5636)
		(stroke
			(width 0.508)
			(type default)
		)
		(layer "In3.Cu")
	)
	(gr_line
		(start 339.922866 -11.3792)
		(end 339.922866 -13.5636)
		(stroke
			(width 0.508)
			(type default)
		)
		(layer "In3.Cu")
	)
	(gr_line
		(start 339.922866 -9.59231)
		(end 338.906866 -9.59231)
		(stroke
			(width 0.1778)
			(type default)
		)
		(layer "In3.Cu")
	)
	(gr_line
		(start 339.922866 -9.36371)
		(end 339.795866 -9.36371)
		(stroke
			(width 0.508)
			(type default)
		)
		(layer "In3.Cu")
	)
	(gr_line
		(start 339.922866 -7.17931)
		(end 339.922866 -9.36371)
		(stroke
			(width 0.508)
			(type default)
		)
		(layer "In3.Cu")
	)
	(gr_line
		(start 339.948266 -13.5636)
		(end 339.795866 -13.5636)
		(stroke
			(width 0.381)
			(type default)
		)
		(layer "In3.Cu")
	)
	(gr_line
		(start 339.948266 -11.3792)
		(end 339.948266 -13.5636)
		(stroke
			(width 0.381)
			(type default)
		)
		(layer "In3.Cu")
	)
	(gr_line
		(start 339.948266 -9.36371)
		(end 339.795866 -9.36371)
		(stroke
			(width 0.381)
			(type default)
		)
		(layer "In3.Cu")
	)
	(gr_line
		(start 339.948266 -7.17931)
		(end 339.948266 -9.36371)
		(stroke
			(width 0.381)
			(type default)
		)
		(layer "In3.Cu")
	)
	(gr_line
		(start 339.999066 -13.6398)
		(end 339.135466 -13.6398)
		(stroke
			(width 0.381)
			(type default)
		)
		(layer "In3.Cu")
	)
	(gr_line
		(start 339.999066 -11.3284)
		(end 339.999066 -13.6398)
		(stroke
			(width 0.381)
			(type default)
		)
		(layer "In3.Cu")
	)
	(gr_line
		(start 339.999066 -9.43991)
		(end 339.135466 -9.43991)
		(stroke
			(width 0.381)
			(type default)
		)
		(layer "In3.Cu")
	)
	(gr_line
		(start 339.999066 -7.12851)
		(end 339.999066 -9.43991)
		(stroke
			(width 0.381)
			(type default)
		)
		(layer "In3.Cu")
	)
	(gr_line
		(start 340.049866 -13.6906)
		(end 339.846666 -13.6906)
		(stroke
			(width 0.3556)
			(type default)
		)
		(layer "In3.Cu")
	)
	(gr_line
		(start 340.049866 -11.2776)
		(end 340.049866 -13.6906)
		(stroke
			(width 0.3556)
			(type default)
		)
		(layer "In3.Cu")
	)
	(gr_line
		(start 340.049866 -9.49071)
		(end 339.846666 -9.49071)
		(stroke
			(width 0.3556)
			(type default)
		)
		(layer "In3.Cu")
	)
	(gr_line
		(start 340.049866 -7.07771)
		(end 340.049866 -9.49071)
		(stroke
			(width 0.3556)
			(type default)
		)
		(layer "In3.Cu")
	)
	(gr_line
		(start 340.075266 -13.8176)
		(end 338.881466 -13.8176)
		(stroke
			(width 0.127)
			(type default)
		)
		(layer "In3.Cu")
	)
	(gr_line
		(start 340.075266 -9.61771)
		(end 338.881466 -9.61771)
		(stroke
			(width 0.127)
			(type default)
		)
		(layer "In3.Cu")
	)
	(gr_line
		(start 340.100666 -13.716)
		(end 339.846666 -13.716)
		(stroke
			(width 0.254)
			(type default)
		)
		(layer "In3.Cu")
	)
	(gr_line
		(start 340.100666 -11.2522)
		(end 340.100666 -13.716)
		(stroke
			(width 0.254)
			(type default)
		)
		(layer "In3.Cu")
	)
	(gr_line
		(start 340.100666 -9.51611)
		(end 339.846666 -9.51611)
		(stroke
			(width 0.254)
			(type default)
		)
		(layer "In3.Cu")
	)
	(gr_line
		(start 340.100666 -7.05231)
		(end 340.100666 -9.51611)
		(stroke
			(width 0.254)
			(type default)
		)
		(layer "In3.Cu")
	)
	(gr_line
		(start 340.126066 -13.7668)
		(end 338.983066 -13.7668)
		(stroke
			(width 0.254)
			(type default)
		)
		(layer "In3.Cu")
	)
	(gr_line
		(start 340.126066 -13.7668)
		(end 339.897466 -13.7668)
		(stroke
			(width 0.1778)
			(type default)
		)
		(layer "In3.Cu")
	)
	(gr_line
		(start 340.126066 -11.2268)
		(end 340.126066 -13.7668)
		(stroke
			(width 0.254)
			(type default)
		)
		(layer "In3.Cu")
	)
	(gr_line
		(start 340.126066 -11.2014)
		(end 340.126066 -13.7668)
		(stroke
			(width 0.1778)
			(type default)
		)
		(layer "In3.Cu")
	)
	(gr_line
		(start 340.126066 -9.56691)
		(end 338.983066 -9.56691)
		(stroke
			(width 0.254)
			(type default)
		)
		(layer "In3.Cu")
	)
	(gr_line
		(start 340.126066 -9.56691)
		(end 339.897466 -9.56691)
		(stroke
			(width 0.1778)
			(type default)
		)
		(layer "In3.Cu")
	)
	(gr_line
		(start 340.126066 -7.02691)
		(end 340.126066 -9.56691)
		(stroke
			(width 0.254)
			(type default)
		)
		(layer "In3.Cu")
	)
	(gr_line
		(start 340.126066 -7.00151)
		(end 340.126066 -9.56691)
		(stroke
			(width 0.1778)
			(type default)
		)
		(layer "In3.Cu")
	)
	(gr_line
		(start 340.151466 -13.7922)
		(end 338.932266 -13.7922)
		(stroke
			(width 0.1778)
			(type default)
		)
		(layer "In3.Cu")
	)
	(gr_line
		(start 340.151466 -13.7922)
		(end 339.922866 -13.7922)
		(stroke
			(width 0.127)
			(type default)
		)
		(layer "In3.Cu")
	)
	(gr_line
		(start 340.151466 -11.176)
		(end 340.151466 -13.7922)
		(stroke
			(width 0.127)
			(type default)
		)
		(layer "In3.Cu")
	)
	(gr_line
		(start 340.151466 -11.176)
		(end 340.151466 -13.7922)
		(stroke
			(width 0.1778)
			(type default)
		)
		(layer "In3.Cu")
	)
	(gr_line
		(start 340.151466 -9.59231)
		(end 338.932266 -9.59231)
		(stroke
			(width 0.1778)
			(type default)
		)
		(layer "In3.Cu")
	)
	(gr_line
		(start 340.151466 -9.59231)
		(end 339.922866 -9.59231)
		(stroke
			(width 0.127)
			(type default)
		)
		(layer "In3.Cu")
	)
	(gr_line
		(start 340.151466 -6.97611)
		(end 340.151466 -9.59231)
		(stroke
			(width 0.127)
			(type default)
		)
		(layer "In3.Cu")
	)
	(gr_line
		(start 340.151466 -6.97611)
		(end 340.151466 -9.59231)
		(stroke
			(width 0.1778)
			(type default)
		)
		(layer "In3.Cu")
	)
	(gr_line
		(start 340.176866 -13.8176)
		(end 338.906866 -13.8176)
		(stroke
			(width 0.127)
			(type default)
		)
		(layer "In3.Cu")
	)
	(gr_line
		(start 340.176866 -11.1506)
		(end 340.176866 -13.8176)
		(stroke
			(width 0.127)
			(type default)
		)
		(layer "In3.Cu")
	)
	(gr_line
		(start 340.176866 -9.61771)
		(end 338.906866 -9.61771)
		(stroke
			(width 0.127)
			(type default)
		)
		(layer "In3.Cu")
	)
	(gr_line
		(start 340.176866 -6.95071)
		(end 340.176866 -9.61771)
		(stroke
			(width 0.127)
			(type default)
		)
		(layer "In3.Cu")
	)
	(gr_line
		(start 340.202266 -13.843)
		(end 340.202266 -11.1252)
		(stroke
			(width 0.1016)
			(type default)
		)
		(layer "In3.Cu")
	)
	(gr_line
		(start 340.202266 -11.1252)
		(end 338.856066 -11.1252)
		(stroke
			(width 0.1016)
			(type default)
		)
		(layer "In3.Cu")
	)
	(gr_line
		(start 340.202266 -9.64311)
		(end 340.202266 -6.92531)
		(stroke
			(width 0.1016)
			(type default)
		)
		(layer "In3.Cu")
	)
	(gr_line
		(start 340.202266 -6.92531)
		(end 338.856066 -6.92531)
		(stroke
			(width 0.1016)
			(type default)
		)
		(layer "In3.Cu")
	)
	(gr_line
		(start 348.856046 -12.543028)
		(end 349.694246 -12.543028)
		(stroke
			(width 0.1016)
			(type default)
		)
		(layer "In3.Cu")
	)
	(gr_line
		(start 348.856046 -9.825228)
		(end 348.856046 -12.543028)
		(stroke
			(width 0.1016)
			(type default)
		)
		(layer "In3.Cu")
	)
	(gr_line
		(start 348.856046 -8.343138)
		(end 349.694246 -8.343138)
		(stroke
			(width 0.1016)
			(type default)
		)
		(layer "In3.Cu")
	)
	(gr_line
		(start 348.856046 -5.625338)
		(end 348.856046 -8.343138)
		(stroke
			(width 0.1016)
			(type default)
		)
		(layer "In3.Cu")
	)
	(gr_line
		(start 348.881446 -12.517628)
		(end 348.881446 -9.850628)
		(stroke
			(width 0.127)
			(type default)
		)
		(layer "In3.Cu")
	)
	(gr_line
		(start 348.881446 -9.850628)
		(end 350.176846 -9.850628)
		(stroke
			(width 0.127)
			(type default)
		)
		(layer "In3.Cu")
	)
	(gr_line
		(start 348.881446 -8.317738)
		(end 348.881446 -5.650738)
		(stroke
			(width 0.127)
			(type default)
		)
		(layer "In3.Cu")
	)
	(gr_line
		(start 348.881446 -5.650738)
		(end 350.176846 -5.650738)
		(stroke
			(width 0.127)
			(type default)
		)
		(layer "In3.Cu")
	)
	(gr_line
		(start 348.906846 -12.517628)
		(end 348.906846 -9.876028)
		(stroke
			(width 0.127)
			(type default)
		)
		(layer "In3.Cu")
	)
	(gr_line
		(start 348.906846 -12.492228)
		(end 348.906846 -9.876028)
		(stroke
			(width 0.1778)
			(type default)
		)
		(layer "In3.Cu")
	)
	(gr_line
		(start 348.906846 -9.876028)
		(end 350.151446 -9.876028)
		(stroke
			(width 0.127)
			(type default)
		)
		(layer "In3.Cu")
	)
	(gr_line
		(start 348.906846 -9.876028)
		(end 350.151446 -9.876028)
		(stroke
			(width 0.1778)
			(type default)
		)
		(layer "In3.Cu")
	)
	(gr_line
		(start 348.906846 -8.317738)
		(end 348.906846 -5.676138)
		(stroke
			(width 0.127)
			(type default)
		)
		(layer "In3.Cu")
	)
	(gr_line
		(start 348.906846 -8.292338)
		(end 348.906846 -5.676138)
		(stroke
			(width 0.1778)
			(type default)
		)
		(layer "In3.Cu")
	)
	(gr_line
		(start 348.906846 -5.676138)
		(end 350.151446 -5.676138)
		(stroke
			(width 0.127)
			(type default)
		)
		(layer "In3.Cu")
	)
	(gr_line
		(start 348.906846 -5.676138)
		(end 350.151446 -5.676138)
		(stroke
			(width 0.1778)
			(type default)
		)
		(layer "In3.Cu")
	)
	(gr_line
		(start 348.932246 -12.492228)
		(end 348.932246 -9.901428)
		(stroke
			(width 0.1778)
			(type default)
		)
		(layer "In3.Cu")
	)
	(gr_line
		(start 348.932246 -9.901428)
		(end 350.126046 -9.901428)
		(stroke
			(width 0.1778)
			(type default)
		)
		(layer "In3.Cu")
	)
	(gr_line
		(start 348.932246 -8.292338)
		(end 348.932246 -5.701538)
		(stroke
			(width 0.1778)
			(type default)
		)
		(layer "In3.Cu")
	)
	(gr_line
		(start 348.932246 -5.701538)
		(end 350.126046 -5.701538)
		(stroke
			(width 0.1778)
			(type default)
		)
		(layer "In3.Cu")
	)
	(gr_line
		(start 348.957646 -12.466828)
		(end 348.957646 -9.926828)
		(stroke
			(width 0.254)
			(type default)
		)
		(layer "In3.Cu")
	)
	(gr_line
		(start 348.957646 -9.926828)
		(end 350.126046 -9.926828)
		(stroke
			(width 0.254)
			(type default)
		)
		(layer "In3.Cu")
	)
	(gr_line
		(start 348.957646 -8.266938)
		(end 348.957646 -5.726938)
		(stroke
			(width 0.254)
			(type default)
		)
		(layer "In3.Cu")
	)
	(gr_line
		(start 348.957646 -5.726938)
		(end 350.126046 -5.726938)
		(stroke
			(width 0.254)
			(type default)
		)
		(layer "In3.Cu")
	)
	(gr_line
		(start 348.983046 -12.466828)
		(end 348.983046 -9.952228)
		(stroke
			(width 0.254)
			(type default)
		)
		(layer "In3.Cu")
	)
	(gr_line
		(start 348.983046 -9.952228)
		(end 350.100646 -9.952228)
		(stroke
			(width 0.254)
			(type default)
		)
		(layer "In3.Cu")
	)
	(gr_line
		(start 348.983046 -8.266938)
		(end 348.983046 -5.752338)
		(stroke
			(width 0.254)
			(type default)
		)
		(layer "In3.Cu")
	)
	(gr_line
		(start 348.983046 -5.752338)
		(end 350.100646 -5.752338)
		(stroke
			(width 0.254)
			(type default)
		)
		(layer "In3.Cu")
	)
	(gr_line
		(start 349.008446 -12.416028)
		(end 349.008446 -9.977628)
		(stroke
			(width 0.3556)
			(type default)
		)
		(layer "In3.Cu")
	)
	(gr_line
		(start 349.008446 -9.977628)
		(end 350.049846 -9.977628)
		(stroke
			(width 0.3556)
			(type default)
		)
		(layer "In3.Cu")
	)
	(gr_line
		(start 349.008446 -8.216138)
		(end 349.008446 -5.777738)
		(stroke
			(width 0.3556)
			(type default)
		)
		(layer "In3.Cu")
	)
	(gr_line
		(start 349.008446 -5.777738)
		(end 350.049846 -5.777738)
		(stroke
			(width 0.3556)
			(type default)
		)
		(layer "In3.Cu")
	)
	(gr_line
		(start 349.059246 -12.390628)
		(end 349.059246 -10.028428)
		(stroke
			(width 0.381)
			(type default)
		)
		(layer "In3.Cu")
	)
	(gr_line
		(start 349.059246 -10.028428)
		(end 349.999046 -10.028428)
		(stroke
			(width 0.381)
			(type default)
		)
		(layer "In3.Cu")
	)
	(gr_line
		(start 349.059246 -8.190738)
		(end 349.059246 -5.828538)
		(stroke
			(width 0.381)
			(type default)
		)
		(layer "In3.Cu")
	)
	(gr_line
		(start 349.059246 -5.828538)
		(end 349.999046 -5.828538)
		(stroke
			(width 0.381)
			(type default)
		)
		(layer "In3.Cu")
	)
	(gr_line
		(start 349.135446 -12.339828)
		(end 349.135446 -10.079228)
		(stroke
			(width 0.381)
			(type default)
		)
		(layer "In3.Cu")
	)
	(gr_line
		(start 349.135446 -10.079228)
		(end 349.948246 -10.079228)
		(stroke
			(width 0.381)
			(type default)
		)
		(layer "In3.Cu")
	)
	(gr_line
		(start 349.135446 -8.139938)
		(end 349.135446 -5.879338)
		(stroke
			(width 0.381)
			(type default)
		)
		(layer "In3.Cu")
	)
	(gr_line
		(start 349.135446 -5.879338)
		(end 349.948246 -5.879338)
		(stroke
			(width 0.381)
			(type default)
		)
		(layer "In3.Cu")
	)
	(gr_line
		(start 349.160846 -12.263628)
		(end 349.160846 -10.079228)
		(stroke
			(width 0.508)
			(type default)
		)
		(layer "In3.Cu")
	)
	(gr_line
		(start 349.160846 -10.079228)
		(end 349.922846 -10.079228)
		(stroke
			(width 0.508)
			(type default)
		)
		(layer "In3.Cu")
	)
	(gr_line
		(start 349.160846 -8.063738)
		(end 349.160846 -5.879338)
		(stroke
			(width 0.508)
			(type default)
		)
		(layer "In3.Cu")
	)
	(gr_line
		(start 349.160846 -5.879338)
		(end 349.922846 -5.879338)
		(stroke
			(width 0.508)
			(type default)
		)
		(layer "In3.Cu")
	)
	(gr_line
		(start 349.186246 -12.111228)
		(end 349.770446 -12.111228)
		(stroke
			(width 0.762)
			(type default)
		)
		(layer "In3.Cu")
	)
	(gr_line
		(start 349.186246 -10.282428)
		(end 349.770446 -10.282428)
		(stroke
			(width 0.762)
			(type default)
		)
		(layer "In3.Cu")
	)
	(gr_line
		(start 349.186246 -7.911338)
		(end 349.770446 -7.911338)
		(stroke
			(width 0.762)
			(type default)
		)
		(layer "In3.Cu")
	)
	(gr_line
		(start 349.186246 -6.082538)
		(end 349.770446 -6.082538)
		(stroke
			(width 0.762)
			(type default)
		)
		(layer "In3.Cu")
	)
	(gr_line
		(start 349.211646 -12.263628)
		(end 349.211646 -10.130028)
		(stroke
			(width 0.635)
			(type default)
		)
		(layer "In3.Cu")
	)
	(gr_line
		(start 349.211646 -12.212828)
		(end 349.211646 -10.180828)
		(stroke
			(width 0.762)
			(type default)
		)
		(layer "In3.Cu")
	)
	(gr_line
		(start 349.211646 -10.130028)
		(end 349.897446 -10.130028)
		(stroke
			(width 0.635)
			(type default)
		)
		(layer "In3.Cu")
	)
	(gr_line
		(start 349.211646 -8.063738)
		(end 349.211646 -5.930138)
		(stroke
			(width 0.635)
			(type default)
		)
		(layer "In3.Cu")
	)
	(gr_line
		(start 349.211646 -8.012938)
		(end 349.211646 -5.980938)
		(stroke
			(width 0.762)
			(type default)
		)
		(layer "In3.Cu")
	)
	(gr_line
		(start 349.211646 -5.930138)
		(end 349.897446 -5.930138)
		(stroke
			(width 0.635)
			(type default)
		)
		(layer "In3.Cu")
	)
	(gr_line
		(start 349.237046 -12.212828)
		(end 349.237046 -10.180828)
		(stroke
			(width 0.762)
			(type default)
		)
		(layer "In3.Cu")
	)
	(gr_line
		(start 349.237046 -10.180828)
		(end 349.821246 -10.180828)
		(stroke
			(width 0.762)
			(type default)
		)
		(layer "In3.Cu")
	)
	(gr_line
		(start 349.237046 -8.012938)
		(end 349.237046 -5.980938)
		(stroke
			(width 0.762)
			(type default)
		)
		(layer "In3.Cu")
	)
	(gr_line
		(start 349.237046 -5.980938)
		(end 349.821246 -5.980938)
		(stroke
			(width 0.762)
			(type default)
		)
		(layer "In3.Cu")
	)
	(gr_line
		(start 349.262446 -12.212828)
		(end 349.262446 -10.180828)
		(stroke
			(width 0.762)
			(type default)
		)
		(layer "In3.Cu")
	)
	(gr_line
		(start 349.262446 -12.212828)
		(end 349.846646 -12.212828)
		(stroke
			(width 0.762)
			(type default)
		)
		(layer "In3.Cu")
	)
	(gr_line
		(start 349.262446 -12.187428)
		(end 349.262446 -10.155428)
		(stroke
			(width 0.762)
			(type default)
		)
		(layer "In3.Cu")
	)
	(gr_line
		(start 349.262446 -8.012938)
		(end 349.262446 -5.980938)
		(stroke
			(width 0.762)
			(type default)
		)
		(layer "In3.Cu")
	)
	(gr_line
		(start 349.262446 -8.012938)
		(end 349.846646 -8.012938)
		(stroke
			(width 0.762)
			(type default)
		)
		(layer "In3.Cu")
	)
	(gr_line
		(start 349.262446 -7.987538)
		(end 349.262446 -5.955538)
		(stroke
			(width 0.762)
			(type default)
		)
		(layer "In3.Cu")
	)
	(gr_line
		(start 349.287846 -12.212828)
		(end 349.287846 -10.180828)
		(stroke
			(width 0.762)
			(type default)
		)
		(layer "In3.Cu")
	)
	(gr_line
		(start 349.287846 -8.012938)
		(end 349.287846 -5.980938)
		(stroke
			(width 0.762)
			(type default)
		)
		(layer "In3.Cu")
	)
	(gr_line
		(start 349.313246 -12.212828)
		(end 349.313246 -10.180828)
		(stroke
			(width 0.762)
			(type default)
		)
		(layer "In3.Cu")
	)
	(gr_line
		(start 349.313246 -8.012938)
		(end 349.313246 -5.980938)
		(stroke
			(width 0.762)
			(type default)
		)
		(layer "In3.Cu")
	)
	(gr_line
		(start 349.338646 -12.212828)
		(end 349.338646 -10.180828)
		(stroke
			(width 0.762)
			(type default)
		)
		(layer "In3.Cu")
	)
	(gr_line
		(start 349.338646 -8.012938)
		(end 349.338646 -5.980938)
		(stroke
			(width 0.762)
			(type default)
		)
		(layer "In3.Cu")
	)
	(gr_line
		(start 349.389446 -12.212828)
		(end 349.389446 -10.180828)
		(stroke
			(width 0.762)
			(type default)
		)
		(layer "In3.Cu")
	)
	(gr_line
		(start 349.389446 -8.012938)
		(end 349.389446 -5.980938)
		(stroke
			(width 0.762)
			(type default)
		)
		(layer "In3.Cu")
	)
	(gr_line
		(start 349.414846 -12.212828)
		(end 349.414846 -10.180828)
		(stroke
			(width 0.762)
			(type default)
		)
		(layer "In3.Cu")
	)
	(gr_line
		(start 349.414846 -8.012938)
		(end 349.414846 -5.980938)
		(stroke
			(width 0.762)
			(type default)
		)
		(layer "In3.Cu")
	)
	(gr_line
		(start 349.440246 -12.212828)
		(end 349.440246 -10.409428)
		(stroke
			(width 0.635)
			(type default)
		)
		(layer "In3.Cu")
	)
	(gr_line
		(start 349.440246 -10.409428)
		(end 349.541846 -10.409428)
		(stroke
			(width 0.635)
			(type default)
		)
		(layer "In3.Cu")
	)
	(gr_line
		(start 349.440246 -8.012938)
		(end 349.440246 -6.209538)
		(stroke
			(width 0.635)
			(type default)
		)
		(layer "In3.Cu")
	)
	(gr_line
		(start 349.440246 -6.209538)
		(end 349.541846 -6.209538)
		(stroke
			(width 0.635)
			(type default)
		)
		(layer "In3.Cu")
	)
	(gr_line
		(start 349.465646 -12.212828)
		(end 349.465646 -10.180828)
		(stroke
			(width 0.762)
			(type default)
		)
		(layer "In3.Cu")
	)
	(gr_line
		(start 349.465646 -12.187428)
		(end 349.465646 -10.155428)
		(stroke
			(width 0.762)
			(type default)
		)
		(layer "In3.Cu")
	)
	(gr_line
		(start 349.465646 -12.136628)
		(end 349.465646 -10.358628)
		(stroke
			(width 0.635)
			(type default)
		)
		(layer "In3.Cu")
	)
	(gr_line
		(start 349.465646 -8.012938)
		(end 349.465646 -5.980938)
		(stroke
			(width 0.762)
			(type default)
		)
		(layer "In3.Cu")
	)
	(gr_line
		(start 349.465646 -7.987538)
		(end 349.465646 -5.955538)
		(stroke
			(width 0.762)
			(type default)
		)
		(layer "In3.Cu")
	)
	(gr_line
		(start 349.465646 -7.936738)
		(end 349.465646 -6.158738)
		(stroke
			(width 0.635)
			(type default)
		)
		(layer "In3.Cu")
	)
	(gr_line
		(start 349.516446 -12.212828)
		(end 349.516446 -10.180828)
		(stroke
			(width 0.762)
			(type default)
		)
		(layer "In3.Cu")
	)
	(gr_line
		(start 349.516446 -8.012938)
		(end 349.516446 -5.980938)
		(stroke
			(width 0.762)
			(type default)
		)
		(layer "In3.Cu")
	)
	(gr_line
		(start 349.541846 -12.212828)
		(end 349.541846 -10.180828)
		(stroke
			(width 0.762)
			(type default)
		)
		(layer "In3.Cu")
	)
	(gr_line
		(start 349.541846 -12.187428)
		(end 349.541846 -10.155428)
		(stroke
			(width 0.762)
			(type default)
		)
		(layer "In3.Cu")
	)
	(gr_line
		(start 349.541846 -12.136628)
		(end 349.465646 -12.136628)
		(stroke
			(width 0.635)
			(type default)
		)
		(layer "In3.Cu")
	)
	(gr_line
		(start 349.541846 -10.409428)
		(end 349.541846 -12.136628)
		(stroke
			(width 0.635)
			(type default)
		)
		(layer "In3.Cu")
	)
	(gr_line
		(start 349.541846 -8.012938)
		(end 349.541846 -5.980938)
		(stroke
			(width 0.762)
			(type default)
		)
		(layer "In3.Cu")
	)
	(gr_line
		(start 349.541846 -7.987538)
		(end 349.541846 -5.955538)
		(stroke
			(width 0.762)
			(type default)
		)
		(layer "In3.Cu")
	)
	(gr_line
		(start 349.541846 -7.936738)
		(end 349.465646 -7.936738)
		(stroke
			(width 0.635)
			(type default)
		)
		(layer "In3.Cu")
	)
	(gr_line
		(start 349.541846 -6.209538)
		(end 349.541846 -7.936738)
		(stroke
			(width 0.635)
			(type default)
		)
		(layer "In3.Cu")
	)
	(gr_line
		(start 349.592646 -12.187428)
		(end 349.592646 -10.155428)
		(stroke
			(width 0.762)
			(type default)
		)
		(layer "In3.Cu")
	)
	(gr_line
		(start 349.592646 -7.987538)
		(end 349.592646 -5.955538)
		(stroke
			(width 0.762)
			(type default)
		)
		(layer "In3.Cu")
	)
	(gr_line
		(start 349.618046 -12.187428)
		(end 349.618046 -10.155428)
		(stroke
			(width 0.762)
			(type default)
		)
		(layer "In3.Cu")
	)
	(gr_line
		(start 349.618046 -7.987538)
		(end 349.618046 -5.955538)
		(stroke
			(width 0.762)
			(type default)
		)
		(layer "In3.Cu")
	)
	(gr_line
		(start 349.668846 -12.212828)
		(end 349.668846 -10.180828)
		(stroke
			(width 0.762)
			(type default)
		)
		(layer "In3.Cu")
	)
	(gr_line
		(start 349.668846 -8.012938)
		(end 349.668846 -5.980938)
		(stroke
			(width 0.762)
			(type default)
		)
		(layer "In3.Cu")
	)
	(gr_line
		(start 349.694246 -12.543028)
		(end 350.202246 -12.543028)
		(stroke
			(width 0.1016)
			(type default)
		)
		(layer "In3.Cu")
	)
	(gr_line
		(start 349.694246 -12.187428)
		(end 349.694246 -10.155428)
		(stroke
			(width 0.762)
			(type default)
		)
		(layer "In3.Cu")
	)
	(gr_line
		(start 349.694246 -8.343138)
		(end 350.202246 -8.343138)
		(stroke
			(width 0.1016)
			(type default)
		)
		(layer "In3.Cu")
	)
	(gr_line
		(start 349.694246 -7.987538)
		(end 349.694246 -5.955538)
		(stroke
			(width 0.762)
			(type default)
		)
		(layer "In3.Cu")
	)
	(gr_line
		(start 349.745046 -12.212828)
		(end 349.745046 -10.180828)
		(stroke
			(width 0.762)
			(type default)
		)
		(layer "In3.Cu")
	)
	(gr_line
		(start 349.745046 -12.187428)
		(end 349.745046 -10.155428)
		(stroke
			(width 0.762)
			(type default)
		)
		(layer "In3.Cu")
	)
	(gr_line
		(start 349.745046 -8.012938)
		(end 349.745046 -5.980938)
		(stroke
			(width 0.762)
			(type default)
		)
		(layer "In3.Cu")
	)
	(gr_line
		(start 349.745046 -7.987538)
		(end 349.745046 -5.955538)
		(stroke
			(width 0.762)
			(type default)
		)
		(layer "In3.Cu")
	)
	(gr_line
		(start 349.770446 -12.187428)
		(end 349.770446 -10.155428)
		(stroke
			(width 0.762)
			(type default)
		)
		(layer "In3.Cu")
	)
	(gr_line
		(start 349.770446 -7.987538)
		(end 349.770446 -5.955538)
		(stroke
			(width 0.762)
			(type default)
		)
		(layer "In3.Cu")
	)
	(gr_line
		(start 349.795846 -12.263628)
		(end 349.160846 -12.263628)
		(stroke
			(width 0.508)
			(type default)
		)
		(layer "In3.Cu")
	)
	(gr_line
		(start 349.795846 -12.263628)
		(end 349.211646 -12.263628)
		(stroke
			(width 0.635)
			(type default)
		)
		(layer "In3.Cu")
	)
	(gr_line
		(start 349.795846 -8.063738)
		(end 349.160846 -8.063738)
		(stroke
			(width 0.508)
			(type default)
		)
		(layer "In3.Cu")
	)
	(gr_line
		(start 349.795846 -8.063738)
		(end 349.211646 -8.063738)
		(stroke
			(width 0.635)
			(type default)
		)
		(layer "In3.Cu")
	)
	(gr_line
		(start 349.821246 -12.187428)
		(end 349.821246 -10.155428)
		(stroke
			(width 0.762)
			(type default)
		)
		(layer "In3.Cu")
	)
	(gr_line
		(start 349.821246 -7.987538)
		(end 349.821246 -5.955538)
		(stroke
			(width 0.762)
			(type default)
		)
		(layer "In3.Cu")
	)
	(gr_line
		(start 349.846646 -12.416028)
		(end 349.008446 -12.416028)
		(stroke
			(width 0.3556)
			(type default)
		)
		(layer "In3.Cu")
	)
	(gr_line
		(start 349.846646 -12.390628)
		(end 349.059246 -12.390628)
		(stroke
			(width 0.381)
			(type default)
		)
		(layer "In3.Cu")
	)
	(gr_line
		(start 349.846646 -8.216138)
		(end 349.008446 -8.216138)
		(stroke
			(width 0.3556)
			(type default)
		)
		(layer "In3.Cu")
	)
	(gr_line
		(start 349.846646 -8.190738)
		(end 349.059246 -8.190738)
		(stroke
			(width 0.381)
			(type default)
		)
		(layer "In3.Cu")
	)
	(gr_line
		(start 349.872046 -12.212828)
		(end 349.872046 -10.180828)
		(stroke
			(width 0.762)
			(type default)
		)
		(layer "In3.Cu")
	)
	(gr_line
		(start 349.872046 -8.012938)
		(end 349.872046 -5.980938)
		(stroke
			(width 0.762)
			(type default)
		)
		(layer "In3.Cu")
	)
	(gr_line
		(start 349.897446 -12.466828)
		(end 348.957646 -12.466828)
		(stroke
			(width 0.254)
			(type default)
		)
		(layer "In3.Cu")
	)
	(gr_line
		(start 349.897446 -12.212828)
		(end 349.440246 -12.212828)
		(stroke
			(width 0.635)
			(type default)
		)
		(layer "In3.Cu")
	)
	(gr_line
		(start 349.897446 -10.130028)
		(end 349.897446 -12.212828)
		(stroke
			(width 0.635)
			(type default)
		)
		(layer "In3.Cu")
	)
	(gr_line
		(start 349.897446 -8.266938)
		(end 348.957646 -8.266938)
		(stroke
			(width 0.254)
			(type default)
		)
		(layer "In3.Cu")
	)
	(gr_line
		(start 349.897446 -8.012938)
		(end 349.440246 -8.012938)
		(stroke
			(width 0.635)
			(type default)
		)
		(layer "In3.Cu")
	)
	(gr_line
		(start 349.897446 -5.930138)
		(end 349.897446 -8.012938)
		(stroke
			(width 0.635)
			(type default)
		)
		(layer "In3.Cu")
	)
	(gr_line
		(start 349.922846 -12.492228)
		(end 348.906846 -12.492228)
		(stroke
			(width 0.1778)
			(type default)
		)
		(layer "In3.Cu")
	)
	(gr_line
		(start 349.922846 -12.263628)
		(end 349.795846 -12.263628)
		(stroke
			(width 0.508)
			(type default)
		)
		(layer "In3.Cu")
	)
	(gr_line
		(start 349.922846 -10.079228)
		(end 349.922846 -12.263628)
		(stroke
			(width 0.508)
			(type default)
		)
		(layer "In3.Cu")
	)
	(gr_line
		(start 349.922846 -8.292338)
		(end 348.906846 -8.292338)
		(stroke
			(width 0.1778)
			(type default)
		)
		(layer "In3.Cu")
	)
	(gr_line
		(start 349.922846 -8.063738)
		(end 349.795846 -8.063738)
		(stroke
			(width 0.508)
			(type default)
		)
		(layer "In3.Cu")
	)
	(gr_line
		(start 349.922846 -5.879338)
		(end 349.922846 -8.063738)
		(stroke
			(width 0.508)
			(type default)
		)
		(layer "In3.Cu")
	)
	(gr_line
		(start 349.948246 -12.263628)
		(end 349.795846 -12.263628)
		(stroke
			(width 0.381)
			(type default)
		)
		(layer "In3.Cu")
	)
	(gr_line
		(start 349.948246 -10.079228)
		(end 349.948246 -12.263628)
		(stroke
			(width 0.381)
			(type default)
		)
		(layer "In3.Cu")
	)
	(gr_line
		(start 349.948246 -8.063738)
		(end 349.795846 -8.063738)
		(stroke
			(width 0.381)
			(type default)
		)
		(layer "In3.Cu")
	)
	(gr_line
		(start 349.948246 -5.879338)
		(end 349.948246 -8.063738)
		(stroke
			(width 0.381)
			(type default)
		)
		(layer "In3.Cu")
	)
	(gr_line
		(start 349.999046 -12.339828)
		(end 349.135446 -12.339828)
		(stroke
			(width 0.381)
			(type default)
		)
		(layer "In3.Cu")
	)
	(gr_line
		(start 349.999046 -10.028428)
		(end 349.999046 -12.339828)
		(stroke
			(width 0.381)
			(type default)
		)
		(layer "In3.Cu")
	)
	(gr_line
		(start 349.999046 -8.139938)
		(end 349.135446 -8.139938)
		(stroke
			(width 0.381)
			(type default)
		)
		(layer "In3.Cu")
	)
	(gr_line
		(start 349.999046 -5.828538)
		(end 349.999046 -8.139938)
		(stroke
			(width 0.381)
			(type default)
		)
		(layer "In3.Cu")
	)
	(gr_line
		(start 350.049846 -12.390628)
		(end 349.846646 -12.390628)
		(stroke
			(width 0.3556)
			(type default)
		)
		(layer "In3.Cu")
	)
	(gr_line
		(start 350.049846 -9.977628)
		(end 350.049846 -12.390628)
		(stroke
			(width 0.3556)
			(type default)
		)
		(layer "In3.Cu")
	)
	(gr_line
		(start 350.049846 -8.190738)
		(end 349.846646 -8.190738)
		(stroke
			(width 0.3556)
			(type default)
		)
		(layer "In3.Cu")
	)
	(gr_line
		(start 350.049846 -5.777738)
		(end 350.049846 -8.190738)
		(stroke
			(width 0.3556)
			(type default)
		)
		(layer "In3.Cu")
	)
	(gr_line
		(start 350.075246 -12.517628)
		(end 348.881446 -12.517628)
		(stroke
			(width 0.127)
			(type default)
		)
		(layer "In3.Cu")
	)
	(gr_line
		(start 350.075246 -8.317738)
		(end 348.881446 -8.317738)
		(stroke
			(width 0.127)
			(type default)
		)
		(layer "In3.Cu")
	)
	(gr_line
		(start 350.100646 -12.416028)
		(end 349.846646 -12.416028)
		(stroke
			(width 0.254)
			(type default)
		)
		(layer "In3.Cu")
	)
	(gr_line
		(start 350.100646 -9.952228)
		(end 350.100646 -12.416028)
		(stroke
			(width 0.254)
			(type default)
		)
		(layer "In3.Cu")
	)
	(gr_line
		(start 350.100646 -8.216138)
		(end 349.846646 -8.216138)
		(stroke
			(width 0.254)
			(type default)
		)
		(layer "In3.Cu")
	)
	(gr_line
		(start 350.100646 -5.752338)
		(end 350.100646 -8.216138)
		(stroke
			(width 0.254)
			(type default)
		)
		(layer "In3.Cu")
	)
	(gr_line
		(start 350.126046 -12.466828)
		(end 348.983046 -12.466828)
		(stroke
			(width 0.254)
			(type default)
		)
		(layer "In3.Cu")
	)
	(gr_line
		(start 350.126046 -12.466828)
		(end 349.897446 -12.466828)
		(stroke
			(width 0.1778)
			(type default)
		)
		(layer "In3.Cu")
	)
	(gr_line
		(start 350.126046 -9.926828)
		(end 350.126046 -12.466828)
		(stroke
			(width 0.254)
			(type default)
		)
		(layer "In3.Cu")
	)
	(gr_line
		(start 350.126046 -9.901428)
		(end 350.126046 -12.466828)
		(stroke
			(width 0.1778)
			(type default)
		)
		(layer "In3.Cu")
	)
	(gr_line
		(start 350.126046 -8.266938)
		(end 348.983046 -8.266938)
		(stroke
			(width 0.254)
			(type default)
		)
		(layer "In3.Cu")
	)
	(gr_line
		(start 350.126046 -8.266938)
		(end 349.897446 -8.266938)
		(stroke
			(width 0.1778)
			(type default)
		)
		(layer "In3.Cu")
	)
	(gr_line
		(start 350.126046 -5.726938)
		(end 350.126046 -8.266938)
		(stroke
			(width 0.254)
			(type default)
		)
		(layer "In3.Cu")
	)
	(gr_line
		(start 350.126046 -5.701538)
		(end 350.126046 -8.266938)
		(stroke
			(width 0.1778)
			(type default)
		)
		(layer "In3.Cu")
	)
	(gr_line
		(start 350.151446 -12.492228)
		(end 348.932246 -12.492228)
		(stroke
			(width 0.1778)
			(type default)
		)
		(layer "In3.Cu")
	)
	(gr_line
		(start 350.151446 -12.492228)
		(end 349.922846 -12.492228)
		(stroke
			(width 0.127)
			(type default)
		)
		(layer "In3.Cu")
	)
	(gr_line
		(start 350.151446 -9.876028)
		(end 350.151446 -12.492228)
		(stroke
			(width 0.127)
			(type default)
		)
		(layer "In3.Cu")
	)
	(gr_line
		(start 350.151446 -9.876028)
		(end 350.151446 -12.492228)
		(stroke
			(width 0.1778)
			(type default)
		)
		(layer "In3.Cu")
	)
	(gr_line
		(start 350.151446 -8.292338)
		(end 348.932246 -8.292338)
		(stroke
			(width 0.1778)
			(type default)
		)
		(layer "In3.Cu")
	)
	(gr_line
		(start 350.151446 -8.292338)
		(end 349.922846 -8.292338)
		(stroke
			(width 0.127)
			(type default)
		)
		(layer "In3.Cu")
	)
	(gr_line
		(start 350.151446 -5.676138)
		(end 350.151446 -8.292338)
		(stroke
			(width 0.127)
			(type default)
		)
		(layer "In3.Cu")
	)
	(gr_line
		(start 350.151446 -5.676138)
		(end 350.151446 -8.292338)
		(stroke
			(width 0.1778)
			(type default)
		)
		(layer "In3.Cu")
	)
	(gr_line
		(start 350.176846 -12.517628)
		(end 348.906846 -12.517628)
		(stroke
			(width 0.127)
			(type default)
		)
		(layer "In3.Cu")
	)
	(gr_line
		(start 350.176846 -9.850628)
		(end 350.176846 -12.517628)
		(stroke
			(width 0.127)
			(type default)
		)
		(layer "In3.Cu")
	)
	(gr_line
		(start 350.176846 -8.317738)
		(end 348.906846 -8.317738)
		(stroke
			(width 0.127)
			(type default)
		)
		(layer "In3.Cu")
	)
	(gr_line
		(start 350.176846 -5.650738)
		(end 350.176846 -8.317738)
		(stroke
			(width 0.127)
			(type default)
		)
		(layer "In3.Cu")
	)
	(gr_line
		(start 350.202246 -12.543028)
		(end 350.202246 -9.825228)
		(stroke
			(width 0.1016)
			(type default)
		)
		(layer "In3.Cu")
	)
	(gr_line
		(start 350.202246 -9.825228)
		(end 348.856046 -9.825228)
		(stroke
			(width 0.1016)
			(type default)
		)
		(layer "In3.Cu")
	)
	(gr_line
		(start 350.202246 -8.343138)
		(end 350.202246 -5.625338)
		(stroke
			(width 0.1016)
			(type default)
		)
		(layer "In3.Cu")
	)
	(gr_line
		(start 350.202246 -5.625338)
		(end 348.856046 -5.625338)
		(stroke
			(width 0.1016)
			(type default)
		)
		(layer "In3.Cu")
	)
	(gr_line
		(start 353.918266 -3.95732)
		(end 353.918266 -5.22732)
		(stroke
			(width 1.016)
			(type default)
		)
		(layer "In3.Cu")
	)
	(gr_line
		(start 353.989894 -52.319936)
		(end 335.069942 -52.319936)
		(stroke
			(width 2.032)
			(type default)
		)
		(layer "In3.Cu")
	)
	(gr_arc
		(start 353.989894 -52.319936)
		(mid 354.697017 -52.027048)
		(end 354.989892 -51.319938)
		(stroke
			(width 2.032)
			(type default)
		)
		(layer "In3.Cu")
	)
	(gr_line
		(start 354.989892 -50.8)
		(end 354.989892 -51.319938)
		(stroke
			(width 2.032)
			(type default)
		)
		(layer "In3.Cu")
	)
	(gr_arc
		(start 355.98989 -49.800002)
		(mid 355.282785 -50.092895)
		(end 354.989892 -50.8)
		(stroke
			(width 2.032)
			(type default)
		)
		(layer "In3.Cu")
	)
	(gr_line
		(start 360.496866 -11.378946)
		(end 360.496866 -9.194546)
		(stroke
			(width 0.254)
			(type default)
		)
		(layer "In3.Cu")
	)
	(gr_line
		(start 360.496866 -9.194546)
		(end 362.071666 -9.194546)
		(stroke
			(width 0.254)
			(type default)
		)
		(layer "In3.Cu")
	)
	(gr_line
		(start 360.522266 -11.378946)
		(end 360.522266 -9.245346)
		(stroke
			(width 0.254)
			(type default)
		)
		(layer "In3.Cu")
	)
	(gr_line
		(start 360.522266 -9.245346)
		(end 362.046266 -9.245346)
		(stroke
			(width 0.254)
			(type default)
		)
		(layer "In3.Cu")
	)
	(gr_line
		(start 360.573066 -11.353546)
		(end 360.573066 -9.372346)
		(stroke
			(width 0.254)
			(type default)
		)
		(layer "In3.Cu")
	)
	(gr_line
		(start 360.573066 -9.372346)
		(end 362.020866 -9.372346)
		(stroke
			(width 0.254)
			(type default)
		)
		(layer "In3.Cu")
	)
	(gr_line
		(start 360.627168 -11.302746)
		(end 360.931968 -11.302746)
		(stroke
			(width 0.1016)
			(type default)
		)
		(layer "In3.Cu")
	)
	(gr_line
		(start 360.627168 -9.296146)
		(end 360.627168 -11.302746)
		(stroke
			(width 0.1016)
			(type default)
		)
		(layer "In3.Cu")
	)
	(gr_line
		(start 360.677968 -11.226546)
		(end 361.770168 -11.226546)
		(stroke
			(width 0.2032)
			(type default)
		)
		(layer "In3.Cu")
	)
	(gr_line
		(start 360.677968 -9.372346)
		(end 360.677968 -11.226546)
		(stroke
			(width 0.2032)
			(type default)
		)
		(layer "In3.Cu")
	)
	(gr_line
		(start 360.703368 -11.226546)
		(end 361.871768 -11.226546)
		(stroke
			(width 0.2032)
			(type default)
		)
		(layer "In3.Cu")
	)
	(gr_line
		(start 360.703368 -9.423146)
		(end 360.703368 -11.226546)
		(stroke
			(width 0.2032)
			(type default)
		)
		(layer "In3.Cu")
	)
	(gr_line
		(start 360.750866 -11.124946)
		(end 360.750866 -9.575546)
		(stroke
			(width 0.762)
			(type default)
		)
		(layer "In3.Cu")
	)
	(gr_line
		(start 360.750866 -11.124946)
		(end 361.665266 -11.124946)
		(stroke
			(width 0.762)
			(type default)
		)
		(layer "In3.Cu")
	)
	(gr_line
		(start 360.750866 -11.099546)
		(end 360.750866 -9.550146)
		(stroke
			(width 0.762)
			(type default)
		)
		(layer "In3.Cu")
	)
	(gr_line
		(start 360.750866 -10.997946)
		(end 360.750866 -9.448546)
		(stroke
			(width 0.762)
			(type default)
		)
		(layer "In3.Cu")
	)
	(gr_line
		(start 360.750866 -9.448546)
		(end 361.665266 -9.448546)
		(stroke
			(width 0.762)
			(type default)
		)
		(layer "In3.Cu")
	)
	(gr_line
		(start 360.754168 -11.175746)
		(end 361.846368 -11.175746)
		(stroke
			(width 0.2032)
			(type default)
		)
		(layer "In3.Cu")
	)
	(gr_line
		(start 360.754168 -9.473946)
		(end 360.754168 -11.175746)
		(stroke
			(width 0.2032)
			(type default)
		)
		(layer "In3.Cu")
	)
	(gr_line
		(start 360.776266 -10.997946)
		(end 361.690666 -10.997946)
		(stroke
			(width 0.762)
			(type default)
		)
		(layer "In3.Cu")
	)
	(gr_line
		(start 360.776266 -9.575546)
		(end 361.690666 -9.575546)
		(stroke
			(width 0.762)
			(type default)
		)
		(layer "In3.Cu")
	)
	(gr_line
		(start 360.855768 -11.074146)
		(end 361.643168 -11.074146)
		(stroke
			(width 0.508)
			(type default)
		)
		(layer "In3.Cu")
	)
	(gr_line
		(start 360.855768 -11.048746)
		(end 360.855768 -9.524746)
		(stroke
			(width 0.508)
			(type default)
		)
		(layer "In3.Cu")
	)
	(gr_line
		(start 360.881168 -11.074146)
		(end 360.881168 -9.550146)
		(stroke
			(width 0.508)
			(type default)
		)
		(layer "In3.Cu")
	)
	(gr_line
		(start 360.903266 -11.124946)
		(end 361.817666 -11.124946)
		(stroke
			(width 0.762)
			(type default)
		)
		(layer "In3.Cu")
	)
	(gr_line
		(start 360.903266 -9.448546)
		(end 361.817666 -9.448546)
		(stroke
			(width 0.762)
			(type default)
		)
		(layer "In3.Cu")
	)
	(gr_line
		(start 360.906568 -9.524746)
		(end 361.643168 -9.524746)
		(stroke
			(width 0.508)
			(type default)
		)
		(layer "In3.Cu")
	)
	(gr_line
		(start 360.931968 -11.302746)
		(end 361.922568 -11.302746)
		(stroke
			(width 0.1016)
			(type default)
		)
		(layer "In3.Cu")
	)
	(gr_line
		(start 360.931968 -11.074146)
		(end 360.931968 -9.550146)
		(stroke
			(width 0.508)
			(type default)
		)
		(layer "In3.Cu")
	)
	(gr_line
		(start 360.957368 -11.074146)
		(end 360.957368 -9.550146)
		(stroke
			(width 0.508)
			(type default)
		)
		(layer "In3.Cu")
	)
	(gr_line
		(start 360.982768 -11.074146)
		(end 360.982768 -9.550146)
		(stroke
			(width 0.508)
			(type default)
		)
		(layer "In3.Cu")
	)
	(gr_line
		(start 361.008168 -11.074146)
		(end 361.008168 -9.550146)
		(stroke
			(width 0.508)
			(type default)
		)
		(layer "In3.Cu")
	)
	(gr_line
		(start 361.008168 -11.048746)
		(end 361.008168 -9.524746)
		(stroke
			(width 0.508)
			(type default)
		)
		(layer "In3.Cu")
	)
	(gr_line
		(start 361.033568 -11.074146)
		(end 361.033568 -9.550146)
		(stroke
			(width 0.508)
			(type default)
		)
		(layer "In3.Cu")
	)
	(gr_line
		(start 361.058968 -11.074146)
		(end 361.058968 -9.550146)
		(stroke
			(width 0.508)
			(type default)
		)
		(layer "In3.Cu")
	)
	(gr_line
		(start 361.109768 -11.074146)
		(end 361.109768 -9.550146)
		(stroke
			(width 0.508)
			(type default)
		)
		(layer "In3.Cu")
	)
	(gr_line
		(start 361.109768 -11.048746)
		(end 361.109768 -9.524746)
		(stroke
			(width 0.508)
			(type default)
		)
		(layer "In3.Cu")
	)
	(gr_line
		(start 361.135168 -11.074146)
		(end 361.135168 -9.550146)
		(stroke
			(width 0.508)
			(type default)
		)
		(layer "In3.Cu")
	)
	(gr_line
		(start 361.160568 -11.074146)
		(end 361.160568 -9.550146)
		(stroke
			(width 0.508)
			(type default)
		)
		(layer "In3.Cu")
	)
	(gr_line
		(start 361.185968 -11.074146)
		(end 361.185968 -9.550146)
		(stroke
			(width 0.508)
			(type default)
		)
		(layer "In3.Cu")
	)
	(gr_line
		(start 361.236768 -11.074146)
		(end 361.236768 -9.550146)
		(stroke
			(width 0.508)
			(type default)
		)
		(layer "In3.Cu")
	)
	(gr_line
		(start 361.262168 -11.074146)
		(end 361.262168 -9.550146)
		(stroke
			(width 0.508)
			(type default)
		)
		(layer "In3.Cu")
	)
	(gr_line
		(start 361.262168 -11.048746)
		(end 361.262168 -9.524746)
		(stroke
			(width 0.508)
			(type default)
		)
		(layer "In3.Cu")
	)
	(gr_line
		(start 361.287568 -11.074146)
		(end 361.287568 -9.550146)
		(stroke
			(width 0.508)
			(type default)
		)
		(layer "In3.Cu")
	)
	(gr_line
		(start 361.312968 -11.074146)
		(end 361.312968 -9.550146)
		(stroke
			(width 0.508)
			(type default)
		)
		(layer "In3.Cu")
	)
	(gr_line
		(start 361.338368 -11.074146)
		(end 361.338368 -9.550146)
		(stroke
			(width 0.508)
			(type default)
		)
		(layer "In3.Cu")
	)
	(gr_line
		(start 361.338368 -11.048746)
		(end 361.338368 -9.524746)
		(stroke
			(width 0.508)
			(type default)
		)
		(layer "In3.Cu")
	)
	(gr_line
		(start 361.363768 -11.074146)
		(end 361.363768 -9.550146)
		(stroke
			(width 0.508)
			(type default)
		)
		(layer "In3.Cu")
	)
	(gr_line
		(start 361.389168 -11.074146)
		(end 361.389168 -9.550146)
		(stroke
			(width 0.508)
			(type default)
		)
		(layer "In3.Cu")
	)
	(gr_line
		(start 361.389168 -11.048746)
		(end 361.389168 -9.524746)
		(stroke
			(width 0.508)
			(type default)
		)
		(layer "In3.Cu")
	)
	(gr_line
		(start 361.414568 -11.074146)
		(end 361.414568 -9.550146)
		(stroke
			(width 0.508)
			(type default)
		)
		(layer "In3.Cu")
	)
	(gr_line
		(start 361.414568 -11.048746)
		(end 361.414568 -9.524746)
		(stroke
			(width 0.508)
			(type default)
		)
		(layer "In3.Cu")
	)
	(gr_line
		(start 361.439968 -11.048746)
		(end 361.439968 -9.524746)
		(stroke
			(width 0.508)
			(type default)
		)
		(layer "In3.Cu")
	)
	(gr_line
		(start 361.465368 -11.074146)
		(end 361.465368 -9.550146)
		(stroke
			(width 0.508)
			(type default)
		)
		(layer "In3.Cu")
	)
	(gr_line
		(start 361.487466 -11.378946)
		(end 360.496866 -11.378946)
		(stroke
			(width 0.254)
			(type default)
		)
		(layer "In3.Cu")
	)
	(gr_line
		(start 361.490768 -11.048746)
		(end 361.490768 -9.524746)
		(stroke
			(width 0.508)
			(type default)
		)
		(layer "In3.Cu")
	)
	(gr_line
		(start 361.516168 -11.048746)
		(end 361.516168 -9.524746)
		(stroke
			(width 0.508)
			(type default)
		)
		(layer "In3.Cu")
	)
	(gr_line
		(start 361.541568 -11.074146)
		(end 361.541568 -9.550146)
		(stroke
			(width 0.508)
			(type default)
		)
		(layer "In3.Cu")
	)
	(gr_line
		(start 361.566968 -11.074146)
		(end 361.566968 -9.550146)
		(stroke
			(width 0.508)
			(type default)
		)
		(layer "In3.Cu")
	)
	(gr_line
		(start 361.566968 -11.048746)
		(end 361.566968 -9.524746)
		(stroke
			(width 0.508)
			(type default)
		)
		(layer "In3.Cu")
	)
	(gr_line
		(start 361.617768 -11.074146)
		(end 361.617768 -9.550146)
		(stroke
			(width 0.508)
			(type default)
		)
		(layer "In3.Cu")
	)
	(gr_line
		(start 361.617768 -11.048746)
		(end 361.617768 -9.524746)
		(stroke
			(width 0.508)
			(type default)
		)
		(layer "In3.Cu")
	)
	(gr_line
		(start 361.668568 -11.074146)
		(end 361.668568 -9.550146)
		(stroke
			(width 0.508)
			(type default)
		)
		(layer "In3.Cu")
	)
	(gr_line
		(start 361.668568 -11.048746)
		(end 361.668568 -9.524746)
		(stroke
			(width 0.508)
			(type default)
		)
		(layer "In3.Cu")
	)
	(gr_line
		(start 361.690666 -11.099546)
		(end 361.690666 -9.550146)
		(stroke
			(width 0.762)
			(type default)
		)
		(layer "In3.Cu")
	)
	(gr_line
		(start 361.693968 -11.074146)
		(end 361.693968 -9.550146)
		(stroke
			(width 0.508)
			(type default)
		)
		(layer "In3.Cu")
	)
	(gr_line
		(start 361.719368 -11.074146)
		(end 361.719368 -9.550146)
		(stroke
			(width 0.508)
			(type default)
		)
		(layer "In3.Cu")
	)
	(gr_line
		(start 361.770168 -11.226546)
		(end 361.795568 -11.226546)
		(stroke
			(width 0.2032)
			(type default)
		)
		(layer "In3.Cu")
	)
	(gr_line
		(start 361.795568 -11.226546)
		(end 361.795568 -9.473946)
		(stroke
			(width 0.2032)
			(type default)
		)
		(layer "In3.Cu")
	)
	(gr_line
		(start 361.795568 -9.473946)
		(end 360.754168 -9.473946)
		(stroke
			(width 0.2032)
			(type default)
		)
		(layer "In3.Cu")
	)
	(gr_line
		(start 361.817666 -11.124946)
		(end 361.817666 -9.575546)
		(stroke
			(width 0.762)
			(type default)
		)
		(layer "In3.Cu")
	)
	(gr_line
		(start 361.817666 -11.099546)
		(end 361.817666 -9.600946)
		(stroke
			(width 0.762)
			(type default)
		)
		(layer "In3.Cu")
	)
	(gr_line
		(start 361.817666 -10.997946)
		(end 361.817666 -9.448546)
		(stroke
			(width 0.762)
			(type default)
		)
		(layer "In3.Cu")
	)
	(gr_line
		(start 361.846368 -11.175746)
		(end 361.846368 -9.423146)
		(stroke
			(width 0.2032)
			(type default)
		)
		(layer "In3.Cu")
	)
	(gr_line
		(start 361.846368 -9.423146)
		(end 360.703368 -9.423146)
		(stroke
			(width 0.2032)
			(type default)
		)
		(layer "In3.Cu")
	)
	(gr_line
		(start 361.871768 -11.226546)
		(end 361.871768 -9.372346)
		(stroke
			(width 0.2032)
			(type default)
		)
		(layer "In3.Cu")
	)
	(gr_line
		(start 361.871768 -9.372346)
		(end 360.677968 -9.372346)
		(stroke
			(width 0.2032)
			(type default)
		)
		(layer "In3.Cu")
	)
	(gr_line
		(start 361.922568 -11.302746)
		(end 361.922568 -9.296146)
		(stroke
			(width 0.1016)
			(type default)
		)
		(layer "In3.Cu")
	)
	(gr_line
		(start 361.922568 -9.296146)
		(end 360.627168 -9.296146)
		(stroke
			(width 0.1016)
			(type default)
		)
		(layer "In3.Cu")
	)
	(gr_line
		(start 362.020866 -11.226546)
		(end 361.770168 -11.226546)
		(stroke
			(width 0.254)
			(type default)
		)
		(layer "In3.Cu")
	)
	(gr_line
		(start 362.020866 -9.372346)
		(end 362.020866 -11.226546)
		(stroke
			(width 0.254)
			(type default)
		)
		(layer "In3.Cu")
	)
	(gr_line
		(start 362.046266 -11.353546)
		(end 360.573066 -11.353546)
		(stroke
			(width 0.254)
			(type default)
		)
		(layer "In3.Cu")
	)
	(gr_line
		(start 362.046266 -9.245346)
		(end 362.046266 -11.353546)
		(stroke
			(width 0.254)
			(type default)
		)
		(layer "In3.Cu")
	)
	(gr_line
		(start 362.071666 -11.378946)
		(end 360.522266 -11.378946)
		(stroke
			(width 0.254)
			(type default)
		)
		(layer "In3.Cu")
	)
	(gr_line
		(start 362.071666 -9.194546)
		(end 362.071666 -11.378946)
		(stroke
			(width 0.254)
			(type default)
		)
		(layer "In3.Cu")
	)
	(gr_line
		(start 365.296958 -11.378946)
		(end 365.296958 -9.194546)
		(stroke
			(width 0.254)
			(type default)
		)
		(layer "In3.Cu")
	)
	(gr_line
		(start 365.296958 -9.194546)
		(end 366.871758 -9.194546)
		(stroke
			(width 0.254)
			(type default)
		)
		(layer "In3.Cu")
	)
	(gr_line
		(start 365.322358 -11.378946)
		(end 365.322358 -9.245346)
		(stroke
			(width 0.254)
			(type default)
		)
		(layer "In3.Cu")
	)
	(gr_line
		(start 365.322358 -9.245346)
		(end 366.846358 -9.245346)
		(stroke
			(width 0.254)
			(type default)
		)
		(layer "In3.Cu")
	)
	(gr_line
		(start 365.373158 -11.353546)
		(end 365.373158 -9.372346)
		(stroke
			(width 0.254)
			(type default)
		)
		(layer "In3.Cu")
	)
	(gr_line
		(start 365.373158 -9.372346)
		(end 366.820958 -9.372346)
		(stroke
			(width 0.254)
			(type default)
		)
		(layer "In3.Cu")
	)
	(gr_line
		(start 365.42726 -11.302746)
		(end 365.73206 -11.302746)
		(stroke
			(width 0.1016)
			(type default)
		)
		(layer "In3.Cu")
	)
	(gr_line
		(start 365.42726 -9.296146)
		(end 365.42726 -11.302746)
		(stroke
			(width 0.1016)
			(type default)
		)
		(layer "In3.Cu")
	)
	(gr_line
		(start 365.4552 -5.715)
		(end 366.7252 -5.715)
		(stroke
			(width 1.016)
			(type default)
		)
		(layer "In3.Cu")
	)
	(gr_line
		(start 365.47806 -11.226546)
		(end 366.57026 -11.226546)
		(stroke
			(width 0.2032)
			(type default)
		)
		(layer "In3.Cu")
	)
	(gr_line
		(start 365.47806 -9.372346)
		(end 365.47806 -11.226546)
		(stroke
			(width 0.2032)
			(type default)
		)
		(layer "In3.Cu")
	)
	(gr_line
		(start 365.50346 -11.226546)
		(end 366.67186 -11.226546)
		(stroke
			(width 0.2032)
			(type default)
		)
		(layer "In3.Cu")
	)
	(gr_line
		(start 365.50346 -9.423146)
		(end 365.50346 -11.226546)
		(stroke
			(width 0.2032)
			(type default)
		)
		(layer "In3.Cu")
	)
	(gr_line
		(start 365.550958 -11.124946)
		(end 365.550958 -9.575546)
		(stroke
			(width 0.762)
			(type default)
		)
		(layer "In3.Cu")
	)
	(gr_line
		(start 365.550958 -11.124946)
		(end 366.465358 -11.124946)
		(stroke
			(width 0.762)
			(type default)
		)
		(layer "In3.Cu")
	)
	(gr_line
		(start 365.550958 -11.099546)
		(end 365.550958 -9.550146)
		(stroke
			(width 0.762)
			(type default)
		)
		(layer "In3.Cu")
	)
	(gr_line
		(start 365.550958 -10.997946)
		(end 365.550958 -9.448546)
		(stroke
			(width 0.762)
			(type default)
		)
		(layer "In3.Cu")
	)
	(gr_line
		(start 365.550958 -9.448546)
		(end 366.465358 -9.448546)
		(stroke
			(width 0.762)
			(type default)
		)
		(layer "In3.Cu")
	)
	(gr_line
		(start 365.55426 -11.175746)
		(end 366.64646 -11.175746)
		(stroke
			(width 0.2032)
			(type default)
		)
		(layer "In3.Cu")
	)
	(gr_line
		(start 365.55426 -9.473946)
		(end 365.55426 -11.175746)
		(stroke
			(width 0.2032)
			(type default)
		)
		(layer "In3.Cu")
	)
	(gr_line
		(start 365.576358 -10.997946)
		(end 366.490758 -10.997946)
		(stroke
			(width 0.762)
			(type default)
		)
		(layer "In3.Cu")
	)
	(gr_line
		(start 365.576358 -9.575546)
		(end 366.490758 -9.575546)
		(stroke
			(width 0.762)
			(type default)
		)
		(layer "In3.Cu")
	)
	(gr_line
		(start 365.65586 -11.074146)
		(end 366.44326 -11.074146)
		(stroke
			(width 0.508)
			(type default)
		)
		(layer "In3.Cu")
	)
	(gr_line
		(start 365.65586 -11.048746)
		(end 365.65586 -9.524746)
		(stroke
			(width 0.508)
			(type default)
		)
		(layer "In3.Cu")
	)
	(gr_line
		(start 365.68126 -11.074146)
		(end 365.68126 -9.550146)
		(stroke
			(width 0.508)
			(type default)
		)
		(layer "In3.Cu")
	)
	(gr_line
		(start 365.703358 -11.124946)
		(end 366.617758 -11.124946)
		(stroke
			(width 0.762)
			(type default)
		)
		(layer "In3.Cu")
	)
	(gr_line
		(start 365.703358 -9.448546)
		(end 366.617758 -9.448546)
		(stroke
			(width 0.762)
			(type default)
		)
		(layer "In3.Cu")
	)
	(gr_line
		(start 365.70666 -9.524746)
		(end 366.44326 -9.524746)
		(stroke
			(width 0.508)
			(type default)
		)
		(layer "In3.Cu")
	)
	(gr_line
		(start 365.73206 -11.302746)
		(end 366.72266 -11.302746)
		(stroke
			(width 0.1016)
			(type default)
		)
		(layer "In3.Cu")
	)
	(gr_line
		(start 365.73206 -11.074146)
		(end 365.73206 -9.550146)
		(stroke
			(width 0.508)
			(type default)
		)
		(layer "In3.Cu")
	)
	(gr_line
		(start 365.75746 -11.074146)
		(end 365.75746 -9.550146)
		(stroke
			(width 0.508)
			(type default)
		)
		(layer "In3.Cu")
	)
	(gr_line
		(start 365.78286 -11.074146)
		(end 365.78286 -9.550146)
		(stroke
			(width 0.508)
			(type default)
		)
		(layer "In3.Cu")
	)
	(gr_line
		(start 365.80826 -11.074146)
		(end 365.80826 -9.550146)
		(stroke
			(width 0.508)
			(type default)
		)
		(layer "In3.Cu")
	)
	(gr_line
		(start 365.80826 -11.048746)
		(end 365.80826 -9.524746)
		(stroke
			(width 0.508)
			(type default)
		)
		(layer "In3.Cu")
	)
	(gr_line
		(start 365.83366 -11.074146)
		(end 365.83366 -9.550146)
		(stroke
			(width 0.508)
			(type default)
		)
		(layer "In3.Cu")
	)
	(gr_line
		(start 365.85906 -11.074146)
		(end 365.85906 -9.550146)
		(stroke
			(width 0.508)
			(type default)
		)
		(layer "In3.Cu")
	)
	(gr_line
		(start 365.90986 -11.074146)
		(end 365.90986 -9.550146)
		(stroke
			(width 0.508)
			(type default)
		)
		(layer "In3.Cu")
	)
	(gr_line
		(start 365.90986 -11.048746)
		(end 365.90986 -9.524746)
		(stroke
			(width 0.508)
			(type default)
		)
		(layer "In3.Cu")
	)
	(gr_line
		(start 365.93526 -11.074146)
		(end 365.93526 -9.550146)
		(stroke
			(width 0.508)
			(type default)
		)
		(layer "In3.Cu")
	)
	(gr_line
		(start 365.96066 -11.074146)
		(end 365.96066 -9.550146)
		(stroke
			(width 0.508)
			(type default)
		)
		(layer "In3.Cu")
	)
	(gr_line
		(start 365.98606 -11.074146)
		(end 365.98606 -9.550146)
		(stroke
			(width 0.508)
			(type default)
		)
		(layer "In3.Cu")
	)
	(gr_line
		(start 366.03686 -11.074146)
		(end 366.03686 -9.550146)
		(stroke
			(width 0.508)
			(type default)
		)
		(layer "In3.Cu")
	)
	(gr_line
		(start 366.06226 -11.074146)
		(end 366.06226 -9.550146)
		(stroke
			(width 0.508)
			(type default)
		)
		(layer "In3.Cu")
	)
	(gr_line
		(start 366.06226 -11.048746)
		(end 366.06226 -9.524746)
		(stroke
			(width 0.508)
			(type default)
		)
		(layer "In3.Cu")
	)
	(gr_line
		(start 366.08766 -11.074146)
		(end 366.08766 -9.550146)
		(stroke
			(width 0.508)
			(type default)
		)
		(layer "In3.Cu")
	)
	(gr_line
		(start 366.11306 -11.074146)
		(end 366.11306 -9.550146)
		(stroke
			(width 0.508)
			(type default)
		)
		(layer "In3.Cu")
	)
	(gr_line
		(start 366.13846 -11.074146)
		(end 366.13846 -9.550146)
		(stroke
			(width 0.508)
			(type default)
		)
		(layer "In3.Cu")
	)
	(gr_line
		(start 366.13846 -11.048746)
		(end 366.13846 -9.524746)
		(stroke
			(width 0.508)
			(type default)
		)
		(layer "In3.Cu")
	)
	(gr_line
		(start 366.16386 -11.074146)
		(end 366.16386 -9.550146)
		(stroke
			(width 0.508)
			(type default)
		)
		(layer "In3.Cu")
	)
	(gr_line
		(start 366.18926 -11.074146)
		(end 366.18926 -9.550146)
		(stroke
			(width 0.508)
			(type default)
		)
		(layer "In3.Cu")
	)
	(gr_line
		(start 366.18926 -11.048746)
		(end 366.18926 -9.524746)
		(stroke
			(width 0.508)
			(type default)
		)
		(layer "In3.Cu")
	)
	(gr_line
		(start 366.21466 -11.074146)
		(end 366.21466 -9.550146)
		(stroke
			(width 0.508)
			(type default)
		)
		(layer "In3.Cu")
	)
	(gr_line
		(start 366.21466 -11.048746)
		(end 366.21466 -9.524746)
		(stroke
			(width 0.508)
			(type default)
		)
		(layer "In3.Cu")
	)
	(gr_line
		(start 366.24006 -11.048746)
		(end 366.24006 -9.524746)
		(stroke
			(width 0.508)
			(type default)
		)
		(layer "In3.Cu")
	)
	(gr_line
		(start 366.26546 -11.074146)
		(end 366.26546 -9.550146)
		(stroke
			(width 0.508)
			(type default)
		)
		(layer "In3.Cu")
	)
	(gr_line
		(start 366.287558 -11.378946)
		(end 365.296958 -11.378946)
		(stroke
			(width 0.254)
			(type default)
		)
		(layer "In3.Cu")
	)
	(gr_line
		(start 366.29086 -11.048746)
		(end 366.29086 -9.524746)
		(stroke
			(width 0.508)
			(type default)
		)
		(layer "In3.Cu")
	)
	(gr_line
		(start 366.31626 -11.048746)
		(end 366.31626 -9.524746)
		(stroke
			(width 0.508)
			(type default)
		)
		(layer "In3.Cu")
	)
	(gr_line
		(start 366.34166 -11.074146)
		(end 366.34166 -9.550146)
		(stroke
			(width 0.508)
			(type default)
		)
		(layer "In3.Cu")
	)
	(gr_line
		(start 366.36706 -11.074146)
		(end 366.36706 -9.550146)
		(stroke
			(width 0.508)
			(type default)
		)
		(layer "In3.Cu")
	)
	(gr_line
		(start 366.36706 -11.048746)
		(end 366.36706 -9.524746)
		(stroke
			(width 0.508)
			(type default)
		)
		(layer "In3.Cu")
	)
	(gr_line
		(start 366.41786 -11.074146)
		(end 366.41786 -9.550146)
		(stroke
			(width 0.508)
			(type default)
		)
		(layer "In3.Cu")
	)
	(gr_line
		(start 366.41786 -11.048746)
		(end 366.41786 -9.524746)
		(stroke
			(width 0.508)
			(type default)
		)
		(layer "In3.Cu")
	)
	(gr_line
		(start 366.46866 -11.074146)
		(end 366.46866 -9.550146)
		(stroke
			(width 0.508)
			(type default)
		)
		(layer "In3.Cu")
	)
	(gr_line
		(start 366.46866 -11.048746)
		(end 366.46866 -9.524746)
		(stroke
			(width 0.508)
			(type default)
		)
		(layer "In3.Cu")
	)
	(gr_line
		(start 366.490758 -11.099546)
		(end 366.490758 -9.550146)
		(stroke
			(width 0.762)
			(type default)
		)
		(layer "In3.Cu")
	)
	(gr_line
		(start 366.49406 -11.074146)
		(end 366.49406 -9.550146)
		(stroke
			(width 0.508)
			(type default)
		)
		(layer "In3.Cu")
	)
	(gr_line
		(start 366.51946 -11.074146)
		(end 366.51946 -9.550146)
		(stroke
			(width 0.508)
			(type default)
		)
		(layer "In3.Cu")
	)
	(gr_line
		(start 366.57026 -11.226546)
		(end 366.59566 -11.226546)
		(stroke
			(width 0.2032)
			(type default)
		)
		(layer "In3.Cu")
	)
	(gr_line
		(start 366.59566 -11.226546)
		(end 366.59566 -9.473946)
		(stroke
			(width 0.2032)
			(type default)
		)
		(layer "In3.Cu")
	)
	(gr_line
		(start 366.59566 -9.473946)
		(end 365.55426 -9.473946)
		(stroke
			(width 0.2032)
			(type default)
		)
		(layer "In3.Cu")
	)
	(gr_line
		(start 366.617758 -11.124946)
		(end 366.617758 -9.575546)
		(stroke
			(width 0.762)
			(type default)
		)
		(layer "In3.Cu")
	)
	(gr_line
		(start 366.617758 -11.099546)
		(end 366.617758 -9.600946)
		(stroke
			(width 0.762)
			(type default)
		)
		(layer "In3.Cu")
	)
	(gr_line
		(start 366.617758 -10.997946)
		(end 366.617758 -9.448546)
		(stroke
			(width 0.762)
			(type default)
		)
		(layer "In3.Cu")
	)
	(gr_line
		(start 366.64646 -11.175746)
		(end 366.64646 -9.423146)
		(stroke
			(width 0.2032)
			(type default)
		)
		(layer "In3.Cu")
	)
	(gr_line
		(start 366.64646 -9.423146)
		(end 365.50346 -9.423146)
		(stroke
			(width 0.2032)
			(type default)
		)
		(layer "In3.Cu")
	)
	(gr_line
		(start 366.67186 -11.226546)
		(end 366.67186 -9.372346)
		(stroke
			(width 0.2032)
			(type default)
		)
		(layer "In3.Cu")
	)
	(gr_line
		(start 366.67186 -9.372346)
		(end 365.47806 -9.372346)
		(stroke
			(width 0.2032)
			(type default)
		)
		(layer "In3.Cu")
	)
	(gr_line
		(start 366.72266 -11.302746)
		(end 366.72266 -9.296146)
		(stroke
			(width 0.1016)
			(type default)
		)
		(layer "In3.Cu")
	)
	(gr_line
		(start 366.72266 -9.296146)
		(end 365.42726 -9.296146)
		(stroke
			(width 0.1016)
			(type default)
		)
		(layer "In3.Cu")
	)
	(gr_line
		(start 366.820958 -11.226546)
		(end 366.57026 -11.226546)
		(stroke
			(width 0.254)
			(type default)
		)
		(layer "In3.Cu")
	)
	(gr_line
		(start 366.820958 -9.372346)
		(end 366.820958 -11.226546)
		(stroke
			(width 0.254)
			(type default)
		)
		(layer "In3.Cu")
	)
	(gr_line
		(start 366.846358 -11.353546)
		(end 365.373158 -11.353546)
		(stroke
			(width 0.254)
			(type default)
		)
		(layer "In3.Cu")
	)
	(gr_line
		(start 366.846358 -9.245346)
		(end 366.846358 -11.353546)
		(stroke
			(width 0.254)
			(type default)
		)
		(layer "In3.Cu")
	)
	(gr_line
		(start 366.871758 -11.378946)
		(end 365.322358 -11.378946)
		(stroke
			(width 0.254)
			(type default)
		)
		(layer "In3.Cu")
	)
	(gr_line
		(start 366.871758 -9.194546)
		(end 366.871758 -11.378946)
		(stroke
			(width 0.254)
			(type default)
		)
		(layer "In3.Cu")
	)
	(gr_line
		(start 370.98986 -49.800002)
		(end 355.98989 -49.800002)
		(stroke
			(width 2.032)
			(type default)
		)
		(layer "In3.Cu")
	)
	(gr_line
		(start 371.989858 -51.319938)
		(end 371.989858 -50.8)
		(stroke
			(width 2.032)
			(type default)
		)
		(layer "In3.Cu")
	)
	(gr_arc
		(start 371.989858 -51.319938)
		(mid 372.282761 -52.027034)
		(end 372.989856 -52.319936)
		(stroke
			(width 2.032)
			(type default)
		)
		(layer "In3.Cu")
	)
	(gr_arc
		(start 371.989858 -50.8)
		(mid 371.696965 -50.092895)
		(end 370.98986 -49.800002)
		(stroke
			(width 2.032)
			(type default)
		)
		(layer "In3.Cu")
	)
	(gr_line
		(start 379.990096 -52.319936)
		(end 372.989856 -52.319936)
		(stroke
			(width 2.032)
			(type default)
		)
		(layer "In3.Cu")
	)
	(gr_line
		(start 380.37262 -52.24399)
		(end 379.990096 -52.319936)
		(stroke
			(width 2.032)
			(type default)
		)
		(layer "In3.Cu")
	)
	(gr_line
		(start 380.697232 -52.027074)
		(end 380.37262 -52.24399)
		(stroke
			(width 2.032)
			(type default)
		)
		(layer "In3.Cu")
	)
	(gr_line
		(start 380.913894 -51.702716)
		(end 380.697232 -52.027074)
		(stroke
			(width 2.032)
			(type default)
		)
		(layer "In3.Cu")
	)
	(gr_line
		(start 380.98222 -51.376072)
		(end 380.913894 -51.702716)
		(stroke
			(width 2.032)
			(type default)
		)
		(layer "In3.Cu")
	)
	(gr_line
		(start 381.070866 -50.996088)
		(end 380.98222 -51.376072)
		(stroke
			(width 2.032)
			(type default)
		)
		(layer "In3.Cu")
	)
	(gr_line
		(start 381.288798 -50.677064)
		(end 381.070866 -50.996088)
		(stroke
			(width 2.032)
			(type default)
		)
		(layer "In3.Cu")
	)
	(gr_line
		(start 381.611124 -50.464466)
		(end 381.288798 -50.677064)
		(stroke
			(width 2.032)
			(type default)
		)
		(layer "In3.Cu")
	)
	(gr_line
		(start 381.990092 -50.390044)
		(end 381.611124 -50.464466)
		(stroke
			(width 2.032)
			(type default)
		)
		(layer "In3.Cu")
	)
	(gr_line
		(start 385.287266 -13.8176)
		(end 386.074666 -13.8176)
		(stroke
			(width 0.1016)
			(type default)
		)
		(layer "In3.Cu")
	)
	(gr_line
		(start 385.287266 -13.7668)
		(end 385.287266 -11.1506)
		(stroke
			(width 0.1016)
			(type default)
		)
		(layer "In3.Cu")
	)
	(gr_line
		(start 385.287266 -11.1506)
		(end 385.287266 -13.8176)
		(stroke
			(width 0.1016)
			(type default)
		)
		(layer "In3.Cu")
	)
	(gr_line
		(start 385.287266 -11.1506)
		(end 386.481066 -11.1506)
		(stroke
			(width 0.1016)
			(type default)
		)
		(layer "In3.Cu")
	)
	(gr_line
		(start 385.287266 -9.617456)
		(end 386.074666 -9.617456)
		(stroke
			(width 0.1016)
			(type default)
		)
		(layer "In3.Cu")
	)
	(gr_line
		(start 385.287266 -9.566656)
		(end 385.287266 -6.950456)
		(stroke
			(width 0.1016)
			(type default)
		)
		(layer "In3.Cu")
	)
	(gr_line
		(start 385.287266 -6.950456)
		(end 385.287266 -9.617456)
		(stroke
			(width 0.1016)
			(type default)
		)
		(layer "In3.Cu")
	)
	(gr_line
		(start 385.287266 -6.950456)
		(end 386.481066 -6.950456)
		(stroke
			(width 0.1016)
			(type default)
		)
		(layer "In3.Cu")
	)
	(gr_line
		(start 385.287266 -5.417312)
		(end 386.074666 -5.417312)
		(stroke
			(width 0.1016)
			(type default)
		)
		(layer "In3.Cu")
	)
	(gr_line
		(start 385.287266 -5.366512)
		(end 385.287266 -2.750312)
		(stroke
			(width 0.1016)
			(type default)
		)
		(layer "In3.Cu")
	)
	(gr_line
		(start 385.287266 -2.750312)
		(end 385.287266 -5.417312)
		(stroke
			(width 0.1016)
			(type default)
		)
		(layer "In3.Cu")
	)
	(gr_line
		(start 385.287266 -2.750312)
		(end 386.481066 -2.750312)
		(stroke
			(width 0.1016)
			(type default)
		)
		(layer "In3.Cu")
	)
	(gr_line
		(start 385.312666 -13.7668)
		(end 385.312666 -11.176)
		(stroke
			(width 0.1016)
			(type default)
		)
		(layer "In3.Cu")
	)
	(gr_line
		(start 385.312666 -11.176)
		(end 386.455666 -11.176)
		(stroke
			(width 0.1016)
			(type default)
		)
		(layer "In3.Cu")
	)
	(gr_line
		(start 385.312666 -9.566656)
		(end 385.312666 -6.975856)
		(stroke
			(width 0.1016)
			(type default)
		)
		(layer "In3.Cu")
	)
	(gr_line
		(start 385.312666 -6.975856)
		(end 386.455666 -6.975856)
		(stroke
			(width 0.1016)
			(type default)
		)
		(layer "In3.Cu")
	)
	(gr_line
		(start 385.312666 -5.366512)
		(end 385.312666 -2.775712)
		(stroke
			(width 0.1016)
			(type default)
		)
		(layer "In3.Cu")
	)
	(gr_line
		(start 385.312666 -2.775712)
		(end 386.455666 -2.775712)
		(stroke
			(width 0.1016)
			(type default)
		)
		(layer "In3.Cu")
	)
	(gr_line
		(start 385.338066 -13.7668)
		(end 385.338066 -11.2014)
		(stroke
			(width 0.1016)
			(type default)
		)
		(layer "In3.Cu")
	)
	(gr_line
		(start 385.338066 -11.2014)
		(end 385.592066 -11.2014)
		(stroke
			(width 0.1016)
			(type default)
		)
		(layer "In3.Cu")
	)
	(gr_line
		(start 385.338066 -9.566656)
		(end 385.338066 -7.001256)
		(stroke
			(width 0.1016)
			(type default)
		)
		(layer "In3.Cu")
	)
	(gr_line
		(start 385.338066 -7.001256)
		(end 385.592066 -7.001256)
		(stroke
			(width 0.1016)
			(type default)
		)
		(layer "In3.Cu")
	)
	(gr_line
		(start 385.338066 -5.366512)
		(end 385.338066 -2.801112)
		(stroke
			(width 0.1016)
			(type default)
		)
		(layer "In3.Cu")
	)
	(gr_line
		(start 385.338066 -2.801112)
		(end 385.592066 -2.801112)
		(stroke
			(width 0.1016)
			(type default)
		)
		(layer "In3.Cu")
	)
	(gr_line
		(start 385.363466 -13.7668)
		(end 385.363466 -11.2014)
		(stroke
			(width 0.2032)
			(type default)
		)
		(layer "In3.Cu")
	)
	(gr_line
		(start 385.363466 -11.2014)
		(end 386.379466 -11.2014)
		(stroke
			(width 0.2032)
			(type default)
		)
		(layer "In3.Cu")
	)
	(gr_line
		(start 385.363466 -9.566656)
		(end 385.363466 -7.001256)
		(stroke
			(width 0.2032)
			(type default)
		)
		(layer "In3.Cu")
	)
	(gr_line
		(start 385.363466 -7.001256)
		(end 386.379466 -7.001256)
		(stroke
			(width 0.2032)
			(type default)
		)
		(layer "In3.Cu")
	)
	(gr_line
		(start 385.363466 -5.366512)
		(end 385.363466 -2.801112)
		(stroke
			(width 0.2032)
			(type default)
		)
		(layer "In3.Cu")
	)
	(gr_line
		(start 385.363466 -2.801112)
		(end 386.379466 -2.801112)
		(stroke
			(width 0.2032)
			(type default)
		)
		(layer "In3.Cu")
	)
	(gr_line
		(start 385.414266 -13.7414)
		(end 385.414266 -11.2522)
		(stroke
			(width 0.2032)
			(type default)
		)
		(layer "In3.Cu")
	)
	(gr_line
		(start 385.414266 -13.7414)
		(end 385.414266 -11.2522)
		(stroke
			(width 0.254)
			(type default)
		)
		(layer "In3.Cu")
	)
	(gr_line
		(start 385.414266 -11.2522)
		(end 385.617466 -11.2522)
		(stroke
			(width 0.2032)
			(type default)
		)
		(layer "In3.Cu")
	)
	(gr_line
		(start 385.414266 -11.2522)
		(end 386.303266 -11.2522)
		(stroke
			(width 0.254)
			(type default)
		)
		(layer "In3.Cu")
	)
	(gr_line
		(start 385.414266 -9.541256)
		(end 385.414266 -7.052056)
		(stroke
			(width 0.2032)
			(type default)
		)
		(layer "In3.Cu")
	)
	(gr_line
		(start 385.414266 -9.541256)
		(end 385.414266 -7.052056)
		(stroke
			(width 0.254)
			(type default)
		)
		(layer "In3.Cu")
	)
	(gr_line
		(start 385.414266 -7.052056)
		(end 385.617466 -7.052056)
		(stroke
			(width 0.2032)
			(type default)
		)
		(layer "In3.Cu")
	)
	(gr_line
		(start 385.414266 -7.052056)
		(end 386.303266 -7.052056)
		(stroke
			(width 0.254)
			(type default)
		)
		(layer "In3.Cu")
	)
	(gr_line
		(start 385.414266 -5.341112)
		(end 385.414266 -2.851912)
		(stroke
			(width 0.2032)
			(type default)
		)
		(layer "In3.Cu")
	)
	(gr_line
		(start 385.414266 -5.341112)
		(end 385.414266 -2.851912)
		(stroke
			(width 0.254)
			(type default)
		)
		(layer "In3.Cu")
	)
	(gr_line
		(start 385.414266 -2.851912)
		(end 385.617466 -2.851912)
		(stroke
			(width 0.2032)
			(type default)
		)
		(layer "In3.Cu")
	)
	(gr_line
		(start 385.414266 -2.851912)
		(end 386.303266 -2.851912)
		(stroke
			(width 0.254)
			(type default)
		)
		(layer "In3.Cu")
	)
	(gr_line
		(start 385.439666 -13.716)
		(end 385.439666 -11.2776)
		(stroke
			(width 0.254)
			(type default)
		)
		(layer "In3.Cu")
	)
	(gr_line
		(start 385.439666 -11.2776)
		(end 386.277866 -11.2776)
		(stroke
			(width 0.254)
			(type default)
		)
		(layer "In3.Cu")
	)
	(gr_line
		(start 385.439666 -9.515856)
		(end 385.439666 -7.077456)
		(stroke
			(width 0.254)
			(type default)
		)
		(layer "In3.Cu")
	)
	(gr_line
		(start 385.439666 -7.077456)
		(end 386.277866 -7.077456)
		(stroke
			(width 0.254)
			(type default)
		)
		(layer "In3.Cu")
	)
	(gr_line
		(start 385.439666 -5.315712)
		(end 385.439666 -2.877312)
		(stroke
			(width 0.254)
			(type default)
		)
		(layer "In3.Cu")
	)
	(gr_line
		(start 385.439666 -2.877312)
		(end 386.277866 -2.877312)
		(stroke
			(width 0.254)
			(type default)
		)
		(layer "In3.Cu")
	)
	(gr_line
		(start 385.465066 -13.6906)
		(end 385.465066 -11.303)
		(stroke
			(width 0.254)
			(type default)
		)
		(layer "In3.Cu")
	)
	(gr_line
		(start 385.465066 -11.303)
		(end 386.252466 -11.303)
		(stroke
			(width 0.254)
			(type default)
		)
		(layer "In3.Cu")
	)
	(gr_line
		(start 385.465066 -9.490456)
		(end 385.465066 -7.102856)
		(stroke
			(width 0.254)
			(type default)
		)
		(layer "In3.Cu")
	)
	(gr_line
		(start 385.465066 -7.102856)
		(end 386.252466 -7.102856)
		(stroke
			(width 0.254)
			(type default)
		)
		(layer "In3.Cu")
	)
	(gr_line
		(start 385.465066 -5.290312)
		(end 385.465066 -2.902712)
		(stroke
			(width 0.254)
			(type default)
		)
		(layer "In3.Cu")
	)
	(gr_line
		(start 385.465066 -2.902712)
		(end 386.252466 -2.902712)
		(stroke
			(width 0.254)
			(type default)
		)
		(layer "In3.Cu")
	)
	(gr_line
		(start 385.490466 -13.6144)
		(end 386.125466 -13.6144)
		(stroke
			(width 0.508)
			(type default)
		)
		(layer "In3.Cu")
	)
	(gr_line
		(start 385.490466 -11.43)
		(end 386.125466 -11.43)
		(stroke
			(width 0.508)
			(type default)
		)
		(layer "In3.Cu")
	)
	(gr_line
		(start 385.490466 -11.3792)
		(end 386.125466 -11.3792)
		(stroke
			(width 0.508)
			(type default)
		)
		(layer "In3.Cu")
	)
	(gr_line
		(start 385.490466 -9.414256)
		(end 386.125466 -9.414256)
		(stroke
			(width 0.508)
			(type default)
		)
		(layer "In3.Cu")
	)
	(gr_line
		(start 385.490466 -7.229856)
		(end 386.125466 -7.229856)
		(stroke
			(width 0.508)
			(type default)
		)
		(layer "In3.Cu")
	)
	(gr_line
		(start 385.490466 -7.179056)
		(end 386.125466 -7.179056)
		(stroke
			(width 0.508)
			(type default)
		)
		(layer "In3.Cu")
	)
	(gr_line
		(start 385.490466 -5.214112)
		(end 386.125466 -5.214112)
		(stroke
			(width 0.508)
			(type default)
		)
		(layer "In3.Cu")
	)
	(gr_line
		(start 385.490466 -3.029712)
		(end 386.125466 -3.029712)
		(stroke
			(width 0.508)
			(type default)
		)
		(layer "In3.Cu")
	)
	(gr_line
		(start 385.490466 -2.978912)
		(end 386.125466 -2.978912)
		(stroke
			(width 0.508)
			(type default)
		)
		(layer "In3.Cu")
	)
	(gr_line
		(start 385.515866 -11.684)
		(end 386.150866 -11.684)
		(stroke
			(width 0.508)
			(type default)
		)
		(layer "In3.Cu")
	)
	(gr_line
		(start 385.515866 -7.483856)
		(end 386.150866 -7.483856)
		(stroke
			(width 0.508)
			(type default)
		)
		(layer "In3.Cu")
	)
	(gr_line
		(start 385.515866 -3.283712)
		(end 386.150866 -3.283712)
		(stroke
			(width 0.508)
			(type default)
		)
		(layer "In3.Cu")
	)
	(gr_line
		(start 385.541266 -13.6398)
		(end 385.541266 -11.3792)
		(stroke
			(width 0.254)
			(type default)
		)
		(layer "In3.Cu")
	)
	(gr_line
		(start 385.541266 -13.4874)
		(end 386.176266 -13.4874)
		(stroke
			(width 0.508)
			(type default)
		)
		(layer "In3.Cu")
	)
	(gr_line
		(start 385.541266 -11.3792)
		(end 386.176266 -11.3792)
		(stroke
			(width 0.254)
			(type default)
		)
		(layer "In3.Cu")
	)
	(gr_line
		(start 385.541266 -9.439656)
		(end 385.541266 -7.179056)
		(stroke
			(width 0.254)
			(type default)
		)
		(layer "In3.Cu")
	)
	(gr_line
		(start 385.541266 -9.287256)
		(end 386.176266 -9.287256)
		(stroke
			(width 0.508)
			(type default)
		)
		(layer "In3.Cu")
	)
	(gr_line
		(start 385.541266 -7.179056)
		(end 386.176266 -7.179056)
		(stroke
			(width 0.254)
			(type default)
		)
		(layer "In3.Cu")
	)
	(gr_line
		(start 385.541266 -5.239512)
		(end 385.541266 -2.978912)
		(stroke
			(width 0.254)
			(type default)
		)
		(layer "In3.Cu")
	)
	(gr_line
		(start 385.541266 -5.087112)
		(end 386.176266 -5.087112)
		(stroke
			(width 0.508)
			(type default)
		)
		(layer "In3.Cu")
	)
	(gr_line
		(start 385.541266 -2.978912)
		(end 386.176266 -2.978912)
		(stroke
			(width 0.254)
			(type default)
		)
		(layer "In3.Cu")
	)
	(gr_line
		(start 385.566666 -13.335)
		(end 386.201666 -13.335)
		(stroke
			(width 0.508)
			(type default)
		)
		(layer "In3.Cu")
	)
	(gr_line
		(start 385.566666 -9.134856)
		(end 386.201666 -9.134856)
		(stroke
			(width 0.508)
			(type default)
		)
		(layer "In3.Cu")
	)
	(gr_line
		(start 385.566666 -4.934712)
		(end 386.201666 -4.934712)
		(stroke
			(width 0.508)
			(type default)
		)
		(layer "In3.Cu")
	)
	(gr_line
		(start 385.592066 -13.6144)
		(end 386.227066 -13.6144)
		(stroke
			(width 0.508)
			(type default)
		)
		(layer "In3.Cu")
	)
	(gr_line
		(start 385.592066 -11.2014)
		(end 386.430266 -11.2014)
		(stroke
			(width 0.2032)
			(type default)
		)
		(layer "In3.Cu")
	)
	(gr_line
		(start 385.592066 -9.414256)
		(end 386.227066 -9.414256)
		(stroke
			(width 0.508)
			(type default)
		)
		(layer "In3.Cu")
	)
	(gr_line
		(start 385.592066 -7.001256)
		(end 386.430266 -7.001256)
		(stroke
			(width 0.2032)
			(type default)
		)
		(layer "In3.Cu")
	)
	(gr_line
		(start 385.592066 -5.214112)
		(end 386.227066 -5.214112)
		(stroke
			(width 0.508)
			(type default)
		)
		(layer "In3.Cu")
	)
	(gr_line
		(start 385.592066 -2.801112)
		(end 386.430266 -2.801112)
		(stroke
			(width 0.2032)
			(type default)
		)
		(layer "In3.Cu")
	)
	(gr_line
		(start 385.617466 -13.6144)
		(end 385.617466 -11.43)
		(stroke
			(width 0.254)
			(type default)
		)
		(layer "In3.Cu")
	)
	(gr_line
		(start 385.617466 -11.43)
		(end 386.100066 -11.43)
		(stroke
			(width 0.254)
			(type default)
		)
		(layer "In3.Cu")
	)
	(gr_line
		(start 385.617466 -11.2522)
		(end 386.354066 -11.2522)
		(stroke
			(width 0.254)
			(type default)
		)
		(layer "In3.Cu")
	)
	(gr_line
		(start 385.617466 -9.414256)
		(end 385.617466 -7.229856)
		(stroke
			(width 0.254)
			(type default)
		)
		(layer "In3.Cu")
	)
	(gr_line
		(start 385.617466 -7.229856)
		(end 386.100066 -7.229856)
		(stroke
			(width 0.254)
			(type default)
		)
		(layer "In3.Cu")
	)
	(gr_line
		(start 385.617466 -7.052056)
		(end 386.354066 -7.052056)
		(stroke
			(width 0.254)
			(type default)
		)
		(layer "In3.Cu")
	)
	(gr_line
		(start 385.617466 -5.214112)
		(end 385.617466 -3.029712)
		(stroke
			(width 0.254)
			(type default)
		)
		(layer "In3.Cu")
	)
	(gr_line
		(start 385.617466 -3.029712)
		(end 386.100066 -3.029712)
		(stroke
			(width 0.254)
			(type default)
		)
		(layer "In3.Cu")
	)
	(gr_line
		(start 385.617466 -2.851912)
		(end 386.354066 -2.851912)
		(stroke
			(width 0.254)
			(type default)
		)
		(layer "In3.Cu")
	)
	(gr_line
		(start 385.636008 -11.36523)
		(end 386.271008 -11.36523)
		(stroke
			(width 0.508)
			(type default)
		)
		(layer "In3.Cu")
	)
	(gr_line
		(start 385.636008 -7.165086)
		(end 386.271008 -7.165086)
		(stroke
			(width 0.508)
			(type default)
		)
		(layer "In3.Cu")
	)
	(gr_line
		(start 385.636008 -2.964942)
		(end 386.271008 -2.964942)
		(stroke
			(width 0.508)
			(type default)
		)
		(layer "In3.Cu")
	)
	(gr_line
		(start 385.642866 -13.6144)
		(end 386.277866 -13.6144)
		(stroke
			(width 0.508)
			(type default)
		)
		(layer "In3.Cu")
	)
	(gr_line
		(start 385.642866 -13.4874)
		(end 385.642866 -11.5062)
		(stroke
			(width 0.762)
			(type default)
		)
		(layer "In3.Cu")
	)
	(gr_line
		(start 385.642866 -11.5062)
		(end 386.277866 -11.5062)
		(stroke
			(width 0.508)
			(type default)
		)
		(layer "In3.Cu")
	)
	(gr_line
		(start 385.642866 -9.414256)
		(end 386.277866 -9.414256)
		(stroke
			(width 0.508)
			(type default)
		)
		(layer "In3.Cu")
	)
	(gr_line
		(start 385.642866 -9.287256)
		(end 385.642866 -7.306056)
		(stroke
			(width 0.762)
			(type default)
		)
		(layer "In3.Cu")
	)
	(gr_line
		(start 385.642866 -7.306056)
		(end 386.277866 -7.306056)
		(stroke
			(width 0.508)
			(type default)
		)
		(layer "In3.Cu")
	)
	(gr_line
		(start 385.642866 -5.214112)
		(end 386.277866 -5.214112)
		(stroke
			(width 0.508)
			(type default)
		)
		(layer "In3.Cu")
	)
	(gr_line
		(start 385.642866 -5.087112)
		(end 385.642866 -3.105912)
		(stroke
			(width 0.762)
			(type default)
		)
		(layer "In3.Cu")
	)
	(gr_line
		(start 385.642866 -3.105912)
		(end 386.277866 -3.105912)
		(stroke
			(width 0.508)
			(type default)
		)
		(layer "In3.Cu")
	)
	(gr_line
		(start 385.693666 -13.5382)
		(end 385.693666 -11.5062)
		(stroke
			(width 0.254)
			(type default)
		)
		(layer "In3.Cu")
	)
	(gr_line
		(start 385.693666 -11.5062)
		(end 386.023866 -11.5062)
		(stroke
			(width 0.254)
			(type default)
		)
		(layer "In3.Cu")
	)
	(gr_line
		(start 385.693666 -9.338056)
		(end 385.693666 -7.306056)
		(stroke
			(width 0.254)
			(type default)
		)
		(layer "In3.Cu")
	)
	(gr_line
		(start 385.693666 -7.306056)
		(end 386.023866 -7.306056)
		(stroke
			(width 0.254)
			(type default)
		)
		(layer "In3.Cu")
	)
	(gr_line
		(start 385.693666 -5.137912)
		(end 385.693666 -3.105912)
		(stroke
			(width 0.254)
			(type default)
		)
		(layer "In3.Cu")
	)
	(gr_line
		(start 385.693666 -3.105912)
		(end 386.023866 -3.105912)
		(stroke
			(width 0.254)
			(type default)
		)
		(layer "In3.Cu")
	)
	(gr_line
		(start 385.795266 -13.462)
		(end 385.795266 -11.6586)
		(stroke
			(width 0.254)
			(type default)
		)
		(layer "In3.Cu")
	)
	(gr_line
		(start 385.795266 -13.462)
		(end 385.795266 -11.4808)
		(stroke
			(width 0.762)
			(type default)
		)
		(layer "In3.Cu")
	)
	(gr_line
		(start 385.795266 -11.6586)
		(end 385.896866 -11.6586)
		(stroke
			(width 0.254)
			(type default)
		)
		(layer "In3.Cu")
	)
	(gr_line
		(start 385.795266 -9.261856)
		(end 385.795266 -7.458456)
		(stroke
			(width 0.254)
			(type default)
		)
		(layer "In3.Cu")
	)
	(gr_line
		(start 385.795266 -9.261856)
		(end 385.795266 -7.280656)
		(stroke
			(width 0.762)
			(type default)
		)
		(layer "In3.Cu")
	)
	(gr_line
		(start 385.795266 -7.458456)
		(end 385.896866 -7.458456)
		(stroke
			(width 0.254)
			(type default)
		)
		(layer "In3.Cu")
	)
	(gr_line
		(start 385.795266 -5.061712)
		(end 385.795266 -3.258312)
		(stroke
			(width 0.254)
			(type default)
		)
		(layer "In3.Cu")
	)
	(gr_line
		(start 385.795266 -5.061712)
		(end 385.795266 -3.080512)
		(stroke
			(width 0.762)
			(type default)
		)
		(layer "In3.Cu")
	)
	(gr_line
		(start 385.795266 -3.258312)
		(end 385.896866 -3.258312)
		(stroke
			(width 0.254)
			(type default)
		)
		(layer "In3.Cu")
	)
	(gr_line
		(start 385.896866 -13.5636)
		(end 385.846066 -13.5636)
		(stroke
			(width 0.254)
			(type default)
		)
		(layer "In3.Cu")
	)
	(gr_line
		(start 385.896866 -11.6586)
		(end 385.896866 -13.5636)
		(stroke
			(width 0.254)
			(type default)
		)
		(layer "In3.Cu")
	)
	(gr_line
		(start 385.896866 -9.363456)
		(end 385.846066 -9.363456)
		(stroke
			(width 0.254)
			(type default)
		)
		(layer "In3.Cu")
	)
	(gr_line
		(start 385.896866 -7.458456)
		(end 385.896866 -9.363456)
		(stroke
			(width 0.254)
			(type default)
		)
		(layer "In3.Cu")
	)
	(gr_line
		(start 385.896866 -5.163312)
		(end 385.846066 -5.163312)
		(stroke
			(width 0.254)
			(type default)
		)
		(layer "In3.Cu")
	)
	(gr_line
		(start 385.896866 -3.258312)
		(end 385.896866 -5.163312)
		(stroke
			(width 0.254)
			(type default)
		)
		(layer "In3.Cu")
	)
	(gr_line
		(start 385.947666 -13.4874)
		(end 385.947666 -11.5062)
		(stroke
			(width 0.762)
			(type default)
		)
		(layer "In3.Cu")
	)
	(gr_line
		(start 385.947666 -9.287256)
		(end 385.947666 -7.306056)
		(stroke
			(width 0.762)
			(type default)
		)
		(layer "In3.Cu")
	)
	(gr_line
		(start 385.947666 -5.087112)
		(end 385.947666 -3.105912)
		(stroke
			(width 0.762)
			(type default)
		)
		(layer "In3.Cu")
	)
	(gr_line
		(start 386.023866 -13.462)
		(end 385.795266 -13.462)
		(stroke
			(width 0.254)
			(type default)
		)
		(layer "In3.Cu")
	)
	(gr_line
		(start 386.023866 -11.5062)
		(end 386.023866 -13.462)
		(stroke
			(width 0.254)
			(type default)
		)
		(layer "In3.Cu")
	)
	(gr_line
		(start 386.023866 -9.261856)
		(end 385.795266 -9.261856)
		(stroke
			(width 0.254)
			(type default)
		)
		(layer "In3.Cu")
	)
	(gr_line
		(start 386.023866 -7.306056)
		(end 386.023866 -9.261856)
		(stroke
			(width 0.254)
			(type default)
		)
		(layer "In3.Cu")
	)
	(gr_line
		(start 386.023866 -5.061712)
		(end 385.795266 -5.061712)
		(stroke
			(width 0.254)
			(type default)
		)
		(layer "In3.Cu")
	)
	(gr_line
		(start 386.023866 -3.105912)
		(end 386.023866 -5.061712)
		(stroke
			(width 0.254)
			(type default)
		)
		(layer "In3.Cu")
	)
	(gr_line
		(start 386.074666 -13.8176)
		(end 386.074666 -13.7668)
		(stroke
			(width 0.1016)
			(type default)
		)
		(layer "In3.Cu")
	)
	(gr_line
		(start 386.074666 -13.8176)
		(end 386.481066 -13.8176)
		(stroke
			(width 0.1016)
			(type default)
		)
		(layer "In3.Cu")
	)
	(gr_line
		(start 386.074666 -13.7668)
		(end 385.312666 -13.7668)
		(stroke
			(width 0.1016)
			(type default)
		)
		(layer "In3.Cu")
	)
	(gr_line
		(start 386.074666 -13.4874)
		(end 386.074666 -11.5062)
		(stroke
			(width 0.762)
			(type default)
		)
		(layer "In3.Cu")
	)
	(gr_line
		(start 386.074666 -9.617456)
		(end 386.074666 -9.566656)
		(stroke
			(width 0.1016)
			(type default)
		)
		(layer "In3.Cu")
	)
	(gr_line
		(start 386.074666 -9.617456)
		(end 386.481066 -9.617456)
		(stroke
			(width 0.1016)
			(type default)
		)
		(layer "In3.Cu")
	)
	(gr_line
		(start 386.074666 -9.566656)
		(end 385.312666 -9.566656)
		(stroke
			(width 0.1016)
			(type default)
		)
		(layer "In3.Cu")
	)
	(gr_line
		(start 386.074666 -9.287256)
		(end 386.074666 -7.306056)
		(stroke
			(width 0.762)
			(type default)
		)
		(layer "In3.Cu")
	)
	(gr_line
		(start 386.074666 -5.417312)
		(end 386.074666 -5.366512)
		(stroke
			(width 0.1016)
			(type default)
		)
		(layer "In3.Cu")
	)
	(gr_line
		(start 386.074666 -5.417312)
		(end 386.481066 -5.417312)
		(stroke
			(width 0.1016)
			(type default)
		)
		(layer "In3.Cu")
	)
	(gr_line
		(start 386.074666 -5.366512)
		(end 385.312666 -5.366512)
		(stroke
			(width 0.1016)
			(type default)
		)
		(layer "In3.Cu")
	)
	(gr_line
		(start 386.074666 -5.087112)
		(end 386.074666 -3.105912)
		(stroke
			(width 0.762)
			(type default)
		)
		(layer "In3.Cu")
	)
	(gr_line
		(start 386.100066 -13.5382)
		(end 385.693666 -13.5382)
		(stroke
			(width 0.254)
			(type default)
		)
		(layer "In3.Cu")
	)
	(gr_line
		(start 386.100066 -11.43)
		(end 386.100066 -13.5382)
		(stroke
			(width 0.254)
			(type default)
		)
		(layer "In3.Cu")
	)
	(gr_line
		(start 386.100066 -9.338056)
		(end 385.693666 -9.338056)
		(stroke
			(width 0.254)
			(type default)
		)
		(layer "In3.Cu")
	)
	(gr_line
		(start 386.100066 -7.229856)
		(end 386.100066 -9.338056)
		(stroke
			(width 0.254)
			(type default)
		)
		(layer "In3.Cu")
	)
	(gr_line
		(start 386.100066 -5.137912)
		(end 385.693666 -5.137912)
		(stroke
			(width 0.254)
			(type default)
		)
		(layer "In3.Cu")
	)
	(gr_line
		(start 386.100066 -3.029712)
		(end 386.100066 -5.137912)
		(stroke
			(width 0.254)
			(type default)
		)
		(layer "In3.Cu")
	)
	(gr_line
		(start 386.150866 -13.4874)
		(end 386.150866 -11.5062)
		(stroke
			(width 0.762)
			(type default)
		)
		(layer "In3.Cu")
	)
	(gr_line
		(start 386.150866 -9.287256)
		(end 386.150866 -7.306056)
		(stroke
			(width 0.762)
			(type default)
		)
		(layer "In3.Cu")
	)
	(gr_line
		(start 386.150866 -5.087112)
		(end 386.150866 -3.105912)
		(stroke
			(width 0.762)
			(type default)
		)
		(layer "In3.Cu")
	)
	(gr_line
		(start 386.176266 -13.6144)
		(end 385.617466 -13.6144)
		(stroke
			(width 0.254)
			(type default)
		)
		(layer "In3.Cu")
	)
	(gr_line
		(start 386.176266 -11.3792)
		(end 386.176266 -13.6144)
		(stroke
			(width 0.254)
			(type default)
		)
		(layer "In3.Cu")
	)
	(gr_line
		(start 386.176266 -9.414256)
		(end 385.617466 -9.414256)
		(stroke
			(width 0.254)
			(type default)
		)
		(layer "In3.Cu")
	)
	(gr_line
		(start 386.176266 -7.179056)
		(end 386.176266 -9.414256)
		(stroke
			(width 0.254)
			(type default)
		)
		(layer "In3.Cu")
	)
	(gr_line
		(start 386.176266 -5.214112)
		(end 385.617466 -5.214112)
		(stroke
			(width 0.254)
			(type default)
		)
		(layer "In3.Cu")
	)
	(gr_line
		(start 386.176266 -2.978912)
		(end 386.176266 -5.214112)
		(stroke
			(width 0.254)
			(type default)
		)
		(layer "In3.Cu")
	)
	(gr_line
		(start 386.252466 -13.6398)
		(end 385.541266 -13.6398)
		(stroke
			(width 0.254)
			(type default)
		)
		(layer "In3.Cu")
	)
	(gr_line
		(start 386.252466 -11.303)
		(end 386.252466 -13.6398)
		(stroke
			(width 0.254)
			(type default)
		)
		(layer "In3.Cu")
	)
	(gr_line
		(start 386.252466 -9.439656)
		(end 385.541266 -9.439656)
		(stroke
			(width 0.254)
			(type default)
		)
		(layer "In3.Cu")
	)
	(gr_line
		(start 386.252466 -7.102856)
		(end 386.252466 -9.439656)
		(stroke
			(width 0.254)
			(type default)
		)
		(layer "In3.Cu")
	)
	(gr_line
		(start 386.252466 -5.239512)
		(end 385.541266 -5.239512)
		(stroke
			(width 0.254)
			(type default)
		)
		(layer "In3.Cu")
	)
	(gr_line
		(start 386.252466 -2.902712)
		(end 386.252466 -5.239512)
		(stroke
			(width 0.254)
			(type default)
		)
		(layer "In3.Cu")
	)
	(gr_line
		(start 386.277866 -13.7668)
		(end 385.287266 -13.7668)
		(stroke
			(width 0.1016)
			(type default)
		)
		(layer "In3.Cu")
	)
	(gr_line
		(start 386.277866 -13.6906)
		(end 385.465066 -13.6906)
		(stroke
			(width 0.254)
			(type default)
		)
		(layer "In3.Cu")
	)
	(gr_line
		(start 386.277866 -11.2776)
		(end 386.277866 -13.6906)
		(stroke
			(width 0.254)
			(type default)
		)
		(layer "In3.Cu")
	)
	(gr_line
		(start 386.277866 -9.566656)
		(end 385.287266 -9.566656)
		(stroke
			(width 0.1016)
			(type default)
		)
		(layer "In3.Cu")
	)
	(gr_line
		(start 386.277866 -9.490456)
		(end 385.465066 -9.490456)
		(stroke
			(width 0.254)
			(type default)
		)
		(layer "In3.Cu")
	)
	(gr_line
		(start 386.277866 -7.077456)
		(end 386.277866 -9.490456)
		(stroke
			(width 0.254)
			(type default)
		)
		(layer "In3.Cu")
	)
	(gr_line
		(start 386.277866 -5.366512)
		(end 385.287266 -5.366512)
		(stroke
			(width 0.1016)
			(type default)
		)
		(layer "In3.Cu")
	)
	(gr_line
		(start 386.277866 -5.290312)
		(end 385.465066 -5.290312)
		(stroke
			(width 0.254)
			(type default)
		)
		(layer "In3.Cu")
	)
	(gr_line
		(start 386.277866 -2.877312)
		(end 386.277866 -5.290312)
		(stroke
			(width 0.254)
			(type default)
		)
		(layer "In3.Cu")
	)
	(gr_line
		(start 386.303266 -13.716)
		(end 385.439666 -13.716)
		(stroke
			(width 0.254)
			(type default)
		)
		(layer "In3.Cu")
	)
	(gr_line
		(start 386.303266 -11.2522)
		(end 386.303266 -13.716)
		(stroke
			(width 0.254)
			(type default)
		)
		(layer "In3.Cu")
	)
	(gr_line
		(start 386.303266 -9.515856)
		(end 385.439666 -9.515856)
		(stroke
			(width 0.254)
			(type default)
		)
		(layer "In3.Cu")
	)
	(gr_line
		(start 386.303266 -7.052056)
		(end 386.303266 -9.515856)
		(stroke
			(width 0.254)
			(type default)
		)
		(layer "In3.Cu")
	)
	(gr_line
		(start 386.303266 -5.315712)
		(end 385.439666 -5.315712)
		(stroke
			(width 0.254)
			(type default)
		)
		(layer "In3.Cu")
	)
	(gr_line
		(start 386.303266 -2.851912)
		(end 386.303266 -5.315712)
		(stroke
			(width 0.254)
			(type default)
		)
		(layer "In3.Cu")
	)
	(gr_line
		(start 386.354066 -13.7414)
		(end 385.414266 -13.7414)
		(stroke
			(width 0.254)
			(type default)
		)
		(layer "In3.Cu")
	)
	(gr_line
		(start 386.354066 -11.2522)
		(end 386.354066 -13.7414)
		(stroke
			(width 0.254)
			(type default)
		)
		(layer "In3.Cu")
	)
	(gr_line
		(start 386.354066 -9.541256)
		(end 385.414266 -9.541256)
		(stroke
			(width 0.254)
			(type default)
		)
		(layer "In3.Cu")
	)
	(gr_line
		(start 386.354066 -7.052056)
		(end 386.354066 -9.541256)
		(stroke
			(width 0.254)
			(type default)
		)
		(layer "In3.Cu")
	)
	(gr_line
		(start 386.354066 -5.341112)
		(end 385.414266 -5.341112)
		(stroke
			(width 0.254)
			(type default)
		)
		(layer "In3.Cu")
	)
	(gr_line
		(start 386.354066 -2.851912)
		(end 386.354066 -5.341112)
		(stroke
			(width 0.254)
			(type default)
		)
		(layer "In3.Cu")
	)
	(gr_line
		(start 386.379466 -13.7414)
		(end 385.414266 -13.7414)
		(stroke
			(width 0.2032)
			(type default)
		)
		(layer "In3.Cu")
	)
	(gr_line
		(start 386.379466 -11.2014)
		(end 386.379466 -13.7414)
		(stroke
			(width 0.2032)
			(type default)
		)
		(layer "In3.Cu")
	)
	(gr_line
		(start 386.379466 -9.541256)
		(end 385.414266 -9.541256)
		(stroke
			(width 0.2032)
			(type default)
		)
		(layer "In3.Cu")
	)
	(gr_line
		(start 386.379466 -7.001256)
		(end 386.379466 -9.541256)
		(stroke
			(width 0.2032)
			(type default)
		)
		(layer "In3.Cu")
	)
	(gr_line
		(start 386.379466 -5.341112)
		(end 385.414266 -5.341112)
		(stroke
			(width 0.2032)
			(type default)
		)
		(layer "In3.Cu")
	)
	(gr_line
		(start 386.379466 -2.801112)
		(end 386.379466 -5.341112)
		(stroke
			(width 0.2032)
			(type default)
		)
		(layer "In3.Cu")
	)
	(gr_line
		(start 386.430266 -13.7668)
		(end 385.363466 -13.7668)
		(stroke
			(width 0.2032)
			(type default)
		)
		(layer "In3.Cu")
	)
	(gr_line
		(start 386.430266 -11.2014)
		(end 386.430266 -13.7668)
		(stroke
			(width 0.2032)
			(type default)
		)
		(layer "In3.Cu")
	)
	(gr_line
		(start 386.430266 -9.566656)
		(end 385.363466 -9.566656)
		(stroke
			(width 0.2032)
			(type default)
		)
		(layer "In3.Cu")
	)
	(gr_line
		(start 386.430266 -7.001256)
		(end 386.430266 -9.566656)
		(stroke
			(width 0.2032)
			(type default)
		)
		(layer "In3.Cu")
	)
	(gr_line
		(start 386.430266 -5.366512)
		(end 385.363466 -5.366512)
		(stroke
			(width 0.2032)
			(type default)
		)
		(layer "In3.Cu")
	)
	(gr_line
		(start 386.430266 -2.801112)
		(end 386.430266 -5.366512)
		(stroke
			(width 0.2032)
			(type default)
		)
		(layer "In3.Cu")
	)
	(gr_line
		(start 386.455666 -13.7668)
		(end 385.338066 -13.7668)
		(stroke
			(width 0.1016)
			(type default)
		)
		(layer "In3.Cu")
	)
	(gr_line
		(start 386.455666 -11.176)
		(end 386.455666 -13.7668)
		(stroke
			(width 0.1016)
			(type default)
		)
		(layer "In3.Cu")
	)
	(gr_line
		(start 386.455666 -9.566656)
		(end 385.338066 -9.566656)
		(stroke
			(width 0.1016)
			(type default)
		)
		(layer "In3.Cu")
	)
	(gr_line
		(start 386.455666 -6.975856)
		(end 386.455666 -9.566656)
		(stroke
			(width 0.1016)
			(type default)
		)
		(layer "In3.Cu")
	)
	(gr_line
		(start 386.455666 -5.366512)
		(end 385.338066 -5.366512)
		(stroke
			(width 0.1016)
			(type default)
		)
		(layer "In3.Cu")
	)
	(gr_line
		(start 386.455666 -2.775712)
		(end 386.455666 -5.366512)
		(stroke
			(width 0.1016)
			(type default)
		)
		(layer "In3.Cu")
	)
	(gr_line
		(start 386.481066 -13.8176)
		(end 386.074666 -13.8176)
		(stroke
			(width 0.1016)
			(type default)
		)
		(layer "In3.Cu")
	)
	(gr_line
		(start 386.481066 -13.8176)
		(end 386.481066 -11.1506)
		(stroke
			(width 0.1016)
			(type default)
		)
		(layer "In3.Cu")
	)
	(gr_line
		(start 386.481066 -11.1506)
		(end 385.287266 -11.1506)
		(stroke
			(width 0.1016)
			(type default)
		)
		(layer "In3.Cu")
	)
	(gr_line
		(start 386.481066 -11.1506)
		(end 386.481066 -13.8176)
		(stroke
			(width 0.1016)
			(type default)
		)
		(layer "In3.Cu")
	)
	(gr_line
		(start 386.481066 -9.617456)
		(end 386.074666 -9.617456)
		(stroke
			(width 0.1016)
			(type default)
		)
		(layer "In3.Cu")
	)
	(gr_line
		(start 386.481066 -9.617456)
		(end 386.481066 -6.950456)
		(stroke
			(width 0.1016)
			(type default)
		)
		(layer "In3.Cu")
	)
	(gr_line
		(start 386.481066 -6.950456)
		(end 385.287266 -6.950456)
		(stroke
			(width 0.1016)
			(type default)
		)
		(layer "In3.Cu")
	)
	(gr_line
		(start 386.481066 -6.950456)
		(end 386.481066 -9.617456)
		(stroke
			(width 0.1016)
			(type default)
		)
		(layer "In3.Cu")
	)
	(gr_line
		(start 386.481066 -5.417312)
		(end 386.074666 -5.417312)
		(stroke
			(width 0.1016)
			(type default)
		)
		(layer "In3.Cu")
	)
	(gr_line
		(start 386.481066 -5.417312)
		(end 386.481066 -2.750312)
		(stroke
			(width 0.1016)
			(type default)
		)
		(layer "In3.Cu")
	)
	(gr_line
		(start 386.481066 -2.750312)
		(end 385.287266 -2.750312)
		(stroke
			(width 0.1016)
			(type default)
		)
		(layer "In3.Cu")
	)
	(gr_line
		(start 386.481066 -2.750312)
		(end 386.481066 -5.417312)
		(stroke
			(width 0.1016)
			(type default)
		)
		(layer "In3.Cu")
	)
	(gr_line
		(start 387.217666 -24.6634)
		(end 387.217666 -23.3934)
		(stroke
			(width 0.7874)
			(type default)
		)
		(layer "In3.Cu")
	)
	(gr_line
		(start 387.287262 -12.563348)
		(end 388.074662 -12.563348)
		(stroke
			(width 0.1016)
			(type default)
		)
		(layer "In3.Cu")
	)
	(gr_line
		(start 387.287262 -12.512548)
		(end 387.287262 -9.896348)
		(stroke
			(width 0.1016)
			(type default)
		)
		(layer "In3.Cu")
	)
	(gr_line
		(start 387.287262 -12.463272)
		(end 388.074662 -12.463272)
		(stroke
			(width 0.1016)
			(type default)
		)
		(layer "In3.Cu")
	)
	(gr_line
		(start 387.287262 -12.412472)
		(end 387.287262 -9.796272)
		(stroke
			(width 0.1016)
			(type default)
		)
		(layer "In3.Cu")
	)
	(gr_line
		(start 387.287262 -9.896348)
		(end 387.287262 -12.563348)
		(stroke
			(width 0.1016)
			(type default)
		)
		(layer "In3.Cu")
	)
	(gr_line
		(start 387.287262 -9.896348)
		(end 388.481062 -9.896348)
		(stroke
			(width 0.1016)
			(type default)
		)
		(layer "In3.Cu")
	)
	(gr_line
		(start 387.287262 -9.796272)
		(end 387.287262 -12.463272)
		(stroke
			(width 0.1016)
			(type default)
		)
		(layer "In3.Cu")
	)
	(gr_line
		(start 387.287262 -9.796272)
		(end 388.481062 -9.796272)
		(stroke
			(width 0.1016)
			(type default)
		)
		(layer "In3.Cu")
	)
	(gr_line
		(start 387.287262 -8.363204)
		(end 388.074662 -8.363204)
		(stroke
			(width 0.1016)
			(type default)
		)
		(layer "In3.Cu")
	)
	(gr_line
		(start 387.287262 -8.312404)
		(end 387.287262 -5.696204)
		(stroke
			(width 0.1016)
			(type default)
		)
		(layer "In3.Cu")
	)
	(gr_line
		(start 387.287262 -8.263128)
		(end 388.074662 -8.263128)
		(stroke
			(width 0.1016)
			(type default)
		)
		(layer "In3.Cu")
	)
	(gr_line
		(start 387.287262 -8.212328)
		(end 387.287262 -5.596128)
		(stroke
			(width 0.1016)
			(type default)
		)
		(layer "In3.Cu")
	)
	(gr_line
		(start 387.287262 -5.696204)
		(end 387.287262 -8.363204)
		(stroke
			(width 0.1016)
			(type default)
		)
		(layer "In3.Cu")
	)
	(gr_line
		(start 387.287262 -5.696204)
		(end 388.481062 -5.696204)
		(stroke
			(width 0.1016)
			(type default)
		)
		(layer "In3.Cu")
	)
	(gr_line
		(start 387.287262 -5.596128)
		(end 387.287262 -8.263128)
		(stroke
			(width 0.1016)
			(type default)
		)
		(layer "In3.Cu")
	)
	(gr_line
		(start 387.287262 -5.596128)
		(end 388.481062 -5.596128)
		(stroke
			(width 0.1016)
			(type default)
		)
		(layer "In3.Cu")
	)
	(gr_line
		(start 387.287262 -4.16306)
		(end 388.074662 -4.16306)
		(stroke
			(width 0.1016)
			(type default)
		)
		(layer "In3.Cu")
	)
	(gr_line
		(start 387.287262 -4.11226)
		(end 387.287262 -1.49606)
		(stroke
			(width 0.1016)
			(type default)
		)
		(layer "In3.Cu")
	)
	(gr_line
		(start 387.287262 -4.062984)
		(end 388.074662 -4.062984)
		(stroke
			(width 0.1016)
			(type default)
		)
		(layer "In3.Cu")
	)
	(gr_line
		(start 387.287262 -4.012184)
		(end 387.287262 -1.395984)
		(stroke
			(width 0.1016)
			(type default)
		)
		(layer "In3.Cu")
	)
	(gr_line
		(start 387.287262 -1.49606)
		(end 387.287262 -4.16306)
		(stroke
			(width 0.1016)
			(type default)
		)
		(layer "In3.Cu")
	)
	(gr_line
		(start 387.287262 -1.49606)
		(end 388.481062 -1.49606)
		(stroke
			(width 0.1016)
			(type default)
		)
		(layer "In3.Cu")
	)
	(gr_line
		(start 387.287262 -1.395984)
		(end 387.287262 -4.062984)
		(stroke
			(width 0.1016)
			(type default)
		)
		(layer "In3.Cu")
	)
	(gr_line
		(start 387.287262 -1.395984)
		(end 388.481062 -1.395984)
		(stroke
			(width 0.1016)
			(type default)
		)
		(layer "In3.Cu")
	)
	(gr_line
		(start 387.312662 -12.512548)
		(end 387.312662 -9.921748)
		(stroke
			(width 0.1016)
			(type default)
		)
		(layer "In3.Cu")
	)
	(gr_line
		(start 387.312662 -12.412472)
		(end 387.312662 -9.821672)
		(stroke
			(width 0.1016)
			(type default)
		)
		(layer "In3.Cu")
	)
	(gr_line
		(start 387.312662 -9.921748)
		(end 388.455662 -9.921748)
		(stroke
			(width 0.1016)
			(type default)
		)
		(layer "In3.Cu")
	)
	(gr_line
		(start 387.312662 -9.821672)
		(end 388.455662 -9.821672)
		(stroke
			(width 0.1016)
			(type default)
		)
		(layer "In3.Cu")
	)
	(gr_line
		(start 387.312662 -8.312404)
		(end 387.312662 -5.721604)
		(stroke
			(width 0.1016)
			(type default)
		)
		(layer "In3.Cu")
	)
	(gr_line
		(start 387.312662 -8.212328)
		(end 387.312662 -5.621528)
		(stroke
			(width 0.1016)
			(type default)
		)
		(layer "In3.Cu")
	)
	(gr_line
		(start 387.312662 -5.721604)
		(end 388.455662 -5.721604)
		(stroke
			(width 0.1016)
			(type default)
		)
		(layer "In3.Cu")
	)
	(gr_line
		(start 387.312662 -5.621528)
		(end 388.455662 -5.621528)
		(stroke
			(width 0.1016)
			(type default)
		)
		(layer "In3.Cu")
	)
	(gr_line
		(start 387.312662 -4.11226)
		(end 387.312662 -1.52146)
		(stroke
			(width 0.1016)
			(type default)
		)
		(layer "In3.Cu")
	)
	(gr_line
		(start 387.312662 -4.012184)
		(end 387.312662 -1.421384)
		(stroke
			(width 0.1016)
			(type default)
		)
		(layer "In3.Cu")
	)
	(gr_line
		(start 387.312662 -1.52146)
		(end 388.455662 -1.52146)
		(stroke
			(width 0.1016)
			(type default)
		)
		(layer "In3.Cu")
	)
	(gr_line
		(start 387.312662 -1.421384)
		(end 388.455662 -1.421384)
		(stroke
			(width 0.1016)
			(type default)
		)
		(layer "In3.Cu")
	)
	(gr_line
		(start 387.338062 -12.512548)
		(end 387.338062 -9.947148)
		(stroke
			(width 0.1016)
			(type default)
		)
		(layer "In3.Cu")
	)
	(gr_line
		(start 387.338062 -12.412472)
		(end 387.338062 -9.847072)
		(stroke
			(width 0.1016)
			(type default)
		)
		(layer "In3.Cu")
	)
	(gr_line
		(start 387.338062 -9.947148)
		(end 387.592062 -9.947148)
		(stroke
			(width 0.1016)
			(type default)
		)
		(layer "In3.Cu")
	)
	(gr_line
		(start 387.338062 -9.847072)
		(end 387.592062 -9.847072)
		(stroke
			(width 0.1016)
			(type default)
		)
		(layer "In3.Cu")
	)
	(gr_line
		(start 387.338062 -8.312404)
		(end 387.338062 -5.747004)
		(stroke
			(width 0.1016)
			(type default)
		)
		(layer "In3.Cu")
	)
	(gr_line
		(start 387.338062 -8.212328)
		(end 387.338062 -5.646928)
		(stroke
			(width 0.1016)
			(type default)
		)
		(layer "In3.Cu")
	)
	(gr_line
		(start 387.338062 -5.747004)
		(end 387.592062 -5.747004)
		(stroke
			(width 0.1016)
			(type default)
		)
		(layer "In3.Cu")
	)
	(gr_line
		(start 387.338062 -5.646928)
		(end 387.592062 -5.646928)
		(stroke
			(width 0.1016)
			(type default)
		)
		(layer "In3.Cu")
	)
	(gr_line
		(start 387.338062 -4.11226)
		(end 387.338062 -1.54686)
		(stroke
			(width 0.1016)
			(type default)
		)
		(layer "In3.Cu")
	)
	(gr_line
		(start 387.338062 -4.012184)
		(end 387.338062 -1.446784)
		(stroke
			(width 0.1016)
			(type default)
		)
		(layer "In3.Cu")
	)
	(gr_line
		(start 387.338062 -1.54686)
		(end 387.592062 -1.54686)
		(stroke
			(width 0.1016)
			(type default)
		)
		(layer "In3.Cu")
	)
	(gr_line
		(start 387.338062 -1.446784)
		(end 387.592062 -1.446784)
		(stroke
			(width 0.1016)
			(type default)
		)
		(layer "In3.Cu")
	)
	(gr_line
		(start 387.363462 -12.512548)
		(end 387.363462 -9.947148)
		(stroke
			(width 0.2032)
			(type default)
		)
		(layer "In3.Cu")
	)
	(gr_line
		(start 387.363462 -12.412472)
		(end 387.363462 -9.847072)
		(stroke
			(width 0.2032)
			(type default)
		)
		(layer "In3.Cu")
	)
	(gr_line
		(start 387.363462 -9.947148)
		(end 388.379462 -9.947148)
		(stroke
			(width 0.2032)
			(type default)
		)
		(layer "In3.Cu")
	)
	(gr_line
		(start 387.363462 -9.847072)
		(end 388.379462 -9.847072)
		(stroke
			(width 0.2032)
			(type default)
		)
		(layer "In3.Cu")
	)
	(gr_line
		(start 387.363462 -8.312404)
		(end 387.363462 -5.747004)
		(stroke
			(width 0.2032)
			(type default)
		)
		(layer "In3.Cu")
	)
	(gr_line
		(start 387.363462 -8.212328)
		(end 387.363462 -5.646928)
		(stroke
			(width 0.2032)
			(type default)
		)
		(layer "In3.Cu")
	)
	(gr_line
		(start 387.363462 -5.747004)
		(end 388.379462 -5.747004)
		(stroke
			(width 0.2032)
			(type default)
		)
		(layer "In3.Cu")
	)
	(gr_line
		(start 387.363462 -5.646928)
		(end 388.379462 -5.646928)
		(stroke
			(width 0.2032)
			(type default)
		)
		(layer "In3.Cu")
	)
	(gr_line
		(start 387.363462 -4.11226)
		(end 387.363462 -1.54686)
		(stroke
			(width 0.2032)
			(type default)
		)
		(layer "In3.Cu")
	)
	(gr_line
		(start 387.363462 -4.012184)
		(end 387.363462 -1.446784)
		(stroke
			(width 0.2032)
			(type default)
		)
		(layer "In3.Cu")
	)
	(gr_line
		(start 387.363462 -1.54686)
		(end 388.379462 -1.54686)
		(stroke
			(width 0.2032)
			(type default)
		)
		(layer "In3.Cu")
	)
	(gr_line
		(start 387.363462 -1.446784)
		(end 388.379462 -1.446784)
		(stroke
			(width 0.2032)
			(type default)
		)
		(layer "In3.Cu")
	)
	(gr_line
		(start 387.414262 -12.487148)
		(end 387.414262 -9.997948)
		(stroke
			(width 0.2032)
			(type default)
		)
		(layer "In3.Cu")
	)
	(gr_line
		(start 387.414262 -12.487148)
		(end 387.414262 -9.997948)
		(stroke
			(width 0.254)
			(type default)
		)
		(layer "In3.Cu")
	)
	(gr_line
		(start 387.414262 -12.387072)
		(end 387.414262 -9.897872)
		(stroke
			(width 0.2032)
			(type default)
		)
		(layer "In3.Cu")
	)
	(gr_line
		(start 387.414262 -12.387072)
		(end 387.414262 -9.897872)
		(stroke
			(width 0.254)
			(type default)
		)
		(layer "In3.Cu")
	)
	(gr_line
		(start 387.414262 -9.997948)
		(end 387.617462 -9.997948)
		(stroke
			(width 0.2032)
			(type default)
		)
		(layer "In3.Cu")
	)
	(gr_line
		(start 387.414262 -9.997948)
		(end 388.303262 -9.997948)
		(stroke
			(width 0.254)
			(type default)
		)
		(layer "In3.Cu")
	)
	(gr_line
		(start 387.414262 -9.897872)
		(end 387.617462 -9.897872)
		(stroke
			(width 0.2032)
			(type default)
		)
		(layer "In3.Cu")
	)
	(gr_line
		(start 387.414262 -9.897872)
		(end 388.303262 -9.897872)
		(stroke
			(width 0.254)
			(type default)
		)
		(layer "In3.Cu")
	)
	(gr_line
		(start 387.414262 -8.287004)
		(end 387.414262 -5.797804)
		(stroke
			(width 0.2032)
			(type default)
		)
		(layer "In3.Cu")
	)
	(gr_line
		(start 387.414262 -8.287004)
		(end 387.414262 -5.797804)
		(stroke
			(width 0.254)
			(type default)
		)
		(layer "In3.Cu")
	)
	(gr_line
		(start 387.414262 -8.186928)
		(end 387.414262 -5.697728)
		(stroke
			(width 0.2032)
			(type default)
		)
		(layer "In3.Cu")
	)
	(gr_line
		(start 387.414262 -8.186928)
		(end 387.414262 -5.697728)
		(stroke
			(width 0.254)
			(type default)
		)
		(layer "In3.Cu")
	)
	(gr_line
		(start 387.414262 -5.797804)
		(end 387.617462 -5.797804)
		(stroke
			(width 0.2032)
			(type default)
		)
		(layer "In3.Cu")
	)
	(gr_line
		(start 387.414262 -5.797804)
		(end 388.303262 -5.797804)
		(stroke
			(width 0.254)
			(type default)
		)
		(layer "In3.Cu")
	)
	(gr_line
		(start 387.414262 -5.697728)
		(end 387.617462 -5.697728)
		(stroke
			(width 0.2032)
			(type default)
		)
		(layer "In3.Cu")
	)
	(gr_line
		(start 387.414262 -5.697728)
		(end 388.303262 -5.697728)
		(stroke
			(width 0.254)
			(type default)
		)
		(layer "In3.Cu")
	)
	(gr_line
		(start 387.414262 -4.08686)
		(end 387.414262 -1.59766)
		(stroke
			(width 0.2032)
			(type default)
		)
		(layer "In3.Cu")
	)
	(gr_line
		(start 387.414262 -4.08686)
		(end 387.414262 -1.59766)
		(stroke
			(width 0.254)
			(type default)
		)
		(layer "In3.Cu")
	)
	(gr_line
		(start 387.414262 -3.986784)
		(end 387.414262 -1.497584)
		(stroke
			(width 0.2032)
			(type default)
		)
		(layer "In3.Cu")
	)
	(gr_line
		(start 387.414262 -3.986784)
		(end 387.414262 -1.497584)
		(stroke
			(width 0.254)
			(type default)
		)
		(layer "In3.Cu")
	)
	(gr_line
		(start 387.414262 -1.59766)
		(end 387.617462 -1.59766)
		(stroke
			(width 0.2032)
			(type default)
		)
		(layer "In3.Cu")
	)
	(gr_line
		(start 387.414262 -1.59766)
		(end 388.303262 -1.59766)
		(stroke
			(width 0.254)
			(type default)
		)
		(layer "In3.Cu")
	)
	(gr_line
		(start 387.414262 -1.497584)
		(end 387.617462 -1.497584)
		(stroke
			(width 0.2032)
			(type default)
		)
		(layer "In3.Cu")
	)
	(gr_line
		(start 387.414262 -1.497584)
		(end 388.303262 -1.497584)
		(stroke
			(width 0.254)
			(type default)
		)
		(layer "In3.Cu")
	)
	(gr_line
		(start 387.439662 -12.461748)
		(end 387.439662 -10.023348)
		(stroke
			(width 0.254)
			(type default)
		)
		(layer "In3.Cu")
	)
	(gr_line
		(start 387.439662 -12.361672)
		(end 387.439662 -9.923272)
		(stroke
			(width 0.254)
			(type default)
		)
		(layer "In3.Cu")
	)
	(gr_line
		(start 387.439662 -10.023348)
		(end 388.277862 -10.023348)
		(stroke
			(width 0.254)
			(type default)
		)
		(layer "In3.Cu")
	)
	(gr_line
		(start 387.439662 -9.923272)
		(end 388.277862 -9.923272)
		(stroke
			(width 0.254)
			(type default)
		)
		(layer "In3.Cu")
	)
	(gr_line
		(start 387.439662 -8.261604)
		(end 387.439662 -5.823204)
		(stroke
			(width 0.254)
			(type default)
		)
		(layer "In3.Cu")
	)
	(gr_line
		(start 387.439662 -8.161528)
		(end 387.439662 -5.723128)
		(stroke
			(width 0.254)
			(type default)
		)
		(layer "In3.Cu")
	)
	(gr_line
		(start 387.439662 -5.823204)
		(end 388.277862 -5.823204)
		(stroke
			(width 0.254)
			(type default)
		)
		(layer "In3.Cu")
	)
	(gr_line
		(start 387.439662 -5.723128)
		(end 388.277862 -5.723128)
		(stroke
			(width 0.254)
			(type default)
		)
		(layer "In3.Cu")
	)
	(gr_line
		(start 387.439662 -4.06146)
		(end 387.439662 -1.62306)
		(stroke
			(width 0.254)
			(type default)
		)
		(layer "In3.Cu")
	)
	(gr_line
		(start 387.439662 -3.961384)
		(end 387.439662 -1.522984)
		(stroke
			(width 0.254)
			(type default)
		)
		(layer "In3.Cu")
	)
	(gr_line
		(start 387.439662 -1.62306)
		(end 388.277862 -1.62306)
		(stroke
			(width 0.254)
			(type default)
		)
		(layer "In3.Cu")
	)
	(gr_line
		(start 387.439662 -1.522984)
		(end 388.277862 -1.522984)
		(stroke
			(width 0.254)
			(type default)
		)
		(layer "In3.Cu")
	)
	(gr_line
		(start 387.465062 -12.436348)
		(end 387.465062 -10.048748)
		(stroke
			(width 0.254)
			(type default)
		)
		(layer "In3.Cu")
	)
	(gr_line
		(start 387.465062 -12.336272)
		(end 387.465062 -9.948672)
		(stroke
			(width 0.254)
			(type default)
		)
		(layer "In3.Cu")
	)
	(gr_line
		(start 387.465062 -10.048748)
		(end 388.252462 -10.048748)
		(stroke
			(width 0.254)
			(type default)
		)
		(layer "In3.Cu")
	)
	(gr_line
		(start 387.465062 -9.948672)
		(end 388.252462 -9.948672)
		(stroke
			(width 0.254)
			(type default)
		)
		(layer "In3.Cu")
	)
	(gr_line
		(start 387.465062 -8.236204)
		(end 387.465062 -5.848604)
		(stroke
			(width 0.254)
			(type default)
		)
		(layer "In3.Cu")
	)
	(gr_line
		(start 387.465062 -8.136128)
		(end 387.465062 -5.748528)
		(stroke
			(width 0.254)
			(type default)
		)
		(layer "In3.Cu")
	)
	(gr_line
		(start 387.465062 -5.848604)
		(end 388.252462 -5.848604)
		(stroke
			(width 0.254)
			(type default)
		)
		(layer "In3.Cu")
	)
	(gr_line
		(start 387.465062 -5.748528)
		(end 388.252462 -5.748528)
		(stroke
			(width 0.254)
			(type default)
		)
		(layer "In3.Cu")
	)
	(gr_line
		(start 387.465062 -4.03606)
		(end 387.465062 -1.64846)
		(stroke
			(width 0.254)
			(type default)
		)
		(layer "In3.Cu")
	)
	(gr_line
		(start 387.465062 -3.935984)
		(end 387.465062 -1.548384)
		(stroke
			(width 0.254)
			(type default)
		)
		(layer "In3.Cu")
	)
	(gr_line
		(start 387.465062 -1.64846)
		(end 388.252462 -1.64846)
		(stroke
			(width 0.254)
			(type default)
		)
		(layer "In3.Cu")
	)
	(gr_line
		(start 387.465062 -1.548384)
		(end 388.252462 -1.548384)
		(stroke
			(width 0.254)
			(type default)
		)
		(layer "In3.Cu")
	)
	(gr_line
		(start 387.490462 -12.360148)
		(end 388.125462 -12.360148)
		(stroke
			(width 0.508)
			(type default)
		)
		(layer "In3.Cu")
	)
	(gr_line
		(start 387.490462 -12.260072)
		(end 388.125462 -12.260072)
		(stroke
			(width 0.508)
			(type default)
		)
		(layer "In3.Cu")
	)
	(gr_line
		(start 387.490462 -10.175748)
		(end 388.125462 -10.175748)
		(stroke
			(width 0.508)
			(type default)
		)
		(layer "In3.Cu")
	)
	(gr_line
		(start 387.490462 -10.124948)
		(end 388.125462 -10.124948)
		(stroke
			(width 0.508)
			(type default)
		)
		(layer "In3.Cu")
	)
	(gr_line
		(start 387.490462 -10.075672)
		(end 388.125462 -10.075672)
		(stroke
			(width 0.508)
			(type default)
		)
		(layer "In3.Cu")
	)
	(gr_line
		(start 387.490462 -10.024872)
		(end 388.125462 -10.024872)
		(stroke
			(width 0.508)
			(type default)
		)
		(layer "In3.Cu")
	)
	(gr_line
		(start 387.490462 -8.160004)
		(end 388.125462 -8.160004)
		(stroke
			(width 0.508)
			(type default)
		)
		(layer "In3.Cu")
	)
	(gr_line
		(start 387.490462 -8.059928)
		(end 388.125462 -8.059928)
		(stroke
			(width 0.508)
			(type default)
		)
		(layer "In3.Cu")
	)
	(gr_line
		(start 387.490462 -5.975604)
		(end 388.125462 -5.975604)
		(stroke
			(width 0.508)
			(type default)
		)
		(layer "In3.Cu")
	)
	(gr_line
		(start 387.490462 -5.924804)
		(end 388.125462 -5.924804)
		(stroke
			(width 0.508)
			(type default)
		)
		(layer "In3.Cu")
	)
	(gr_line
		(start 387.490462 -5.875528)
		(end 388.125462 -5.875528)
		(stroke
			(width 0.508)
			(type default)
		)
		(layer "In3.Cu")
	)
	(gr_line
		(start 387.490462 -5.824728)
		(end 388.125462 -5.824728)
		(stroke
			(width 0.508)
			(type default)
		)
		(layer "In3.Cu")
	)
	(gr_line
		(start 387.490462 -3.95986)
		(end 388.125462 -3.95986)
		(stroke
			(width 0.508)
			(type default)
		)
		(layer "In3.Cu")
	)
	(gr_line
		(start 387.490462 -3.859784)
		(end 388.125462 -3.859784)
		(stroke
			(width 0.508)
			(type default)
		)
		(layer "In3.Cu")
	)
	(gr_line
		(start 387.490462 -1.77546)
		(end 388.125462 -1.77546)
		(stroke
			(width 0.508)
			(type default)
		)
		(layer "In3.Cu")
	)
	(gr_line
		(start 387.490462 -1.72466)
		(end 388.125462 -1.72466)
		(stroke
			(width 0.508)
			(type default)
		)
		(layer "In3.Cu")
	)
	(gr_line
		(start 387.490462 -1.675384)
		(end 388.125462 -1.675384)
		(stroke
			(width 0.508)
			(type default)
		)
		(layer "In3.Cu")
	)
	(gr_line
		(start 387.490462 -1.624584)
		(end 388.125462 -1.624584)
		(stroke
			(width 0.508)
			(type default)
		)
		(layer "In3.Cu")
	)
	(gr_line
		(start 387.515862 -10.429748)
		(end 388.150862 -10.429748)
		(stroke
			(width 0.508)
			(type default)
		)
		(layer "In3.Cu")
	)
	(gr_line
		(start 387.515862 -10.329672)
		(end 388.150862 -10.329672)
		(stroke
			(width 0.508)
			(type default)
		)
		(layer "In3.Cu")
	)
	(gr_line
		(start 387.515862 -6.229604)
		(end 388.150862 -6.229604)
		(stroke
			(width 0.508)
			(type default)
		)
		(layer "In3.Cu")
	)
	(gr_line
		(start 387.515862 -6.129528)
		(end 388.150862 -6.129528)
		(stroke
			(width 0.508)
			(type default)
		)
		(layer "In3.Cu")
	)
	(gr_line
		(start 387.515862 -2.02946)
		(end 388.150862 -2.02946)
		(stroke
			(width 0.508)
			(type default)
		)
		(layer "In3.Cu")
	)
	(gr_line
		(start 387.515862 -1.929384)
		(end 388.150862 -1.929384)
		(stroke
			(width 0.508)
			(type default)
		)
		(layer "In3.Cu")
	)
	(gr_line
		(start 387.541262 -12.385548)
		(end 387.541262 -10.124948)
		(stroke
			(width 0.254)
			(type default)
		)
		(layer "In3.Cu")
	)
	(gr_line
		(start 387.541262 -12.285472)
		(end 387.541262 -10.024872)
		(stroke
			(width 0.254)
			(type default)
		)
		(layer "In3.Cu")
	)
	(gr_line
		(start 387.541262 -12.233148)
		(end 388.176262 -12.233148)
		(stroke
			(width 0.508)
			(type default)
		)
		(layer "In3.Cu")
	)
	(gr_line
		(start 387.541262 -12.133072)
		(end 388.176262 -12.133072)
		(stroke
			(width 0.508)
			(type default)
		)
		(layer "In3.Cu")
	)
	(gr_line
		(start 387.541262 -10.124948)
		(end 388.176262 -10.124948)
		(stroke
			(width 0.254)
			(type default)
		)
		(layer "In3.Cu")
	)
	(gr_line
		(start 387.541262 -10.024872)
		(end 388.176262 -10.024872)
		(stroke
			(width 0.254)
			(type default)
		)
		(layer "In3.Cu")
	)
	(gr_line
		(start 387.541262 -8.185404)
		(end 387.541262 -5.924804)
		(stroke
			(width 0.254)
			(type default)
		)
		(layer "In3.Cu")
	)
	(gr_line
		(start 387.541262 -8.085328)
		(end 387.541262 -5.824728)
		(stroke
			(width 0.254)
			(type default)
		)
		(layer "In3.Cu")
	)
	(gr_line
		(start 387.541262 -8.033004)
		(end 388.176262 -8.033004)
		(stroke
			(width 0.508)
			(type default)
		)
		(layer "In3.Cu")
	)
	(gr_line
		(start 387.541262 -7.932928)
		(end 388.176262 -7.932928)
		(stroke
			(width 0.508)
			(type default)
		)
		(layer "In3.Cu")
	)
	(gr_line
		(start 387.541262 -5.924804)
		(end 388.176262 -5.924804)
		(stroke
			(width 0.254)
			(type default)
		)
		(layer "In3.Cu")
	)
	(gr_line
		(start 387.541262 -5.824728)
		(end 388.176262 -5.824728)
		(stroke
			(width 0.254)
			(type default)
		)
		(layer "In3.Cu")
	)
	(gr_line
		(start 387.541262 -3.98526)
		(end 387.541262 -1.72466)
		(stroke
			(width 0.254)
			(type default)
		)
		(layer "In3.Cu")
	)
	(gr_line
		(start 387.541262 -3.885184)
		(end 387.541262 -1.624584)
		(stroke
			(width 0.254)
			(type default)
		)
		(layer "In3.Cu")
	)
	(gr_line
		(start 387.541262 -3.83286)
		(end 388.176262 -3.83286)
		(stroke
			(width 0.508)
			(type default)
		)
		(layer "In3.Cu")
	)
	(gr_line
		(start 387.541262 -3.732784)
		(end 388.176262 -3.732784)
		(stroke
			(width 0.508)
			(type default)
		)
		(layer "In3.Cu")
	)
	(gr_line
		(start 387.541262 -1.72466)
		(end 388.176262 -1.72466)
		(stroke
			(width 0.254)
			(type default)
		)
		(layer "In3.Cu")
	)
	(gr_line
		(start 387.541262 -1.624584)
		(end 388.176262 -1.624584)
		(stroke
			(width 0.254)
			(type default)
		)
		(layer "In3.Cu")
	)
	(gr_line
		(start 387.566662 -12.080748)
		(end 388.201662 -12.080748)
		(stroke
			(width 0.508)
			(type default)
		)
		(layer "In3.Cu")
	)
	(gr_line
		(start 387.566662 -11.980672)
		(end 388.201662 -11.980672)
		(stroke
			(width 0.508)
			(type default)
		)
		(layer "In3.Cu")
	)
	(gr_line
		(start 387.566662 -7.880604)
		(end 388.201662 -7.880604)
		(stroke
			(width 0.508)
			(type default)
		)
		(layer "In3.Cu")
	)
	(gr_line
		(start 387.566662 -7.780528)
		(end 388.201662 -7.780528)
		(stroke
			(width 0.508)
			(type default)
		)
		(layer "In3.Cu")
	)
	(gr_line
		(start 387.566662 -3.68046)
		(end 388.201662 -3.68046)
		(stroke
			(width 0.508)
			(type default)
		)
		(layer "In3.Cu")
	)
	(gr_line
		(start 387.566662 -3.580384)
		(end 388.201662 -3.580384)
		(stroke
			(width 0.508)
			(type default)
		)
		(layer "In3.Cu")
	)
	(gr_line
		(start 387.592062 -12.360148)
		(end 388.227062 -12.360148)
		(stroke
			(width 0.508)
			(type default)
		)
		(layer "In3.Cu")
	)
	(gr_line
		(start 387.592062 -12.260072)
		(end 388.227062 -12.260072)
		(stroke
			(width 0.508)
			(type default)
		)
		(layer "In3.Cu")
	)
	(gr_line
		(start 387.592062 -9.947148)
		(end 388.430262 -9.947148)
		(stroke
			(width 0.2032)
			(type default)
		)
		(layer "In3.Cu")
	)
	(gr_line
		(start 387.592062 -9.847072)
		(end 388.430262 -9.847072)
		(stroke
			(width 0.2032)
			(type default)
		)
		(layer "In3.Cu")
	)
	(gr_line
		(start 387.592062 -8.160004)
		(end 388.227062 -8.160004)
		(stroke
			(width 0.508)
			(type default)
		)
		(layer "In3.Cu")
	)
	(gr_line
		(start 387.592062 -8.059928)
		(end 388.227062 -8.059928)
		(stroke
			(width 0.508)
			(type default)
		)
		(layer "In3.Cu")
	)
	(gr_line
		(start 387.592062 -5.747004)
		(end 388.430262 -5.747004)
		(stroke
			(width 0.2032)
			(type default)
		)
		(layer "In3.Cu")
	)
	(gr_line
		(start 387.592062 -5.646928)
		(end 388.430262 -5.646928)
		(stroke
			(width 0.2032)
			(type default)
		)
		(layer "In3.Cu")
	)
	(gr_line
		(start 387.592062 -3.95986)
		(end 388.227062 -3.95986)
		(stroke
			(width 0.508)
			(type default)
		)
		(layer "In3.Cu")
	)
	(gr_line
		(start 387.592062 -3.859784)
		(end 388.227062 -3.859784)
		(stroke
			(width 0.508)
			(type default)
		)
		(layer "In3.Cu")
	)
	(gr_line
		(start 387.592062 -1.54686)
		(end 388.430262 -1.54686)
		(stroke
			(width 0.2032)
			(type default)
		)
		(layer "In3.Cu")
	)
	(gr_line
		(start 387.592062 -1.446784)
		(end 388.430262 -1.446784)
		(stroke
			(width 0.2032)
			(type default)
		)
		(layer "In3.Cu")
	)
	(gr_line
		(start 387.617462 -12.360148)
		(end 387.617462 -10.175748)
		(stroke
			(width 0.254)
			(type default)
		)
		(layer "In3.Cu")
	)
	(gr_line
		(start 387.617462 -12.260072)
		(end 387.617462 -10.075672)
		(stroke
			(width 0.254)
			(type default)
		)
		(layer "In3.Cu")
	)
	(gr_line
		(start 387.617462 -10.175748)
		(end 388.100062 -10.175748)
		(stroke
			(width 0.254)
			(type default)
		)
		(layer "In3.Cu")
	)
	(gr_line
		(start 387.617462 -10.075672)
		(end 388.100062 -10.075672)
		(stroke
			(width 0.254)
			(type default)
		)
		(layer "In3.Cu")
	)
	(gr_line
		(start 387.617462 -9.997948)
		(end 388.354062 -9.997948)
		(stroke
			(width 0.254)
			(type default)
		)
		(layer "In3.Cu")
	)
	(gr_line
		(start 387.617462 -9.897872)
		(end 388.354062 -9.897872)
		(stroke
			(width 0.254)
			(type default)
		)
		(layer "In3.Cu")
	)
	(gr_line
		(start 387.617462 -8.160004)
		(end 387.617462 -5.975604)
		(stroke
			(width 0.254)
			(type default)
		)
		(layer "In3.Cu")
	)
	(gr_line
		(start 387.617462 -8.059928)
		(end 387.617462 -5.875528)
		(stroke
			(width 0.254)
			(type default)
		)
		(layer "In3.Cu")
	)
	(gr_line
		(start 387.617462 -5.975604)
		(end 388.100062 -5.975604)
		(stroke
			(width 0.254)
			(type default)
		)
		(layer "In3.Cu")
	)
	(gr_line
		(start 387.617462 -5.875528)
		(end 388.100062 -5.875528)
		(stroke
			(width 0.254)
			(type default)
		)
		(layer "In3.Cu")
	)
	(gr_line
		(start 387.617462 -5.797804)
		(end 388.354062 -5.797804)
		(stroke
			(width 0.254)
			(type default)
		)
		(layer "In3.Cu")
	)
	(gr_line
		(start 387.617462 -5.697728)
		(end 388.354062 -5.697728)
		(stroke
			(width 0.254)
			(type default)
		)
		(layer "In3.Cu")
	)
	(gr_line
		(start 387.617462 -3.95986)
		(end 387.617462 -1.77546)
		(stroke
			(width 0.254)
			(type default)
		)
		(layer "In3.Cu")
	)
	(gr_line
		(start 387.617462 -3.859784)
		(end 387.617462 -1.675384)
		(stroke
			(width 0.254)
			(type default)
		)
		(layer "In3.Cu")
	)
	(gr_line
		(start 387.617462 -1.77546)
		(end 388.100062 -1.77546)
		(stroke
			(width 0.254)
			(type default)
		)
		(layer "In3.Cu")
	)
	(gr_line
		(start 387.617462 -1.675384)
		(end 388.100062 -1.675384)
		(stroke
			(width 0.254)
			(type default)
		)
		(layer "In3.Cu")
	)
	(gr_line
		(start 387.617462 -1.59766)
		(end 388.354062 -1.59766)
		(stroke
			(width 0.254)
			(type default)
		)
		(layer "In3.Cu")
	)
	(gr_line
		(start 387.617462 -1.497584)
		(end 388.354062 -1.497584)
		(stroke
			(width 0.254)
			(type default)
		)
		(layer "In3.Cu")
	)
	(gr_line
		(start 387.636004 -10.110978)
		(end 388.271004 -10.110978)
		(stroke
			(width 0.508)
			(type default)
		)
		(layer "In3.Cu")
	)
	(gr_line
		(start 387.636004 -10.010902)
		(end 388.271004 -10.010902)
		(stroke
			(width 0.508)
			(type default)
		)
		(layer "In3.Cu")
	)
	(gr_line
		(start 387.636004 -5.910834)
		(end 388.271004 -5.910834)
		(stroke
			(width 0.508)
			(type default)
		)
		(layer "In3.Cu")
	)
	(gr_line
		(start 387.636004 -5.810758)
		(end 388.271004 -5.810758)
		(stroke
			(width 0.508)
			(type default)
		)
		(layer "In3.Cu")
	)
	(gr_line
		(start 387.636004 -1.71069)
		(end 388.271004 -1.71069)
		(stroke
			(width 0.508)
			(type default)
		)
		(layer "In3.Cu")
	)
	(gr_line
		(start 387.636004 -1.610614)
		(end 388.271004 -1.610614)
		(stroke
			(width 0.508)
			(type default)
		)
		(layer "In3.Cu")
	)
	(gr_line
		(start 387.642862 -12.360148)
		(end 388.277862 -12.360148)
		(stroke
			(width 0.508)
			(type default)
		)
		(layer "In3.Cu")
	)
	(gr_line
		(start 387.642862 -12.260072)
		(end 388.277862 -12.260072)
		(stroke
			(width 0.508)
			(type default)
		)
		(layer "In3.Cu")
	)
	(gr_line
		(start 387.642862 -12.233148)
		(end 387.642862 -10.251948)
		(stroke
			(width 0.762)
			(type default)
		)
		(layer "In3.Cu")
	)
	(gr_line
		(start 387.642862 -12.133072)
		(end 387.642862 -10.151872)
		(stroke
			(width 0.762)
			(type default)
		)
		(layer "In3.Cu")
	)
	(gr_line
		(start 387.642862 -10.251948)
		(end 388.277862 -10.251948)
		(stroke
			(width 0.508)
			(type default)
		)
		(layer "In3.Cu")
	)
	(gr_line
		(start 387.642862 -10.151872)
		(end 388.277862 -10.151872)
		(stroke
			(width 0.508)
			(type default)
		)
		(layer "In3.Cu")
	)
	(gr_line
		(start 387.642862 -8.160004)
		(end 388.277862 -8.160004)
		(stroke
			(width 0.508)
			(type default)
		)
		(layer "In3.Cu")
	)
	(gr_line
		(start 387.642862 -8.059928)
		(end 388.277862 -8.059928)
		(stroke
			(width 0.508)
			(type default)
		)
		(layer "In3.Cu")
	)
	(gr_line
		(start 387.642862 -8.033004)
		(end 387.642862 -6.051804)
		(stroke
			(width 0.762)
			(type default)
		)
		(layer "In3.Cu")
	)
	(gr_line
		(start 387.642862 -7.932928)
		(end 387.642862 -5.951728)
		(stroke
			(width 0.762)
			(type default)
		)
		(layer "In3.Cu")
	)
	(gr_line
		(start 387.642862 -6.051804)
		(end 388.277862 -6.051804)
		(stroke
			(width 0.508)
			(type default)
		)
		(layer "In3.Cu")
	)
	(gr_line
		(start 387.642862 -5.951728)
		(end 388.277862 -5.951728)
		(stroke
			(width 0.508)
			(type default)
		)
		(layer "In3.Cu")
	)
	(gr_line
		(start 387.642862 -3.95986)
		(end 388.277862 -3.95986)
		(stroke
			(width 0.508)
			(type default)
		)
		(layer "In3.Cu")
	)
	(gr_line
		(start 387.642862 -3.859784)
		(end 388.277862 -3.859784)
		(stroke
			(width 0.508)
			(type default)
		)
		(layer "In3.Cu")
	)
	(gr_line
		(start 387.642862 -3.83286)
		(end 387.642862 -1.85166)
		(stroke
			(width 0.762)
			(type default)
		)
		(layer "In3.Cu")
	)
	(gr_line
		(start 387.642862 -3.732784)
		(end 387.642862 -1.751584)
		(stroke
			(width 0.762)
			(type default)
		)
		(layer "In3.Cu")
	)
	(gr_line
		(start 387.642862 -1.85166)
		(end 388.277862 -1.85166)
		(stroke
			(width 0.508)
			(type default)
		)
		(layer "In3.Cu")
	)
	(gr_line
		(start 387.642862 -1.751584)
		(end 388.277862 -1.751584)
		(stroke
			(width 0.508)
			(type default)
		)
		(layer "In3.Cu")
	)
	(gr_line
		(start 387.693662 -12.283948)
		(end 387.693662 -10.251948)
		(stroke
			(width 0.254)
			(type default)
		)
		(layer "In3.Cu")
	)
	(gr_line
		(start 387.693662 -12.183872)
		(end 387.693662 -10.151872)
		(stroke
			(width 0.254)
			(type default)
		)
		(layer "In3.Cu")
	)
	(gr_line
		(start 387.693662 -10.251948)
		(end 388.023862 -10.251948)
		(stroke
			(width 0.254)
			(type default)
		)
		(layer "In3.Cu")
	)
	(gr_line
		(start 387.693662 -10.151872)
		(end 388.023862 -10.151872)
		(stroke
			(width 0.254)
			(type default)
		)
		(layer "In3.Cu")
	)
	(gr_line
		(start 387.693662 -8.083804)
		(end 387.693662 -6.051804)
		(stroke
			(width 0.254)
			(type default)
		)
		(layer "In3.Cu")
	)
	(gr_line
		(start 387.693662 -7.983728)
		(end 387.693662 -5.951728)
		(stroke
			(width 0.254)
			(type default)
		)
		(layer "In3.Cu")
	)
	(gr_line
		(start 387.693662 -6.051804)
		(end 388.023862 -6.051804)
		(stroke
			(width 0.254)
			(type default)
		)
		(layer "In3.Cu")
	)
	(gr_line
		(start 387.693662 -5.951728)
		(end 388.023862 -5.951728)
		(stroke
			(width 0.254)
			(type default)
		)
		(layer "In3.Cu")
	)
	(gr_line
		(start 387.693662 -3.88366)
		(end 387.693662 -1.85166)
		(stroke
			(width 0.254)
			(type default)
		)
		(layer "In3.Cu")
	)
	(gr_line
		(start 387.693662 -3.783584)
		(end 387.693662 -1.751584)
		(stroke
			(width 0.254)
			(type default)
		)
		(layer "In3.Cu")
	)
	(gr_line
		(start 387.693662 -1.85166)
		(end 388.023862 -1.85166)
		(stroke
			(width 0.254)
			(type default)
		)
		(layer "In3.Cu")
	)
	(gr_line
		(start 387.693662 -1.751584)
		(end 388.023862 -1.751584)
		(stroke
			(width 0.254)
			(type default)
		)
		(layer "In3.Cu")
	)
	(gr_line
		(start 387.795262 -12.207748)
		(end 387.795262 -10.404348)
		(stroke
			(width 0.254)
			(type default)
		)
		(layer "In3.Cu")
	)
	(gr_line
		(start 387.795262 -12.207748)
		(end 387.795262 -10.226548)
		(stroke
			(width 0.762)
			(type default)
		)
		(layer "In3.Cu")
	)
	(gr_line
		(start 387.795262 -12.107672)
		(end 387.795262 -10.304272)
		(stroke
			(width 0.254)
			(type default)
		)
		(layer "In3.Cu")
	)
	(gr_line
		(start 387.795262 -12.107672)
		(end 387.795262 -10.126472)
		(stroke
			(width 0.762)
			(type default)
		)
		(layer "In3.Cu")
	)
	(gr_line
		(start 387.795262 -10.404348)
		(end 387.896862 -10.404348)
		(stroke
			(width 0.254)
			(type default)
		)
		(layer "In3.Cu")
	)
	(gr_line
		(start 387.795262 -10.304272)
		(end 387.896862 -10.304272)
		(stroke
			(width 0.254)
			(type default)
		)
		(layer "In3.Cu")
	)
	(gr_line
		(start 387.795262 -8.007604)
		(end 387.795262 -6.204204)
		(stroke
			(width 0.254)
			(type default)
		)
		(layer "In3.Cu")
	)
	(gr_line
		(start 387.795262 -8.007604)
		(end 387.795262 -6.026404)
		(stroke
			(width 0.762)
			(type default)
		)
		(layer "In3.Cu")
	)
	(gr_line
		(start 387.795262 -7.907528)
		(end 387.795262 -6.104128)
		(stroke
			(width 0.254)
			(type default)
		)
		(layer "In3.Cu")
	)
	(gr_line
		(start 387.795262 -7.907528)
		(end 387.795262 -5.926328)
		(stroke
			(width 0.762)
			(type default)
		)
		(layer "In3.Cu")
	)
	(gr_line
		(start 387.795262 -6.204204)
		(end 387.896862 -6.204204)
		(stroke
			(width 0.254)
			(type default)
		)
		(layer "In3.Cu")
	)
	(gr_line
		(start 387.795262 -6.104128)
		(end 387.896862 -6.104128)
		(stroke
			(width 0.254)
			(type default)
		)
		(layer "In3.Cu")
	)
	(gr_line
		(start 387.795262 -3.80746)
		(end 387.795262 -2.00406)
		(stroke
			(width 0.254)
			(type default)
		)
		(layer "In3.Cu")
	)
	(gr_line
		(start 387.795262 -3.80746)
		(end 387.795262 -1.82626)
		(stroke
			(width 0.762)
			(type default)
		)
		(layer "In3.Cu")
	)
	(gr_line
		(start 387.795262 -3.707384)
		(end 387.795262 -1.903984)
		(stroke
			(width 0.254)
			(type default)
		)
		(layer "In3.Cu")
	)
	(gr_line
		(start 387.795262 -3.707384)
		(end 387.795262 -1.726184)
		(stroke
			(width 0.762)
			(type default)
		)
		(layer "In3.Cu")
	)
	(gr_line
		(start 387.795262 -2.00406)
		(end 387.896862 -2.00406)
		(stroke
			(width 0.254)
			(type default)
		)
		(layer "In3.Cu")
	)
	(gr_line
		(start 387.795262 -1.903984)
		(end 387.896862 -1.903984)
		(stroke
			(width 0.254)
			(type default)
		)
		(layer "In3.Cu")
	)
	(gr_line
		(start 387.896862 -12.309348)
		(end 387.846062 -12.309348)
		(stroke
			(width 0.254)
			(type default)
		)
		(layer "In3.Cu")
	)
	(gr_line
		(start 387.896862 -12.209272)
		(end 387.846062 -12.209272)
		(stroke
			(width 0.254)
			(type default)
		)
		(layer "In3.Cu")
	)
	(gr_line
		(start 387.896862 -10.404348)
		(end 387.896862 -12.309348)
		(stroke
			(width 0.254)
			(type default)
		)
		(layer "In3.Cu")
	)
	(gr_line
		(start 387.896862 -10.304272)
		(end 387.896862 -12.209272)
		(stroke
			(width 0.254)
			(type default)
		)
		(layer "In3.Cu")
	)
	(gr_line
		(start 387.896862 -8.109204)
		(end 387.846062 -8.109204)
		(stroke
			(width 0.254)
			(type default)
		)
		(layer "In3.Cu")
	)
	(gr_line
		(start 387.896862 -8.009128)
		(end 387.846062 -8.009128)
		(stroke
			(width 0.254)
			(type default)
		)
		(layer "In3.Cu")
	)
	(gr_line
		(start 387.896862 -6.204204)
		(end 387.896862 -8.109204)
		(stroke
			(width 0.254)
			(type default)
		)
		(layer "In3.Cu")
	)
	(gr_line
		(start 387.896862 -6.104128)
		(end 387.896862 -8.009128)
		(stroke
			(width 0.254)
			(type default)
		)
		(layer "In3.Cu")
	)
	(gr_line
		(start 387.896862 -3.90906)
		(end 387.846062 -3.90906)
		(stroke
			(width 0.254)
			(type default)
		)
		(layer "In3.Cu")
	)
	(gr_line
		(start 387.896862 -3.808984)
		(end 387.846062 -3.808984)
		(stroke
			(width 0.254)
			(type default)
		)
		(layer "In3.Cu")
	)
	(gr_line
		(start 387.896862 -2.00406)
		(end 387.896862 -3.90906)
		(stroke
			(width 0.254)
			(type default)
		)
		(layer "In3.Cu")
	)
	(gr_line
		(start 387.896862 -1.903984)
		(end 387.896862 -3.808984)
		(stroke
			(width 0.254)
			(type default)
		)
		(layer "In3.Cu")
	)
	(gr_line
		(start 387.947662 -12.233148)
		(end 387.947662 -10.251948)
		(stroke
			(width 0.762)
			(type default)
		)
		(layer "In3.Cu")
	)
	(gr_line
		(start 387.947662 -12.133072)
		(end 387.947662 -10.151872)
		(stroke
			(width 0.762)
			(type default)
		)
		(layer "In3.Cu")
	)
	(gr_line
		(start 387.947662 -8.033004)
		(end 387.947662 -6.051804)
		(stroke
			(width 0.762)
			(type default)
		)
		(layer "In3.Cu")
	)
	(gr_line
		(start 387.947662 -7.932928)
		(end 387.947662 -5.951728)
		(stroke
			(width 0.762)
			(type default)
		)
		(layer "In3.Cu")
	)
	(gr_line
		(start 387.947662 -3.83286)
		(end 387.947662 -1.85166)
		(stroke
			(width 0.762)
			(type default)
		)
		(layer "In3.Cu")
	)
	(gr_line
		(start 387.947662 -3.732784)
		(end 387.947662 -1.751584)
		(stroke
			(width 0.762)
			(type default)
		)
		(layer "In3.Cu")
	)
	(gr_line
		(start 388.023862 -12.207748)
		(end 387.795262 -12.207748)
		(stroke
			(width 0.254)
			(type default)
		)
		(layer "In3.Cu")
	)
	(gr_line
		(start 388.023862 -12.107672)
		(end 387.795262 -12.107672)
		(stroke
			(width 0.254)
			(type default)
		)
		(layer "In3.Cu")
	)
	(gr_line
		(start 388.023862 -10.251948)
		(end 388.023862 -12.207748)
		(stroke
			(width 0.254)
			(type default)
		)
		(layer "In3.Cu")
	)
	(gr_line
		(start 388.023862 -10.151872)
		(end 388.023862 -12.107672)
		(stroke
			(width 0.254)
			(type default)
		)
		(layer "In3.Cu")
	)
	(gr_line
		(start 388.023862 -8.007604)
		(end 387.795262 -8.007604)
		(stroke
			(width 0.254)
			(type default)
		)
		(layer "In3.Cu")
	)
	(gr_line
		(start 388.023862 -7.907528)
		(end 387.795262 -7.907528)
		(stroke
			(width 0.254)
			(type default)
		)
		(layer "In3.Cu")
	)
	(gr_line
		(start 388.023862 -6.051804)
		(end 388.023862 -8.007604)
		(stroke
			(width 0.254)
			(type default)
		)
		(layer "In3.Cu")
	)
	(gr_line
		(start 388.023862 -5.951728)
		(end 388.023862 -7.907528)
		(stroke
			(width 0.254)
			(type default)
		)
		(layer "In3.Cu")
	)
	(gr_line
		(start 388.023862 -3.80746)
		(end 387.795262 -3.80746)
		(stroke
			(width 0.254)
			(type default)
		)
		(layer "In3.Cu")
	)
	(gr_line
		(start 388.023862 -3.707384)
		(end 387.795262 -3.707384)
		(stroke
			(width 0.254)
			(type default)
		)
		(layer "In3.Cu")
	)
	(gr_line
		(start 388.023862 -1.85166)
		(end 388.023862 -3.80746)
		(stroke
			(width 0.254)
			(type default)
		)
		(layer "In3.Cu")
	)
	(gr_line
		(start 388.023862 -1.751584)
		(end 388.023862 -3.707384)
		(stroke
			(width 0.254)
			(type default)
		)
		(layer "In3.Cu")
	)
	(gr_line
		(start 388.074662 -12.563348)
		(end 388.074662 -12.512548)
		(stroke
			(width 0.1016)
			(type default)
		)
		(layer "In3.Cu")
	)
	(gr_line
		(start 388.074662 -12.563348)
		(end 388.481062 -12.563348)
		(stroke
			(width 0.1016)
			(type default)
		)
		(layer "In3.Cu")
	)
	(gr_line
		(start 388.074662 -12.512548)
		(end 387.312662 -12.512548)
		(stroke
			(width 0.1016)
			(type default)
		)
		(layer "In3.Cu")
	)
	(gr_line
		(start 388.074662 -12.463272)
		(end 388.074662 -12.412472)
		(stroke
			(width 0.1016)
			(type default)
		)
		(layer "In3.Cu")
	)
	(gr_line
		(start 388.074662 -12.463272)
		(end 388.481062 -12.463272)
		(stroke
			(width 0.1016)
			(type default)
		)
		(layer "In3.Cu")
	)
	(gr_line
		(start 388.074662 -12.412472)
		(end 387.312662 -12.412472)
		(stroke
			(width 0.1016)
			(type default)
		)
		(layer "In3.Cu")
	)
	(gr_line
		(start 388.074662 -12.233148)
		(end 388.074662 -10.251948)
		(stroke
			(width 0.762)
			(type default)
		)
		(layer "In3.Cu")
	)
	(gr_line
		(start 388.074662 -12.133072)
		(end 388.074662 -10.151872)
		(stroke
			(width 0.762)
			(type default)
		)
		(layer "In3.Cu")
	)
	(gr_line
		(start 388.074662 -8.363204)
		(end 388.074662 -8.312404)
		(stroke
			(width 0.1016)
			(type default)
		)
		(layer "In3.Cu")
	)
	(gr_line
		(start 388.074662 -8.363204)
		(end 388.481062 -8.363204)
		(stroke
			(width 0.1016)
			(type default)
		)
		(layer "In3.Cu")
	)
	(gr_line
		(start 388.074662 -8.312404)
		(end 387.312662 -8.312404)
		(stroke
			(width 0.1016)
			(type default)
		)
		(layer "In3.Cu")
	)
	(gr_line
		(start 388.074662 -8.263128)
		(end 388.074662 -8.212328)
		(stroke
			(width 0.1016)
			(type default)
		)
		(layer "In3.Cu")
	)
	(gr_line
		(start 388.074662 -8.263128)
		(end 388.481062 -8.263128)
		(stroke
			(width 0.1016)
			(type default)
		)
		(layer "In3.Cu")
	)
	(gr_line
		(start 388.074662 -8.212328)
		(end 387.312662 -8.212328)
		(stroke
			(width 0.1016)
			(type default)
		)
		(layer "In3.Cu")
	)
	(gr_line
		(start 388.074662 -8.033004)
		(end 388.074662 -6.051804)
		(stroke
			(width 0.762)
			(type default)
		)
		(layer "In3.Cu")
	)
	(gr_line
		(start 388.074662 -7.932928)
		(end 388.074662 -5.951728)
		(stroke
			(width 0.762)
			(type default)
		)
		(layer "In3.Cu")
	)
	(gr_line
		(start 388.074662 -4.16306)
		(end 388.074662 -4.11226)
		(stroke
			(width 0.1016)
			(type default)
		)
		(layer "In3.Cu")
	)
	(gr_line
		(start 388.074662 -4.16306)
		(end 388.481062 -4.16306)
		(stroke
			(width 0.1016)
			(type default)
		)
		(layer "In3.Cu")
	)
	(gr_line
		(start 388.074662 -4.11226)
		(end 387.312662 -4.11226)
		(stroke
			(width 0.1016)
			(type default)
		)
		(layer "In3.Cu")
	)
	(gr_line
		(start 388.074662 -4.062984)
		(end 388.074662 -4.012184)
		(stroke
			(width 0.1016)
			(type default)
		)
		(layer "In3.Cu")
	)
	(gr_line
		(start 388.074662 -4.062984)
		(end 388.481062 -4.062984)
		(stroke
			(width 0.1016)
			(type default)
		)
		(layer "In3.Cu")
	)
	(gr_line
		(start 388.074662 -4.012184)
		(end 387.312662 -4.012184)
		(stroke
			(width 0.1016)
			(type default)
		)
		(layer "In3.Cu")
	)
	(gr_line
		(start 388.074662 -3.83286)
		(end 388.074662 -1.85166)
		(stroke
			(width 0.762)
			(type default)
		)
		(layer "In3.Cu")
	)
	(gr_line
		(start 388.074662 -3.732784)
		(end 388.074662 -1.751584)
		(stroke
			(width 0.762)
			(type default)
		)
		(layer "In3.Cu")
	)
	(gr_line
		(start 388.100062 -12.283948)
		(end 387.693662 -12.283948)
		(stroke
			(width 0.254)
			(type default)
		)
		(layer "In3.Cu")
	)
	(gr_line
		(start 388.100062 -12.183872)
		(end 387.693662 -12.183872)
		(stroke
			(width 0.254)
			(type default)
		)
		(layer "In3.Cu")
	)
	(gr_line
		(start 388.100062 -10.175748)
		(end 388.100062 -12.283948)
		(stroke
			(width 0.254)
			(type default)
		)
		(layer "In3.Cu")
	)
	(gr_line
		(start 388.100062 -10.075672)
		(end 388.100062 -12.183872)
		(stroke
			(width 0.254)
			(type default)
		)
		(layer "In3.Cu")
	)
	(gr_line
		(start 388.100062 -8.083804)
		(end 387.693662 -8.083804)
		(stroke
			(width 0.254)
			(type default)
		)
		(layer "In3.Cu")
	)
	(gr_line
		(start 388.100062 -7.983728)
		(end 387.693662 -7.983728)
		(stroke
			(width 0.254)
			(type default)
		)
		(layer "In3.Cu")
	)
	(gr_line
		(start 388.100062 -5.975604)
		(end 388.100062 -8.083804)
		(stroke
			(width 0.254)
			(type default)
		)
		(layer "In3.Cu")
	)
	(gr_line
		(start 388.100062 -5.875528)
		(end 388.100062 -7.983728)
		(stroke
			(width 0.254)
			(type default)
		)
		(layer "In3.Cu")
	)
	(gr_line
		(start 388.100062 -3.88366)
		(end 387.693662 -3.88366)
		(stroke
			(width 0.254)
			(type default)
		)
		(layer "In3.Cu")
	)
	(gr_line
		(start 388.100062 -3.783584)
		(end 387.693662 -3.783584)
		(stroke
			(width 0.254)
			(type default)
		)
		(layer "In3.Cu")
	)
	(gr_line
		(start 388.100062 -1.77546)
		(end 388.100062 -3.88366)
		(stroke
			(width 0.254)
			(type default)
		)
		(layer "In3.Cu")
	)
	(gr_line
		(start 388.100062 -1.675384)
		(end 388.100062 -3.783584)
		(stroke
			(width 0.254)
			(type default)
		)
		(layer "In3.Cu")
	)
	(gr_line
		(start 388.150862 -12.233148)
		(end 388.150862 -10.251948)
		(stroke
			(width 0.762)
			(type default)
		)
		(layer "In3.Cu")
	)
	(gr_line
		(start 388.150862 -12.133072)
		(end 388.150862 -10.151872)
		(stroke
			(width 0.762)
			(type default)
		)
		(layer "In3.Cu")
	)
	(gr_line
		(start 388.150862 -8.033004)
		(end 388.150862 -6.051804)
		(stroke
			(width 0.762)
			(type default)
		)
		(layer "In3.Cu")
	)
	(gr_line
		(start 388.150862 -7.932928)
		(end 388.150862 -5.951728)
		(stroke
			(width 0.762)
			(type default)
		)
		(layer "In3.Cu")
	)
	(gr_line
		(start 388.150862 -3.83286)
		(end 388.150862 -1.85166)
		(stroke
			(width 0.762)
			(type default)
		)
		(layer "In3.Cu")
	)
	(gr_line
		(start 388.150862 -3.732784)
		(end 388.150862 -1.751584)
		(stroke
			(width 0.762)
			(type default)
		)
		(layer "In3.Cu")
	)
	(gr_line
		(start 388.176262 -12.360148)
		(end 387.617462 -12.360148)
		(stroke
			(width 0.254)
			(type default)
		)
		(layer "In3.Cu")
	)
	(gr_line
		(start 388.176262 -12.260072)
		(end 387.617462 -12.260072)
		(stroke
			(width 0.254)
			(type default)
		)
		(layer "In3.Cu")
	)
	(gr_line
		(start 388.176262 -10.124948)
		(end 388.176262 -12.360148)
		(stroke
			(width 0.254)
			(type default)
		)
		(layer "In3.Cu")
	)
	(gr_line
		(start 388.176262 -10.024872)
		(end 388.176262 -12.260072)
		(stroke
			(width 0.254)
			(type default)
		)
		(layer "In3.Cu")
	)
	(gr_line
		(start 388.176262 -8.160004)
		(end 387.617462 -8.160004)
		(stroke
			(width 0.254)
			(type default)
		)
		(layer "In3.Cu")
	)
	(gr_line
		(start 388.176262 -8.059928)
		(end 387.617462 -8.059928)
		(stroke
			(width 0.254)
			(type default)
		)
		(layer "In3.Cu")
	)
	(gr_line
		(start 388.176262 -5.924804)
		(end 388.176262 -8.160004)
		(stroke
			(width 0.254)
			(type default)
		)
		(layer "In3.Cu")
	)
	(gr_line
		(start 388.176262 -5.824728)
		(end 388.176262 -8.059928)
		(stroke
			(width 0.254)
			(type default)
		)
		(layer "In3.Cu")
	)
	(gr_line
		(start 388.176262 -3.95986)
		(end 387.617462 -3.95986)
		(stroke
			(width 0.254)
			(type default)
		)
		(layer "In3.Cu")
	)
	(gr_line
		(start 388.176262 -3.859784)
		(end 387.617462 -3.859784)
		(stroke
			(width 0.254)
			(type default)
		)
		(layer "In3.Cu")
	)
	(gr_line
		(start 388.176262 -1.72466)
		(end 388.176262 -3.95986)
		(stroke
			(width 0.254)
			(type default)
		)
		(layer "In3.Cu")
	)
	(gr_line
		(start 388.176262 -1.624584)
		(end 388.176262 -3.859784)
		(stroke
			(width 0.254)
			(type default)
		)
		(layer "In3.Cu")
	)
	(gr_line
		(start 388.252462 -12.385548)
		(end 387.541262 -12.385548)
		(stroke
			(width 0.254)
			(type default)
		)
		(layer "In3.Cu")
	)
	(gr_line
		(start 388.252462 -12.285472)
		(end 387.541262 -12.285472)
		(stroke
			(width 0.254)
			(type default)
		)
		(layer "In3.Cu")
	)
	(gr_line
		(start 388.252462 -10.048748)
		(end 388.252462 -12.385548)
		(stroke
			(width 0.254)
			(type default)
		)
		(layer "In3.Cu")
	)
	(gr_line
		(start 388.252462 -9.948672)
		(end 388.252462 -12.285472)
		(stroke
			(width 0.254)
			(type default)
		)
		(layer "In3.Cu")
	)
	(gr_line
		(start 388.252462 -8.185404)
		(end 387.541262 -8.185404)
		(stroke
			(width 0.254)
			(type default)
		)
		(layer "In3.Cu")
	)
	(gr_line
		(start 388.252462 -8.085328)
		(end 387.541262 -8.085328)
		(stroke
			(width 0.254)
			(type default)
		)
		(layer "In3.Cu")
	)
	(gr_line
		(start 388.252462 -5.848604)
		(end 388.252462 -8.185404)
		(stroke
			(width 0.254)
			(type default)
		)
		(layer "In3.Cu")
	)
	(gr_line
		(start 388.252462 -5.748528)
		(end 388.252462 -8.085328)
		(stroke
			(width 0.254)
			(type default)
		)
		(layer "In3.Cu")
	)
	(gr_line
		(start 388.252462 -3.98526)
		(end 387.541262 -3.98526)
		(stroke
			(width 0.254)
			(type default)
		)
		(layer "In3.Cu")
	)
	(gr_line
		(start 388.252462 -3.885184)
		(end 387.541262 -3.885184)
		(stroke
			(width 0.254)
			(type default)
		)
		(layer "In3.Cu")
	)
	(gr_line
		(start 388.252462 -1.64846)
		(end 388.252462 -3.98526)
		(stroke
			(width 0.254)
			(type default)
		)
		(layer "In3.Cu")
	)
	(gr_line
		(start 388.252462 -1.548384)
		(end 388.252462 -3.885184)
		(stroke
			(width 0.254)
			(type default)
		)
		(layer "In3.Cu")
	)
	(gr_line
		(start 388.277862 -12.512548)
		(end 387.287262 -12.512548)
		(stroke
			(width 0.1016)
			(type default)
		)
		(layer "In3.Cu")
	)
	(gr_line
		(start 388.277862 -12.436348)
		(end 387.465062 -12.436348)
		(stroke
			(width 0.254)
			(type default)
		)
		(layer "In3.Cu")
	)
	(gr_line
		(start 388.277862 -12.412472)
		(end 387.287262 -12.412472)
		(stroke
			(width 0.1016)
			(type default)
		)
		(layer "In3.Cu")
	)
	(gr_line
		(start 388.277862 -12.336272)
		(end 387.465062 -12.336272)
		(stroke
			(width 0.254)
			(type default)
		)
		(layer "In3.Cu")
	)
	(gr_line
		(start 388.277862 -10.023348)
		(end 388.277862 -12.436348)
		(stroke
			(width 0.254)
			(type default)
		)
		(layer "In3.Cu")
	)
	(gr_line
		(start 388.277862 -9.923272)
		(end 388.277862 -12.336272)
		(stroke
			(width 0.254)
			(type default)
		)
		(layer "In3.Cu")
	)
	(gr_line
		(start 388.277862 -8.312404)
		(end 387.287262 -8.312404)
		(stroke
			(width 0.1016)
			(type default)
		)
		(layer "In3.Cu")
	)
	(gr_line
		(start 388.277862 -8.236204)
		(end 387.465062 -8.236204)
		(stroke
			(width 0.254)
			(type default)
		)
		(layer "In3.Cu")
	)
	(gr_line
		(start 388.277862 -8.212328)
		(end 387.287262 -8.212328)
		(stroke
			(width 0.1016)
			(type default)
		)
		(layer "In3.Cu")
	)
	(gr_line
		(start 388.277862 -8.136128)
		(end 387.465062 -8.136128)
		(stroke
			(width 0.254)
			(type default)
		)
		(layer "In3.Cu")
	)
	(gr_line
		(start 388.277862 -5.823204)
		(end 388.277862 -8.236204)
		(stroke
			(width 0.254)
			(type default)
		)
		(layer "In3.Cu")
	)
	(gr_line
		(start 388.277862 -5.723128)
		(end 388.277862 -8.136128)
		(stroke
			(width 0.254)
			(type default)
		)
		(layer "In3.Cu")
	)
	(gr_line
		(start 388.277862 -4.11226)
		(end 387.287262 -4.11226)
		(stroke
			(width 0.1016)
			(type default)
		)
		(layer "In3.Cu")
	)
	(gr_line
		(start 388.277862 -4.03606)
		(end 387.465062 -4.03606)
		(stroke
			(width 0.254)
			(type default)
		)
		(layer "In3.Cu")
	)
	(gr_line
		(start 388.277862 -4.012184)
		(end 387.287262 -4.012184)
		(stroke
			(width 0.1016)
			(type default)
		)
		(layer "In3.Cu")
	)
	(gr_line
		(start 388.277862 -3.935984)
		(end 387.465062 -3.935984)
		(stroke
			(width 0.254)
			(type default)
		)
		(layer "In3.Cu")
	)
	(gr_line
		(start 388.277862 -1.62306)
		(end 388.277862 -4.03606)
		(stroke
			(width 0.254)
			(type default)
		)
		(layer "In3.Cu")
	)
	(gr_line
		(start 388.277862 -1.522984)
		(end 388.277862 -3.935984)
		(stroke
			(width 0.254)
			(type default)
		)
		(layer "In3.Cu")
	)
	(gr_line
		(start 388.303262 -12.461748)
		(end 387.439662 -12.461748)
		(stroke
			(width 0.254)
			(type default)
		)
		(layer "In3.Cu")
	)
	(gr_line
		(start 388.303262 -12.361672)
		(end 387.439662 -12.361672)
		(stroke
			(width 0.254)
			(type default)
		)
		(layer "In3.Cu")
	)
	(gr_line
		(start 388.303262 -9.997948)
		(end 388.303262 -12.461748)
		(stroke
			(width 0.254)
			(type default)
		)
		(layer "In3.Cu")
	)
	(gr_line
		(start 388.303262 -9.897872)
		(end 388.303262 -12.361672)
		(stroke
			(width 0.254)
			(type default)
		)
		(layer "In3.Cu")
	)
	(gr_line
		(start 388.303262 -8.261604)
		(end 387.439662 -8.261604)
		(stroke
			(width 0.254)
			(type default)
		)
		(layer "In3.Cu")
	)
	(gr_line
		(start 388.303262 -8.161528)
		(end 387.439662 -8.161528)
		(stroke
			(width 0.254)
			(type default)
		)
		(layer "In3.Cu")
	)
	(gr_line
		(start 388.303262 -5.797804)
		(end 388.303262 -8.261604)
		(stroke
			(width 0.254)
			(type default)
		)
		(layer "In3.Cu")
	)
	(gr_line
		(start 388.303262 -5.697728)
		(end 388.303262 -8.161528)
		(stroke
			(width 0.254)
			(type default)
		)
		(layer "In3.Cu")
	)
	(gr_line
		(start 388.303262 -4.06146)
		(end 387.439662 -4.06146)
		(stroke
			(width 0.254)
			(type default)
		)
		(layer "In3.Cu")
	)
	(gr_line
		(start 388.303262 -3.961384)
		(end 387.439662 -3.961384)
		(stroke
			(width 0.254)
			(type default)
		)
		(layer "In3.Cu")
	)
	(gr_line
		(start 388.303262 -1.59766)
		(end 388.303262 -4.06146)
		(stroke
			(width 0.254)
			(type default)
		)
		(layer "In3.Cu")
	)
	(gr_line
		(start 388.303262 -1.497584)
		(end 388.303262 -3.961384)
		(stroke
			(width 0.254)
			(type default)
		)
		(layer "In3.Cu")
	)
	(gr_line
		(start 388.354062 -12.487148)
		(end 387.414262 -12.487148)
		(stroke
			(width 0.254)
			(type default)
		)
		(layer "In3.Cu")
	)
	(gr_line
		(start 388.354062 -12.387072)
		(end 387.414262 -12.387072)
		(stroke
			(width 0.254)
			(type default)
		)
		(layer "In3.Cu")
	)
	(gr_line
		(start 388.354062 -9.997948)
		(end 388.354062 -12.487148)
		(stroke
			(width 0.254)
			(type default)
		)
		(layer "In3.Cu")
	)
	(gr_line
		(start 388.354062 -9.897872)
		(end 388.354062 -12.387072)
		(stroke
			(width 0.254)
			(type default)
		)
		(layer "In3.Cu")
	)
	(gr_line
		(start 388.354062 -8.287004)
		(end 387.414262 -8.287004)
		(stroke
			(width 0.254)
			(type default)
		)
		(layer "In3.Cu")
	)
	(gr_line
		(start 388.354062 -8.186928)
		(end 387.414262 -8.186928)
		(stroke
			(width 0.254)
			(type default)
		)
		(layer "In3.Cu")
	)
	(gr_line
		(start 388.354062 -5.797804)
		(end 388.354062 -8.287004)
		(stroke
			(width 0.254)
			(type default)
		)
		(layer "In3.Cu")
	)
	(gr_line
		(start 388.354062 -5.697728)
		(end 388.354062 -8.186928)
		(stroke
			(width 0.254)
			(type default)
		)
		(layer "In3.Cu")
	)
	(gr_line
		(start 388.354062 -4.08686)
		(end 387.414262 -4.08686)
		(stroke
			(width 0.254)
			(type default)
		)
		(layer "In3.Cu")
	)
	(gr_line
		(start 388.354062 -3.986784)
		(end 387.414262 -3.986784)
		(stroke
			(width 0.254)
			(type default)
		)
		(layer "In3.Cu")
	)
	(gr_line
		(start 388.354062 -1.59766)
		(end 388.354062 -4.08686)
		(stroke
			(width 0.254)
			(type default)
		)
		(layer "In3.Cu")
	)
	(gr_line
		(start 388.354062 -1.497584)
		(end 388.354062 -3.986784)
		(stroke
			(width 0.254)
			(type default)
		)
		(layer "In3.Cu")
	)
	(gr_line
		(start 388.379462 -12.487148)
		(end 387.414262 -12.487148)
		(stroke
			(width 0.2032)
			(type default)
		)
		(layer "In3.Cu")
	)
	(gr_line
		(start 388.379462 -12.387072)
		(end 387.414262 -12.387072)
		(stroke
			(width 0.2032)
			(type default)
		)
		(layer "In3.Cu")
	)
	(gr_line
		(start 388.379462 -9.947148)
		(end 388.379462 -12.487148)
		(stroke
			(width 0.2032)
			(type default)
		)
		(layer "In3.Cu")
	)
	(gr_line
		(start 388.379462 -9.847072)
		(end 388.379462 -12.387072)
		(stroke
			(width 0.2032)
			(type default)
		)
		(layer "In3.Cu")
	)
	(gr_line
		(start 388.379462 -8.287004)
		(end 387.414262 -8.287004)
		(stroke
			(width 0.2032)
			(type default)
		)
		(layer "In3.Cu")
	)
	(gr_line
		(start 388.379462 -8.186928)
		(end 387.414262 -8.186928)
		(stroke
			(width 0.2032)
			(type default)
		)
		(layer "In3.Cu")
	)
	(gr_line
		(start 388.379462 -5.747004)
		(end 388.379462 -8.287004)
		(stroke
			(width 0.2032)
			(type default)
		)
		(layer "In3.Cu")
	)
	(gr_line
		(start 388.379462 -5.646928)
		(end 388.379462 -8.186928)
		(stroke
			(width 0.2032)
			(type default)
		)
		(layer "In3.Cu")
	)
	(gr_line
		(start 388.379462 -4.08686)
		(end 387.414262 -4.08686)
		(stroke
			(width 0.2032)
			(type default)
		)
		(layer "In3.Cu")
	)
	(gr_line
		(start 388.379462 -3.986784)
		(end 387.414262 -3.986784)
		(stroke
			(width 0.2032)
			(type default)
		)
		(layer "In3.Cu")
	)
	(gr_line
		(start 388.379462 -1.54686)
		(end 388.379462 -4.08686)
		(stroke
			(width 0.2032)
			(type default)
		)
		(layer "In3.Cu")
	)
	(gr_line
		(start 388.379462 -1.446784)
		(end 388.379462 -3.986784)
		(stroke
			(width 0.2032)
			(type default)
		)
		(layer "In3.Cu")
	)
	(gr_line
		(start 388.430262 -12.512548)
		(end 387.363462 -12.512548)
		(stroke
			(width 0.2032)
			(type default)
		)
		(layer "In3.Cu")
	)
	(gr_line
		(start 388.430262 -12.412472)
		(end 387.363462 -12.412472)
		(stroke
			(width 0.2032)
			(type default)
		)
		(layer "In3.Cu")
	)
	(gr_line
		(start 388.430262 -9.947148)
		(end 388.430262 -12.512548)
		(stroke
			(width 0.2032)
			(type default)
		)
		(layer "In3.Cu")
	)
	(gr_line
		(start 388.430262 -9.847072)
		(end 388.430262 -12.412472)
		(stroke
			(width 0.2032)
			(type default)
		)
		(layer "In3.Cu")
	)
	(gr_line
		(start 388.430262 -8.312404)
		(end 387.363462 -8.312404)
		(stroke
			(width 0.2032)
			(type default)
		)
		(layer "In3.Cu")
	)
	(gr_line
		(start 388.430262 -8.212328)
		(end 387.363462 -8.212328)
		(stroke
			(width 0.2032)
			(type default)
		)
		(layer "In3.Cu")
	)
	(gr_line
		(start 388.430262 -5.747004)
		(end 388.430262 -8.312404)
		(stroke
			(width 0.2032)
			(type default)
		)
		(layer "In3.Cu")
	)
	(gr_line
		(start 388.430262 -5.646928)
		(end 388.430262 -8.212328)
		(stroke
			(width 0.2032)
			(type default)
		)
		(layer "In3.Cu")
	)
	(gr_line
		(start 388.430262 -4.11226)
		(end 387.363462 -4.11226)
		(stroke
			(width 0.2032)
			(type default)
		)
		(layer "In3.Cu")
	)
	(gr_line
		(start 388.430262 -4.012184)
		(end 387.363462 -4.012184)
		(stroke
			(width 0.2032)
			(type default)
		)
		(layer "In3.Cu")
	)
	(gr_line
		(start 388.430262 -1.54686)
		(end 388.430262 -4.11226)
		(stroke
			(width 0.2032)
			(type default)
		)
		(layer "In3.Cu")
	)
	(gr_line
		(start 388.430262 -1.446784)
		(end 388.430262 -4.012184)
		(stroke
			(width 0.2032)
			(type default)
		)
		(layer "In3.Cu")
	)
	(gr_line
		(start 388.455662 -12.512548)
		(end 387.338062 -12.512548)
		(stroke
			(width 0.1016)
			(type default)
		)
		(layer "In3.Cu")
	)
	(gr_line
		(start 388.455662 -12.412472)
		(end 387.338062 -12.412472)
		(stroke
			(width 0.1016)
			(type default)
		)
		(layer "In3.Cu")
	)
	(gr_line
		(start 388.455662 -9.921748)
		(end 388.455662 -12.512548)
		(stroke
			(width 0.1016)
			(type default)
		)
		(layer "In3.Cu")
	)
	(gr_line
		(start 388.455662 -9.821672)
		(end 388.455662 -12.412472)
		(stroke
			(width 0.1016)
			(type default)
		)
		(layer "In3.Cu")
	)
	(gr_line
		(start 388.455662 -8.312404)
		(end 387.338062 -8.312404)
		(stroke
			(width 0.1016)
			(type default)
		)
		(layer "In3.Cu")
	)
	(gr_line
		(start 388.455662 -8.212328)
		(end 387.338062 -8.212328)
		(stroke
			(width 0.1016)
			(type default)
		)
		(layer "In3.Cu")
	)
	(gr_line
		(start 388.455662 -5.721604)
		(end 388.455662 -8.312404)
		(stroke
			(width 0.1016)
			(type default)
		)
		(layer "In3.Cu")
	)
	(gr_line
		(start 388.455662 -5.621528)
		(end 388.455662 -8.212328)
		(stroke
			(width 0.1016)
			(type default)
		)
		(layer "In3.Cu")
	)
	(gr_line
		(start 388.455662 -4.11226)
		(end 387.338062 -4.11226)
		(stroke
			(width 0.1016)
			(type default)
		)
		(layer "In3.Cu")
	)
	(gr_line
		(start 388.455662 -4.012184)
		(end 387.338062 -4.012184)
		(stroke
			(width 0.1016)
			(type default)
		)
		(layer "In3.Cu")
	)
	(gr_line
		(start 388.455662 -1.52146)
		(end 388.455662 -4.11226)
		(stroke
			(width 0.1016)
			(type default)
		)
		(layer "In3.Cu")
	)
	(gr_line
		(start 388.455662 -1.421384)
		(end 388.455662 -4.012184)
		(stroke
			(width 0.1016)
			(type default)
		)
		(layer "In3.Cu")
	)
	(gr_line
		(start 388.464806 -18.5166)
		(end 389.734806 -18.5166)
		(stroke
			(width 0.7874)
			(type default)
		)
		(layer "In3.Cu")
	)
	(gr_line
		(start 388.481062 -12.563348)
		(end 388.074662 -12.563348)
		(stroke
			(width 0.1016)
			(type default)
		)
		(layer "In3.Cu")
	)
	(gr_line
		(start 388.481062 -12.563348)
		(end 388.481062 -9.896348)
		(stroke
			(width 0.1016)
			(type default)
		)
		(layer "In3.Cu")
	)
	(gr_line
		(start 388.481062 -12.463272)
		(end 388.074662 -12.463272)
		(stroke
			(width 0.1016)
			(type default)
		)
		(layer "In3.Cu")
	)
	(gr_line
		(start 388.481062 -12.463272)
		(end 388.481062 -9.796272)
		(stroke
			(width 0.1016)
			(type default)
		)
		(layer "In3.Cu")
	)
	(gr_line
		(start 388.481062 -9.896348)
		(end 387.287262 -9.896348)
		(stroke
			(width 0.1016)
			(type default)
		)
		(layer "In3.Cu")
	)
	(gr_line
		(start 388.481062 -9.896348)
		(end 388.481062 -12.563348)
		(stroke
			(width 0.1016)
			(type default)
		)
		(layer "In3.Cu")
	)
	(gr_line
		(start 388.481062 -9.796272)
		(end 387.287262 -9.796272)
		(stroke
			(width 0.1016)
			(type default)
		)
		(layer "In3.Cu")
	)
	(gr_line
		(start 388.481062 -9.796272)
		(end 388.481062 -12.463272)
		(stroke
			(width 0.1016)
			(type default)
		)
		(layer "In3.Cu")
	)
	(gr_line
		(start 388.481062 -8.363204)
		(end 388.074662 -8.363204)
		(stroke
			(width 0.1016)
			(type default)
		)
		(layer "In3.Cu")
	)
	(gr_line
		(start 388.481062 -8.363204)
		(end 388.481062 -5.696204)
		(stroke
			(width 0.1016)
			(type default)
		)
		(layer "In3.Cu")
	)
	(gr_line
		(start 388.481062 -8.263128)
		(end 388.074662 -8.263128)
		(stroke
			(width 0.1016)
			(type default)
		)
		(layer "In3.Cu")
	)
	(gr_line
		(start 388.481062 -8.263128)
		(end 388.481062 -5.596128)
		(stroke
			(width 0.1016)
			(type default)
		)
		(layer "In3.Cu")
	)
	(gr_line
		(start 388.481062 -5.696204)
		(end 387.287262 -5.696204)
		(stroke
			(width 0.1016)
			(type default)
		)
		(layer "In3.Cu")
	)
	(gr_line
		(start 388.481062 -5.696204)
		(end 388.481062 -8.363204)
		(stroke
			(width 0.1016)
			(type default)
		)
		(layer "In3.Cu")
	)
	(gr_line
		(start 388.481062 -5.596128)
		(end 387.287262 -5.596128)
		(stroke
			(width 0.1016)
			(type default)
		)
		(layer "In3.Cu")
	)
	(gr_line
		(start 388.481062 -5.596128)
		(end 388.481062 -8.263128)
		(stroke
			(width 0.1016)
			(type default)
		)
		(layer "In3.Cu")
	)
	(gr_line
		(start 388.481062 -4.16306)
		(end 388.074662 -4.16306)
		(stroke
			(width 0.1016)
			(type default)
		)
		(layer "In3.Cu")
	)
	(gr_line
		(start 388.481062 -4.16306)
		(end 388.481062 -1.49606)
		(stroke
			(width 0.1016)
			(type default)
		)
		(layer "In3.Cu")
	)
	(gr_line
		(start 388.481062 -4.062984)
		(end 388.074662 -4.062984)
		(stroke
			(width 0.1016)
			(type default)
		)
		(layer "In3.Cu")
	)
	(gr_line
		(start 388.481062 -4.062984)
		(end 388.481062 -1.395984)
		(stroke
			(width 0.1016)
			(type default)
		)
		(layer "In3.Cu")
	)
	(gr_line
		(start 388.481062 -1.49606)
		(end 387.287262 -1.49606)
		(stroke
			(width 0.1016)
			(type default)
		)
		(layer "In3.Cu")
	)
	(gr_line
		(start 388.481062 -1.49606)
		(end 388.481062 -4.16306)
		(stroke
			(width 0.1016)
			(type default)
		)
		(layer "In3.Cu")
	)
	(gr_line
		(start 388.481062 -1.494028)
		(end 387.261862 -1.494028)
		(stroke
			(width 0.1016)
			(type default)
		)
		(layer "In3.Cu")
	)
	(gr_line
		(start 388.481062 -1.494028)
		(end 387.287262 -1.494028)
		(stroke
			(width 0.1016)
			(type default)
		)
		(layer "In3.Cu")
	)
	(gr_line
		(start 388.481062 -1.395984)
		(end 387.287262 -1.395984)
		(stroke
			(width 0.1016)
			(type default)
		)
		(layer "In3.Cu")
	)
	(gr_line
		(start 388.481062 -1.395984)
		(end 388.481062 -4.062984)
		(stroke
			(width 0.1016)
			(type default)
		)
		(layer "In3.Cu")
	)
	(gr_line
		(start 388.506462 -1.468628)
		(end 387.261862 -1.468628)
		(stroke
			(width 0.1016)
			(type default)
		)
		(layer "In3.Cu")
	)
	(gr_line
		(start 389.287258 -13.8176)
		(end 390.074658 -13.8176)
		(stroke
			(width 0.1016)
			(type default)
		)
		(layer "In3.Cu")
	)
	(gr_line
		(start 389.287258 -13.7668)
		(end 389.287258 -11.1506)
		(stroke
			(width 0.1016)
			(type default)
		)
		(layer "In3.Cu")
	)
	(gr_line
		(start 389.287258 -11.1506)
		(end 389.287258 -13.8176)
		(stroke
			(width 0.1016)
			(type default)
		)
		(layer "In3.Cu")
	)
	(gr_line
		(start 389.287258 -11.1506)
		(end 390.481058 -11.1506)
		(stroke
			(width 0.1016)
			(type default)
		)
		(layer "In3.Cu")
	)
	(gr_line
		(start 389.287258 -9.617456)
		(end 390.074658 -9.617456)
		(stroke
			(width 0.1016)
			(type default)
		)
		(layer "In3.Cu")
	)
	(gr_line
		(start 389.287258 -9.566656)
		(end 389.287258 -6.950456)
		(stroke
			(width 0.1016)
			(type default)
		)
		(layer "In3.Cu")
	)
	(gr_line
		(start 389.287258 -6.950456)
		(end 389.287258 -9.617456)
		(stroke
			(width 0.1016)
			(type default)
		)
		(layer "In3.Cu")
	)
	(gr_line
		(start 389.287258 -6.950456)
		(end 390.481058 -6.950456)
		(stroke
			(width 0.1016)
			(type default)
		)
		(layer "In3.Cu")
	)
	(gr_line
		(start 389.312658 -13.7668)
		(end 389.312658 -11.176)
		(stroke
			(width 0.1016)
			(type default)
		)
		(layer "In3.Cu")
	)
	(gr_line
		(start 389.312658 -11.176)
		(end 390.455658 -11.176)
		(stroke
			(width 0.1016)
			(type default)
		)
		(layer "In3.Cu")
	)
	(gr_line
		(start 389.312658 -9.566656)
		(end 389.312658 -6.975856)
		(stroke
			(width 0.1016)
			(type default)
		)
		(layer "In3.Cu")
	)
	(gr_line
		(start 389.312658 -6.975856)
		(end 390.455658 -6.975856)
		(stroke
			(width 0.1016)
			(type default)
		)
		(layer "In3.Cu")
	)
	(gr_line
		(start 389.338058 -13.7668)
		(end 389.338058 -11.2014)
		(stroke
			(width 0.1016)
			(type default)
		)
		(layer "In3.Cu")
	)
	(gr_line
		(start 389.338058 -11.2014)
		(end 389.592058 -11.2014)
		(stroke
			(width 0.1016)
			(type default)
		)
		(layer "In3.Cu")
	)
	(gr_line
		(start 389.338058 -9.566656)
		(end 389.338058 -7.001256)
		(stroke
			(width 0.1016)
			(type default)
		)
		(layer "In3.Cu")
	)
	(gr_line
		(start 389.338058 -7.001256)
		(end 389.592058 -7.001256)
		(stroke
			(width 0.1016)
			(type default)
		)
		(layer "In3.Cu")
	)
	(gr_line
		(start 389.363458 -13.7668)
		(end 389.363458 -11.2014)
		(stroke
			(width 0.2032)
			(type default)
		)
		(layer "In3.Cu")
	)
	(gr_line
		(start 389.363458 -11.2014)
		(end 390.379458 -11.2014)
		(stroke
			(width 0.2032)
			(type default)
		)
		(layer "In3.Cu")
	)
	(gr_line
		(start 389.363458 -9.566656)
		(end 389.363458 -7.001256)
		(stroke
			(width 0.2032)
			(type default)
		)
		(layer "In3.Cu")
	)
	(gr_line
		(start 389.363458 -7.001256)
		(end 390.379458 -7.001256)
		(stroke
			(width 0.2032)
			(type default)
		)
		(layer "In3.Cu")
	)
	(gr_line
		(start 389.414258 -13.7414)
		(end 389.414258 -11.2522)
		(stroke
			(width 0.2032)
			(type default)
		)
		(layer "In3.Cu")
	)
	(gr_line
		(start 389.414258 -13.7414)
		(end 389.414258 -11.2522)
		(stroke
			(width 0.254)
			(type default)
		)
		(layer "In3.Cu")
	)
	(gr_line
		(start 389.414258 -11.2522)
		(end 389.617458 -11.2522)
		(stroke
			(width 0.2032)
			(type default)
		)
		(layer "In3.Cu")
	)
	(gr_line
		(start 389.414258 -11.2522)
		(end 390.303258 -11.2522)
		(stroke
			(width 0.254)
			(type default)
		)
		(layer "In3.Cu")
	)
	(gr_line
		(start 389.414258 -9.541256)
		(end 389.414258 -7.052056)
		(stroke
			(width 0.2032)
			(type default)
		)
		(layer "In3.Cu")
	)
	(gr_line
		(start 389.414258 -9.541256)
		(end 389.414258 -7.052056)
		(stroke
			(width 0.254)
			(type default)
		)
		(layer "In3.Cu")
	)
	(gr_line
		(start 389.414258 -7.052056)
		(end 389.617458 -7.052056)
		(stroke
			(width 0.2032)
			(type default)
		)
		(layer "In3.Cu")
	)
	(gr_line
		(start 389.414258 -7.052056)
		(end 390.303258 -7.052056)
		(stroke
			(width 0.254)
			(type default)
		)
		(layer "In3.Cu")
	)
	(gr_line
		(start 389.439658 -13.716)
		(end 389.439658 -11.2776)
		(stroke
			(width 0.254)
			(type default)
		)
		(layer "In3.Cu")
	)
	(gr_line
		(start 389.439658 -11.2776)
		(end 390.277858 -11.2776)
		(stroke
			(width 0.254)
			(type default)
		)
		(layer "In3.Cu")
	)
	(gr_line
		(start 389.439658 -9.515856)
		(end 389.439658 -7.077456)
		(stroke
			(width 0.254)
			(type default)
		)
		(layer "In3.Cu")
	)
	(gr_line
		(start 389.439658 -7.077456)
		(end 390.277858 -7.077456)
		(stroke
			(width 0.254)
			(type default)
		)
		(layer "In3.Cu")
	)
	(gr_line
		(start 389.465058 -13.6906)
		(end 389.465058 -11.303)
		(stroke
			(width 0.254)
			(type default)
		)
		(layer "In3.Cu")
	)
	(gr_line
		(start 389.465058 -11.303)
		(end 390.252458 -11.303)
		(stroke
			(width 0.254)
			(type default)
		)
		(layer "In3.Cu")
	)
	(gr_line
		(start 389.465058 -9.490456)
		(end 389.465058 -7.102856)
		(stroke
			(width 0.254)
			(type default)
		)
		(layer "In3.Cu")
	)
	(gr_line
		(start 389.465058 -7.102856)
		(end 390.252458 -7.102856)
		(stroke
			(width 0.254)
			(type default)
		)
		(layer "In3.Cu")
	)
	(gr_line
		(start 389.490458 -13.6144)
		(end 390.125458 -13.6144)
		(stroke
			(width 0.508)
			(type default)
		)
		(layer "In3.Cu")
	)
	(gr_line
		(start 389.490458 -11.43)
		(end 390.125458 -11.43)
		(stroke
			(width 0.508)
			(type default)
		)
		(layer "In3.Cu")
	)
	(gr_line
		(start 389.490458 -11.3792)
		(end 390.125458 -11.3792)
		(stroke
			(width 0.508)
			(type default)
		)
		(layer "In3.Cu")
	)
	(gr_line
		(start 389.490458 -9.414256)
		(end 390.125458 -9.414256)
		(stroke
			(width 0.508)
			(type default)
		)
		(layer "In3.Cu")
	)
	(gr_line
		(start 389.490458 -7.229856)
		(end 390.125458 -7.229856)
		(stroke
			(width 0.508)
			(type default)
		)
		(layer "In3.Cu")
	)
	(gr_line
		(start 389.490458 -7.179056)
		(end 390.125458 -7.179056)
		(stroke
			(width 0.508)
			(type default)
		)
		(layer "In3.Cu")
	)
	(gr_line
		(start 389.515858 -11.684)
		(end 390.150858 -11.684)
		(stroke
			(width 0.508)
			(type default)
		)
		(layer "In3.Cu")
	)
	(gr_line
		(start 389.515858 -7.483856)
		(end 390.150858 -7.483856)
		(stroke
			(width 0.508)
			(type default)
		)
		(layer "In3.Cu")
	)
	(gr_line
		(start 389.541258 -13.6398)
		(end 389.541258 -11.3792)
		(stroke
			(width 0.254)
			(type default)
		)
		(layer "In3.Cu")
	)
	(gr_line
		(start 389.541258 -13.4874)
		(end 390.176258 -13.4874)
		(stroke
			(width 0.508)
			(type default)
		)
		(layer "In3.Cu")
	)
	(gr_line
		(start 389.541258 -11.3792)
		(end 390.176258 -11.3792)
		(stroke
			(width 0.254)
			(type default)
		)
		(layer "In3.Cu")
	)
	(gr_line
		(start 389.541258 -9.439656)
		(end 389.541258 -7.179056)
		(stroke
			(width 0.254)
			(type default)
		)
		(layer "In3.Cu")
	)
	(gr_line
		(start 389.541258 -9.287256)
		(end 390.176258 -9.287256)
		(stroke
			(width 0.508)
			(type default)
		)
		(layer "In3.Cu")
	)
	(gr_line
		(start 389.541258 -7.179056)
		(end 390.176258 -7.179056)
		(stroke
			(width 0.254)
			(type default)
		)
		(layer "In3.Cu")
	)
	(gr_line
		(start 389.566658 -13.335)
		(end 390.201658 -13.335)
		(stroke
			(width 0.508)
			(type default)
		)
		(layer "In3.Cu")
	)
	(gr_line
		(start 389.566658 -9.134856)
		(end 390.201658 -9.134856)
		(stroke
			(width 0.508)
			(type default)
		)
		(layer "In3.Cu")
	)
	(gr_line
		(start 389.592058 -13.6144)
		(end 390.227058 -13.6144)
		(stroke
			(width 0.508)
			(type default)
		)
		(layer "In3.Cu")
	)
	(gr_line
		(start 389.592058 -11.2014)
		(end 390.430258 -11.2014)
		(stroke
			(width 0.2032)
			(type default)
		)
		(layer "In3.Cu")
	)
	(gr_line
		(start 389.592058 -9.414256)
		(end 390.227058 -9.414256)
		(stroke
			(width 0.508)
			(type default)
		)
		(layer "In3.Cu")
	)
	(gr_line
		(start 389.592058 -7.001256)
		(end 390.430258 -7.001256)
		(stroke
			(width 0.2032)
			(type default)
		)
		(layer "In3.Cu")
	)
	(gr_line
		(start 389.617458 -13.6144)
		(end 389.617458 -11.43)
		(stroke
			(width 0.254)
			(type default)
		)
		(layer "In3.Cu")
	)
	(gr_line
		(start 389.617458 -11.43)
		(end 390.100058 -11.43)
		(stroke
			(width 0.254)
			(type default)
		)
		(layer "In3.Cu")
	)
	(gr_line
		(start 389.617458 -11.2522)
		(end 390.354058 -11.2522)
		(stroke
			(width 0.254)
			(type default)
		)
		(layer "In3.Cu")
	)
	(gr_line
		(start 389.617458 -9.414256)
		(end 389.617458 -7.229856)
		(stroke
			(width 0.254)
			(type default)
		)
		(layer "In3.Cu")
	)
	(gr_line
		(start 389.617458 -7.229856)
		(end 390.100058 -7.229856)
		(stroke
			(width 0.254)
			(type default)
		)
		(layer "In3.Cu")
	)
	(gr_line
		(start 389.617458 -7.052056)
		(end 390.354058 -7.052056)
		(stroke
			(width 0.254)
			(type default)
		)
		(layer "In3.Cu")
	)
	(gr_line
		(start 389.636 -11.36523)
		(end 390.271 -11.36523)
		(stroke
			(width 0.508)
			(type default)
		)
		(layer "In3.Cu")
	)
	(gr_line
		(start 389.636 -7.165086)
		(end 390.271 -7.165086)
		(stroke
			(width 0.508)
			(type default)
		)
		(layer "In3.Cu")
	)
	(gr_line
		(start 389.642858 -13.6144)
		(end 390.277858 -13.6144)
		(stroke
			(width 0.508)
			(type default)
		)
		(layer "In3.Cu")
	)
	(gr_line
		(start 389.642858 -13.4874)
		(end 389.642858 -11.5062)
		(stroke
			(width 0.762)
			(type default)
		)
		(layer "In3.Cu")
	)
	(gr_line
		(start 389.642858 -11.5062)
		(end 390.277858 -11.5062)
		(stroke
			(width 0.508)
			(type default)
		)
		(layer "In3.Cu")
	)
	(gr_line
		(start 389.642858 -9.414256)
		(end 390.277858 -9.414256)
		(stroke
			(width 0.508)
			(type default)
		)
		(layer "In3.Cu")
	)
	(gr_line
		(start 389.642858 -9.287256)
		(end 389.642858 -7.306056)
		(stroke
			(width 0.762)
			(type default)
		)
		(layer "In3.Cu")
	)
	(gr_line
		(start 389.642858 -7.306056)
		(end 390.277858 -7.306056)
		(stroke
			(width 0.508)
			(type default)
		)
		(layer "In3.Cu")
	)
	(gr_line
		(start 389.693658 -13.5382)
		(end 389.693658 -11.5062)
		(stroke
			(width 0.254)
			(type default)
		)
		(layer "In3.Cu")
	)
	(gr_line
		(start 389.693658 -11.5062)
		(end 390.023858 -11.5062)
		(stroke
			(width 0.254)
			(type default)
		)
		(layer "In3.Cu")
	)
	(gr_line
		(start 389.693658 -9.338056)
		(end 389.693658 -7.306056)
		(stroke
			(width 0.254)
			(type default)
		)
		(layer "In3.Cu")
	)
	(gr_line
		(start 389.693658 -7.306056)
		(end 390.023858 -7.306056)
		(stroke
			(width 0.254)
			(type default)
		)
		(layer "In3.Cu")
	)
	(gr_line
		(start 389.795258 -13.462)
		(end 389.795258 -11.6586)
		(stroke
			(width 0.254)
			(type default)
		)
		(layer "In3.Cu")
	)
	(gr_line
		(start 389.795258 -13.462)
		(end 389.795258 -11.4808)
		(stroke
			(width 0.762)
			(type default)
		)
		(layer "In3.Cu")
	)
	(gr_line
		(start 389.795258 -11.6586)
		(end 389.896858 -11.6586)
		(stroke
			(width 0.254)
			(type default)
		)
		(layer "In3.Cu")
	)
	(gr_line
		(start 389.795258 -9.261856)
		(end 389.795258 -7.458456)
		(stroke
			(width 0.254)
			(type default)
		)
		(layer "In3.Cu")
	)
	(gr_line
		(start 389.795258 -9.261856)
		(end 389.795258 -7.280656)
		(stroke
			(width 0.762)
			(type default)
		)
		(layer "In3.Cu")
	)
	(gr_line
		(start 389.795258 -7.458456)
		(end 389.896858 -7.458456)
		(stroke
			(width 0.254)
			(type default)
		)
		(layer "In3.Cu")
	)
	(gr_line
		(start 389.896858 -13.5636)
		(end 389.846058 -13.5636)
		(stroke
			(width 0.254)
			(type default)
		)
		(layer "In3.Cu")
	)
	(gr_line
		(start 389.896858 -11.6586)
		(end 389.896858 -13.5636)
		(stroke
			(width 0.254)
			(type default)
		)
		(layer "In3.Cu")
	)
	(gr_line
		(start 389.896858 -9.363456)
		(end 389.846058 -9.363456)
		(stroke
			(width 0.254)
			(type default)
		)
		(layer "In3.Cu")
	)
	(gr_line
		(start 389.896858 -7.458456)
		(end 389.896858 -9.363456)
		(stroke
			(width 0.254)
			(type default)
		)
		(layer "In3.Cu")
	)
	(gr_line
		(start 389.947658 -13.4874)
		(end 389.947658 -11.5062)
		(stroke
			(width 0.762)
			(type default)
		)
		(layer "In3.Cu")
	)
	(gr_line
		(start 389.947658 -9.287256)
		(end 389.947658 -7.306056)
		(stroke
			(width 0.762)
			(type default)
		)
		(layer "In3.Cu")
	)
	(gr_line
		(start 390.023858 -13.462)
		(end 389.795258 -13.462)
		(stroke
			(width 0.254)
			(type default)
		)
		(layer "In3.Cu")
	)
	(gr_line
		(start 390.023858 -11.5062)
		(end 390.023858 -13.462)
		(stroke
			(width 0.254)
			(type default)
		)
		(layer "In3.Cu")
	)
	(gr_line
		(start 390.023858 -9.261856)
		(end 389.795258 -9.261856)
		(stroke
			(width 0.254)
			(type default)
		)
		(layer "In3.Cu")
	)
	(gr_line
		(start 390.023858 -7.306056)
		(end 390.023858 -9.261856)
		(stroke
			(width 0.254)
			(type default)
		)
		(layer "In3.Cu")
	)
	(gr_line
		(start 390.074658 -13.8176)
		(end 390.074658 -13.7668)
		(stroke
			(width 0.1016)
			(type default)
		)
		(layer "In3.Cu")
	)
	(gr_line
		(start 390.074658 -13.8176)
		(end 390.481058 -13.8176)
		(stroke
			(width 0.1016)
			(type default)
		)
		(layer "In3.Cu")
	)
	(gr_line
		(start 390.074658 -13.7668)
		(end 389.312658 -13.7668)
		(stroke
			(width 0.1016)
			(type default)
		)
		(layer "In3.Cu")
	)
	(gr_line
		(start 390.074658 -13.4874)
		(end 390.074658 -11.5062)
		(stroke
			(width 0.762)
			(type default)
		)
		(layer "In3.Cu")
	)
	(gr_line
		(start 390.074658 -9.617456)
		(end 390.074658 -9.566656)
		(stroke
			(width 0.1016)
			(type default)
		)
		(layer "In3.Cu")
	)
	(gr_line
		(start 390.074658 -9.617456)
		(end 390.481058 -9.617456)
		(stroke
			(width 0.1016)
			(type default)
		)
		(layer "In3.Cu")
	)
	(gr_line
		(start 390.074658 -9.566656)
		(end 389.312658 -9.566656)
		(stroke
			(width 0.1016)
			(type default)
		)
		(layer "In3.Cu")
	)
	(gr_line
		(start 390.074658 -9.287256)
		(end 390.074658 -7.306056)
		(stroke
			(width 0.762)
			(type default)
		)
		(layer "In3.Cu")
	)
	(gr_line
		(start 390.100058 -13.5382)
		(end 389.693658 -13.5382)
		(stroke
			(width 0.254)
			(type default)
		)
		(layer "In3.Cu")
	)
	(gr_line
		(start 390.100058 -11.43)
		(end 390.100058 -13.5382)
		(stroke
			(width 0.254)
			(type default)
		)
		(layer "In3.Cu")
	)
	(gr_line
		(start 390.100058 -9.338056)
		(end 389.693658 -9.338056)
		(stroke
			(width 0.254)
			(type default)
		)
		(layer "In3.Cu")
	)
	(gr_line
		(start 390.100058 -7.229856)
		(end 390.100058 -9.338056)
		(stroke
			(width 0.254)
			(type default)
		)
		(layer "In3.Cu")
	)
	(gr_line
		(start 390.150858 -13.4874)
		(end 390.150858 -11.5062)
		(stroke
			(width 0.762)
			(type default)
		)
		(layer "In3.Cu")
	)
	(gr_line
		(start 390.150858 -9.287256)
		(end 390.150858 -7.306056)
		(stroke
			(width 0.762)
			(type default)
		)
		(layer "In3.Cu")
	)
	(gr_line
		(start 390.176258 -13.6144)
		(end 389.617458 -13.6144)
		(stroke
			(width 0.254)
			(type default)
		)
		(layer "In3.Cu")
	)
	(gr_line
		(start 390.176258 -11.3792)
		(end 390.176258 -13.6144)
		(stroke
			(width 0.254)
			(type default)
		)
		(layer "In3.Cu")
	)
	(gr_line
		(start 390.176258 -9.414256)
		(end 389.617458 -9.414256)
		(stroke
			(width 0.254)
			(type default)
		)
		(layer "In3.Cu")
	)
	(gr_line
		(start 390.176258 -7.179056)
		(end 390.176258 -9.414256)
		(stroke
			(width 0.254)
			(type default)
		)
		(layer "In3.Cu")
	)
	(gr_line
		(start 390.252458 -13.6398)
		(end 389.541258 -13.6398)
		(stroke
			(width 0.254)
			(type default)
		)
		(layer "In3.Cu")
	)
	(gr_line
		(start 390.252458 -11.303)
		(end 390.252458 -13.6398)
		(stroke
			(width 0.254)
			(type default)
		)
		(layer "In3.Cu")
	)
	(gr_line
		(start 390.252458 -9.439656)
		(end 389.541258 -9.439656)
		(stroke
			(width 0.254)
			(type default)
		)
		(layer "In3.Cu")
	)
	(gr_line
		(start 390.252458 -7.102856)
		(end 390.252458 -9.439656)
		(stroke
			(width 0.254)
			(type default)
		)
		(layer "In3.Cu")
	)
	(gr_line
		(start 390.277858 -13.7668)
		(end 389.287258 -13.7668)
		(stroke
			(width 0.1016)
			(type default)
		)
		(layer "In3.Cu")
	)
	(gr_line
		(start 390.277858 -13.6906)
		(end 389.465058 -13.6906)
		(stroke
			(width 0.254)
			(type default)
		)
		(layer "In3.Cu")
	)
	(gr_line
		(start 390.277858 -11.2776)
		(end 390.277858 -13.6906)
		(stroke
			(width 0.254)
			(type default)
		)
		(layer "In3.Cu")
	)
	(gr_line
		(start 390.277858 -9.566656)
		(end 389.287258 -9.566656)
		(stroke
			(width 0.1016)
			(type default)
		)
		(layer "In3.Cu")
	)
	(gr_line
		(start 390.277858 -9.490456)
		(end 389.465058 -9.490456)
		(stroke
			(width 0.254)
			(type default)
		)
		(layer "In3.Cu")
	)
	(gr_line
		(start 390.277858 -7.077456)
		(end 390.277858 -9.490456)
		(stroke
			(width 0.254)
			(type default)
		)
		(layer "In3.Cu")
	)
	(gr_line
		(start 390.303258 -13.716)
		(end 389.439658 -13.716)
		(stroke
			(width 0.254)
			(type default)
		)
		(layer "In3.Cu")
	)
	(gr_line
		(start 390.303258 -11.2522)
		(end 390.303258 -13.716)
		(stroke
			(width 0.254)
			(type default)
		)
		(layer "In3.Cu")
	)
	(gr_line
		(start 390.303258 -9.515856)
		(end 389.439658 -9.515856)
		(stroke
			(width 0.254)
			(type default)
		)
		(layer "In3.Cu")
	)
	(gr_line
		(start 390.303258 -7.052056)
		(end 390.303258 -9.515856)
		(stroke
			(width 0.254)
			(type default)
		)
		(layer "In3.Cu")
	)
	(gr_line
		(start 390.319768 -30.734)
		(end 389.049768 -30.734)
		(stroke
			(width 0.7874)
			(type default)
		)
		(layer "In3.Cu")
	)
	(gr_line
		(start 390.354058 -13.7414)
		(end 389.414258 -13.7414)
		(stroke
			(width 0.254)
			(type default)
		)
		(layer "In3.Cu")
	)
	(gr_line
		(start 390.354058 -11.2522)
		(end 390.354058 -13.7414)
		(stroke
			(width 0.254)
			(type default)
		)
		(layer "In3.Cu")
	)
	(gr_line
		(start 390.354058 -9.541256)
		(end 389.414258 -9.541256)
		(stroke
			(width 0.254)
			(type default)
		)
		(layer "In3.Cu")
	)
	(gr_line
		(start 390.354058 -7.052056)
		(end 390.354058 -9.541256)
		(stroke
			(width 0.254)
			(type default)
		)
		(layer "In3.Cu")
	)
	(gr_line
		(start 390.379458 -13.7414)
		(end 389.414258 -13.7414)
		(stroke
			(width 0.2032)
			(type default)
		)
		(layer "In3.Cu")
	)
	(gr_line
		(start 390.379458 -11.2014)
		(end 390.379458 -13.7414)
		(stroke
			(width 0.2032)
			(type default)
		)
		(layer "In3.Cu")
	)
	(gr_line
		(start 390.379458 -9.541256)
		(end 389.414258 -9.541256)
		(stroke
			(width 0.2032)
			(type default)
		)
		(layer "In3.Cu")
	)
	(gr_line
		(start 390.379458 -7.001256)
		(end 390.379458 -9.541256)
		(stroke
			(width 0.2032)
			(type default)
		)
		(layer "In3.Cu")
	)
	(gr_line
		(start 390.430258 -13.7668)
		(end 389.363458 -13.7668)
		(stroke
			(width 0.2032)
			(type default)
		)
		(layer "In3.Cu")
	)
	(gr_line
		(start 390.430258 -11.2014)
		(end 390.430258 -13.7668)
		(stroke
			(width 0.2032)
			(type default)
		)
		(layer "In3.Cu")
	)
	(gr_line
		(start 390.430258 -9.566656)
		(end 389.363458 -9.566656)
		(stroke
			(width 0.2032)
			(type default)
		)
		(layer "In3.Cu")
	)
	(gr_line
		(start 390.430258 -7.001256)
		(end 390.430258 -9.566656)
		(stroke
			(width 0.2032)
			(type default)
		)
		(layer "In3.Cu")
	)
	(gr_line
		(start 390.455658 -13.7668)
		(end 389.338058 -13.7668)
		(stroke
			(width 0.1016)
			(type default)
		)
		(layer "In3.Cu")
	)
	(gr_line
		(start 390.455658 -11.176)
		(end 390.455658 -13.7668)
		(stroke
			(width 0.1016)
			(type default)
		)
		(layer "In3.Cu")
	)
	(gr_line
		(start 390.455658 -9.566656)
		(end 389.338058 -9.566656)
		(stroke
			(width 0.1016)
			(type default)
		)
		(layer "In3.Cu")
	)
	(gr_line
		(start 390.455658 -6.975856)
		(end 390.455658 -9.566656)
		(stroke
			(width 0.1016)
			(type default)
		)
		(layer "In3.Cu")
	)
	(gr_line
		(start 390.481058 -13.8176)
		(end 390.074658 -13.8176)
		(stroke
			(width 0.1016)
			(type default)
		)
		(layer "In3.Cu")
	)
	(gr_line
		(start 390.481058 -13.8176)
		(end 390.481058 -11.1506)
		(stroke
			(width 0.1016)
			(type default)
		)
		(layer "In3.Cu")
	)
	(gr_line
		(start 390.481058 -11.1506)
		(end 389.287258 -11.1506)
		(stroke
			(width 0.1016)
			(type default)
		)
		(layer "In3.Cu")
	)
	(gr_line
		(start 390.481058 -11.1506)
		(end 390.481058 -13.8176)
		(stroke
			(width 0.1016)
			(type default)
		)
		(layer "In3.Cu")
	)
	(gr_line
		(start 390.481058 -9.617456)
		(end 390.074658 -9.617456)
		(stroke
			(width 0.1016)
			(type default)
		)
		(layer "In3.Cu")
	)
	(gr_line
		(start 390.481058 -9.617456)
		(end 390.481058 -6.950456)
		(stroke
			(width 0.1016)
			(type default)
		)
		(layer "In3.Cu")
	)
	(gr_line
		(start 390.481058 -6.950456)
		(end 389.287258 -6.950456)
		(stroke
			(width 0.1016)
			(type default)
		)
		(layer "In3.Cu")
	)
	(gr_line
		(start 390.481058 -6.950456)
		(end 390.481058 -9.617456)
		(stroke
			(width 0.1016)
			(type default)
		)
		(layer "In3.Cu")
	)
	(gr_line
		(start 391.287254 -12.563348)
		(end 392.074654 -12.563348)
		(stroke
			(width 0.1016)
			(type default)
		)
		(layer "In3.Cu")
	)
	(gr_line
		(start 391.287254 -12.512548)
		(end 391.287254 -9.896348)
		(stroke
			(width 0.1016)
			(type default)
		)
		(layer "In3.Cu")
	)
	(gr_line
		(start 391.287254 -12.463272)
		(end 392.074654 -12.463272)
		(stroke
			(width 0.1016)
			(type default)
		)
		(layer "In3.Cu")
	)
	(gr_line
		(start 391.287254 -12.412472)
		(end 391.287254 -9.796272)
		(stroke
			(width 0.1016)
			(type default)
		)
		(layer "In3.Cu")
	)
	(gr_line
		(start 391.287254 -9.896348)
		(end 391.287254 -12.563348)
		(stroke
			(width 0.1016)
			(type default)
		)
		(layer "In3.Cu")
	)
	(gr_line
		(start 391.287254 -9.896348)
		(end 392.481054 -9.896348)
		(stroke
			(width 0.1016)
			(type default)
		)
		(layer "In3.Cu")
	)
	(gr_line
		(start 391.287254 -9.796272)
		(end 391.287254 -12.463272)
		(stroke
			(width 0.1016)
			(type default)
		)
		(layer "In3.Cu")
	)
	(gr_line
		(start 391.287254 -9.796272)
		(end 392.481054 -9.796272)
		(stroke
			(width 0.1016)
			(type default)
		)
		(layer "In3.Cu")
	)
	(gr_line
		(start 391.287254 -8.363204)
		(end 392.074654 -8.363204)
		(stroke
			(width 0.1016)
			(type default)
		)
		(layer "In3.Cu")
	)
	(gr_line
		(start 391.287254 -8.312404)
		(end 391.287254 -5.696204)
		(stroke
			(width 0.1016)
			(type default)
		)
		(layer "In3.Cu")
	)
	(gr_line
		(start 391.287254 -8.263128)
		(end 392.074654 -8.263128)
		(stroke
			(width 0.1016)
			(type default)
		)
		(layer "In3.Cu")
	)
	(gr_line
		(start 391.287254 -8.212328)
		(end 391.287254 -5.596128)
		(stroke
			(width 0.1016)
			(type default)
		)
		(layer "In3.Cu")
	)
	(gr_line
		(start 391.287254 -5.696204)
		(end 391.287254 -8.363204)
		(stroke
			(width 0.1016)
			(type default)
		)
		(layer "In3.Cu")
	)
	(gr_line
		(start 391.287254 -5.696204)
		(end 392.481054 -5.696204)
		(stroke
			(width 0.1016)
			(type default)
		)
		(layer "In3.Cu")
	)
	(gr_line
		(start 391.287254 -5.596128)
		(end 391.287254 -8.263128)
		(stroke
			(width 0.1016)
			(type default)
		)
		(layer "In3.Cu")
	)
	(gr_line
		(start 391.287254 -5.596128)
		(end 392.481054 -5.596128)
		(stroke
			(width 0.1016)
			(type default)
		)
		(layer "In3.Cu")
	)
	(gr_line
		(start 391.312654 -12.512548)
		(end 391.312654 -9.921748)
		(stroke
			(width 0.1016)
			(type default)
		)
		(layer "In3.Cu")
	)
	(gr_line
		(start 391.312654 -12.412472)
		(end 391.312654 -9.821672)
		(stroke
			(width 0.1016)
			(type default)
		)
		(layer "In3.Cu")
	)
	(gr_line
		(start 391.312654 -9.921748)
		(end 392.455654 -9.921748)
		(stroke
			(width 0.1016)
			(type default)
		)
		(layer "In3.Cu")
	)
	(gr_line
		(start 391.312654 -9.821672)
		(end 392.455654 -9.821672)
		(stroke
			(width 0.1016)
			(type default)
		)
		(layer "In3.Cu")
	)
	(gr_line
		(start 391.312654 -8.312404)
		(end 391.312654 -5.721604)
		(stroke
			(width 0.1016)
			(type default)
		)
		(layer "In3.Cu")
	)
	(gr_line
		(start 391.312654 -8.212328)
		(end 391.312654 -5.621528)
		(stroke
			(width 0.1016)
			(type default)
		)
		(layer "In3.Cu")
	)
	(gr_line
		(start 391.312654 -5.721604)
		(end 392.455654 -5.721604)
		(stroke
			(width 0.1016)
			(type default)
		)
		(layer "In3.Cu")
	)
	(gr_line
		(start 391.312654 -5.621528)
		(end 392.455654 -5.621528)
		(stroke
			(width 0.1016)
			(type default)
		)
		(layer "In3.Cu")
	)
	(gr_line
		(start 391.338054 -12.512548)
		(end 391.338054 -9.947148)
		(stroke
			(width 0.1016)
			(type default)
		)
		(layer "In3.Cu")
	)
	(gr_line
		(start 391.338054 -12.412472)
		(end 391.338054 -9.847072)
		(stroke
			(width 0.1016)
			(type default)
		)
		(layer "In3.Cu")
	)
	(gr_line
		(start 391.338054 -9.947148)
		(end 391.592054 -9.947148)
		(stroke
			(width 0.1016)
			(type default)
		)
		(layer "In3.Cu")
	)
	(gr_line
		(start 391.338054 -9.847072)
		(end 391.592054 -9.847072)
		(stroke
			(width 0.1016)
			(type default)
		)
		(layer "In3.Cu")
	)
	(gr_line
		(start 391.338054 -8.312404)
		(end 391.338054 -5.747004)
		(stroke
			(width 0.1016)
			(type default)
		)
		(layer "In3.Cu")
	)
	(gr_line
		(start 391.338054 -8.212328)
		(end 391.338054 -5.646928)
		(stroke
			(width 0.1016)
			(type default)
		)
		(layer "In3.Cu")
	)
	(gr_line
		(start 391.338054 -5.747004)
		(end 391.592054 -5.747004)
		(stroke
			(width 0.1016)
			(type default)
		)
		(layer "In3.Cu")
	)
	(gr_line
		(start 391.338054 -5.646928)
		(end 391.592054 -5.646928)
		(stroke
			(width 0.1016)
			(type default)
		)
		(layer "In3.Cu")
	)
	(gr_line
		(start 391.363454 -12.512548)
		(end 391.363454 -9.947148)
		(stroke
			(width 0.2032)
			(type default)
		)
		(layer "In3.Cu")
	)
	(gr_line
		(start 391.363454 -12.412472)
		(end 391.363454 -9.847072)
		(stroke
			(width 0.2032)
			(type default)
		)
		(layer "In3.Cu")
	)
	(gr_line
		(start 391.363454 -9.947148)
		(end 392.379454 -9.947148)
		(stroke
			(width 0.2032)
			(type default)
		)
		(layer "In3.Cu")
	)
	(gr_line
		(start 391.363454 -9.847072)
		(end 392.379454 -9.847072)
		(stroke
			(width 0.2032)
			(type default)
		)
		(layer "In3.Cu")
	)
	(gr_line
		(start 391.363454 -8.312404)
		(end 391.363454 -5.747004)
		(stroke
			(width 0.2032)
			(type default)
		)
		(layer "In3.Cu")
	)
	(gr_line
		(start 391.363454 -8.212328)
		(end 391.363454 -5.646928)
		(stroke
			(width 0.2032)
			(type default)
		)
		(layer "In3.Cu")
	)
	(gr_line
		(start 391.363454 -5.747004)
		(end 392.379454 -5.747004)
		(stroke
			(width 0.2032)
			(type default)
		)
		(layer "In3.Cu")
	)
	(gr_line
		(start 391.363454 -5.646928)
		(end 392.379454 -5.646928)
		(stroke
			(width 0.2032)
			(type default)
		)
		(layer "In3.Cu")
	)
	(gr_line
		(start 391.414254 -12.487148)
		(end 391.414254 -9.997948)
		(stroke
			(width 0.2032)
			(type default)
		)
		(layer "In3.Cu")
	)
	(gr_line
		(start 391.414254 -12.487148)
		(end 391.414254 -9.997948)
		(stroke
			(width 0.254)
			(type default)
		)
		(layer "In3.Cu")
	)
	(gr_line
		(start 391.414254 -12.387072)
		(end 391.414254 -9.897872)
		(stroke
			(width 0.2032)
			(type default)
		)
		(layer "In3.Cu")
	)
	(gr_line
		(start 391.414254 -12.387072)
		(end 391.414254 -9.897872)
		(stroke
			(width 0.254)
			(type default)
		)
		(layer "In3.Cu")
	)
	(gr_line
		(start 391.414254 -9.997948)
		(end 391.617454 -9.997948)
		(stroke
			(width 0.2032)
			(type default)
		)
		(layer "In3.Cu")
	)
	(gr_line
		(start 391.414254 -9.997948)
		(end 392.303254 -9.997948)
		(stroke
			(width 0.254)
			(type default)
		)
		(layer "In3.Cu")
	)
	(gr_line
		(start 391.414254 -9.897872)
		(end 391.617454 -9.897872)
		(stroke
			(width 0.2032)
			(type default)
		)
		(layer "In3.Cu")
	)
	(gr_line
		(start 391.414254 -9.897872)
		(end 392.303254 -9.897872)
		(stroke
			(width 0.254)
			(type default)
		)
		(layer "In3.Cu")
	)
	(gr_line
		(start 391.414254 -8.287004)
		(end 391.414254 -5.797804)
		(stroke
			(width 0.2032)
			(type default)
		)
		(layer "In3.Cu")
	)
	(gr_line
		(start 391.414254 -8.287004)
		(end 391.414254 -5.797804)
		(stroke
			(width 0.254)
			(type default)
		)
		(layer "In3.Cu")
	)
	(gr_line
		(start 391.414254 -8.186928)
		(end 391.414254 -5.697728)
		(stroke
			(width 0.2032)
			(type default)
		)
		(layer "In3.Cu")
	)
	(gr_line
		(start 391.414254 -8.186928)
		(end 391.414254 -5.697728)
		(stroke
			(width 0.254)
			(type default)
		)
		(layer "In3.Cu")
	)
	(gr_line
		(start 391.414254 -5.797804)
		(end 391.617454 -5.797804)
		(stroke
			(width 0.2032)
			(type default)
		)
		(layer "In3.Cu")
	)
	(gr_line
		(start 391.414254 -5.797804)
		(end 392.303254 -5.797804)
		(stroke
			(width 0.254)
			(type default)
		)
		(layer "In3.Cu")
	)
	(gr_line
		(start 391.414254 -5.697728)
		(end 391.617454 -5.697728)
		(stroke
			(width 0.2032)
			(type default)
		)
		(layer "In3.Cu")
	)
	(gr_line
		(start 391.414254 -5.697728)
		(end 392.303254 -5.697728)
		(stroke
			(width 0.254)
			(type default)
		)
		(layer "In3.Cu")
	)
	(gr_line
		(start 391.439654 -12.461748)
		(end 391.439654 -10.023348)
		(stroke
			(width 0.254)
			(type default)
		)
		(layer "In3.Cu")
	)
	(gr_line
		(start 391.439654 -12.361672)
		(end 391.439654 -9.923272)
		(stroke
			(width 0.254)
			(type default)
		)
		(layer "In3.Cu")
	)
	(gr_line
		(start 391.439654 -10.023348)
		(end 392.277854 -10.023348)
		(stroke
			(width 0.254)
			(type default)
		)
		(layer "In3.Cu")
	)
	(gr_line
		(start 391.439654 -9.923272)
		(end 392.277854 -9.923272)
		(stroke
			(width 0.254)
			(type default)
		)
		(layer "In3.Cu")
	)
	(gr_line
		(start 391.439654 -8.261604)
		(end 391.439654 -5.823204)
		(stroke
			(width 0.254)
			(type default)
		)
		(layer "In3.Cu")
	)
	(gr_line
		(start 391.439654 -8.161528)
		(end 391.439654 -5.723128)
		(stroke
			(width 0.254)
			(type default)
		)
		(layer "In3.Cu")
	)
	(gr_line
		(start 391.439654 -5.823204)
		(end 392.277854 -5.823204)
		(stroke
			(width 0.254)
			(type default)
		)
		(layer "In3.Cu")
	)
	(gr_line
		(start 391.439654 -5.723128)
		(end 392.277854 -5.723128)
		(stroke
			(width 0.254)
			(type default)
		)
		(layer "In3.Cu")
	)
	(gr_line
		(start 391.465054 -12.436348)
		(end 391.465054 -10.048748)
		(stroke
			(width 0.254)
			(type default)
		)
		(layer "In3.Cu")
	)
	(gr_line
		(start 391.465054 -12.336272)
		(end 391.465054 -9.948672)
		(stroke
			(width 0.254)
			(type default)
		)
		(layer "In3.Cu")
	)
	(gr_line
		(start 391.465054 -10.048748)
		(end 392.252454 -10.048748)
		(stroke
			(width 0.254)
			(type default)
		)
		(layer "In3.Cu")
	)
	(gr_line
		(start 391.465054 -9.948672)
		(end 392.252454 -9.948672)
		(stroke
			(width 0.254)
			(type default)
		)
		(layer "In3.Cu")
	)
	(gr_line
		(start 391.465054 -8.236204)
		(end 391.465054 -5.848604)
		(stroke
			(width 0.254)
			(type default)
		)
		(layer "In3.Cu")
	)
	(gr_line
		(start 391.465054 -8.136128)
		(end 391.465054 -5.748528)
		(stroke
			(width 0.254)
			(type default)
		)
		(layer "In3.Cu")
	)
	(gr_line
		(start 391.465054 -5.848604)
		(end 392.252454 -5.848604)
		(stroke
			(width 0.254)
			(type default)
		)
		(layer "In3.Cu")
	)
	(gr_line
		(start 391.465054 -5.748528)
		(end 392.252454 -5.748528)
		(stroke
			(width 0.254)
			(type default)
		)
		(layer "In3.Cu")
	)
	(gr_line
		(start 391.490454 -12.360148)
		(end 392.125454 -12.360148)
		(stroke
			(width 0.508)
			(type default)
		)
		(layer "In3.Cu")
	)
	(gr_line
		(start 391.490454 -12.260072)
		(end 392.125454 -12.260072)
		(stroke
			(width 0.508)
			(type default)
		)
		(layer "In3.Cu")
	)
	(gr_line
		(start 391.490454 -10.175748)
		(end 392.125454 -10.175748)
		(stroke
			(width 0.508)
			(type default)
		)
		(layer "In3.Cu")
	)
	(gr_line
		(start 391.490454 -10.124948)
		(end 392.125454 -10.124948)
		(stroke
			(width 0.508)
			(type default)
		)
		(layer "In3.Cu")
	)
	(gr_line
		(start 391.490454 -10.075672)
		(end 392.125454 -10.075672)
		(stroke
			(width 0.508)
			(type default)
		)
		(layer "In3.Cu")
	)
	(gr_line
		(start 391.490454 -10.024872)
		(end 392.125454 -10.024872)
		(stroke
			(width 0.508)
			(type default)
		)
		(layer "In3.Cu")
	)
	(gr_line
		(start 391.490454 -8.160004)
		(end 392.125454 -8.160004)
		(stroke
			(width 0.508)
			(type default)
		)
		(layer "In3.Cu")
	)
	(gr_line
		(start 391.490454 -8.059928)
		(end 392.125454 -8.059928)
		(stroke
			(width 0.508)
			(type default)
		)
		(layer "In3.Cu")
	)
	(gr_line
		(start 391.490454 -5.975604)
		(end 392.125454 -5.975604)
		(stroke
			(width 0.508)
			(type default)
		)
		(layer "In3.Cu")
	)
	(gr_line
		(start 391.490454 -5.924804)
		(end 392.125454 -5.924804)
		(stroke
			(width 0.508)
			(type default)
		)
		(layer "In3.Cu")
	)
	(gr_line
		(start 391.490454 -5.875528)
		(end 392.125454 -5.875528)
		(stroke
			(width 0.508)
			(type default)
		)
		(layer "In3.Cu")
	)
	(gr_line
		(start 391.490454 -5.824728)
		(end 392.125454 -5.824728)
		(stroke
			(width 0.508)
			(type default)
		)
		(layer "In3.Cu")
	)
	(gr_line
		(start 391.515854 -10.429748)
		(end 392.150854 -10.429748)
		(stroke
			(width 0.508)
			(type default)
		)
		(layer "In3.Cu")
	)
	(gr_line
		(start 391.515854 -10.329672)
		(end 392.150854 -10.329672)
		(stroke
			(width 0.508)
			(type default)
		)
		(layer "In3.Cu")
	)
	(gr_line
		(start 391.515854 -6.229604)
		(end 392.150854 -6.229604)
		(stroke
			(width 0.508)
			(type default)
		)
		(layer "In3.Cu")
	)
	(gr_line
		(start 391.515854 -6.129528)
		(end 392.150854 -6.129528)
		(stroke
			(width 0.508)
			(type default)
		)
		(layer "In3.Cu")
	)
	(gr_line
		(start 391.541254 -12.385548)
		(end 391.541254 -10.124948)
		(stroke
			(width 0.254)
			(type default)
		)
		(layer "In3.Cu")
	)
	(gr_line
		(start 391.541254 -12.285472)
		(end 391.541254 -10.024872)
		(stroke
			(width 0.254)
			(type default)
		)
		(layer "In3.Cu")
	)
	(gr_line
		(start 391.541254 -12.233148)
		(end 392.176254 -12.233148)
		(stroke
			(width 0.508)
			(type default)
		)
		(layer "In3.Cu")
	)
	(gr_line
		(start 391.541254 -12.133072)
		(end 392.176254 -12.133072)
		(stroke
			(width 0.508)
			(type default)
		)
		(layer "In3.Cu")
	)
	(gr_line
		(start 391.541254 -10.124948)
		(end 392.176254 -10.124948)
		(stroke
			(width 0.254)
			(type default)
		)
		(layer "In3.Cu")
	)
	(gr_line
		(start 391.541254 -10.024872)
		(end 392.176254 -10.024872)
		(stroke
			(width 0.254)
			(type default)
		)
		(layer "In3.Cu")
	)
	(gr_line
		(start 391.541254 -8.185404)
		(end 391.541254 -5.924804)
		(stroke
			(width 0.254)
			(type default)
		)
		(layer "In3.Cu")
	)
	(gr_line
		(start 391.541254 -8.085328)
		(end 391.541254 -5.824728)
		(stroke
			(width 0.254)
			(type default)
		)
		(layer "In3.Cu")
	)
	(gr_line
		(start 391.541254 -8.033004)
		(end 392.176254 -8.033004)
		(stroke
			(width 0.508)
			(type default)
		)
		(layer "In3.Cu")
	)
	(gr_line
		(start 391.541254 -7.932928)
		(end 392.176254 -7.932928)
		(stroke
			(width 0.508)
			(type default)
		)
		(layer "In3.Cu")
	)
	(gr_line
		(start 391.541254 -5.924804)
		(end 392.176254 -5.924804)
		(stroke
			(width 0.254)
			(type default)
		)
		(layer "In3.Cu")
	)
	(gr_line
		(start 391.541254 -5.824728)
		(end 392.176254 -5.824728)
		(stroke
			(width 0.254)
			(type default)
		)
		(layer "In3.Cu")
	)
	(gr_line
		(start 391.566654 -12.080748)
		(end 392.201654 -12.080748)
		(stroke
			(width 0.508)
			(type default)
		)
		(layer "In3.Cu")
	)
	(gr_line
		(start 391.566654 -11.980672)
		(end 392.201654 -11.980672)
		(stroke
			(width 0.508)
			(type default)
		)
		(layer "In3.Cu")
	)
	(gr_line
		(start 391.566654 -7.880604)
		(end 392.201654 -7.880604)
		(stroke
			(width 0.508)
			(type default)
		)
		(layer "In3.Cu")
	)
	(gr_line
		(start 391.566654 -7.780528)
		(end 392.201654 -7.780528)
		(stroke
			(width 0.508)
			(type default)
		)
		(layer "In3.Cu")
	)
	(gr_line
		(start 391.592054 -12.360148)
		(end 392.227054 -12.360148)
		(stroke
			(width 0.508)
			(type default)
		)
		(layer "In3.Cu")
	)
	(gr_line
		(start 391.592054 -12.260072)
		(end 392.227054 -12.260072)
		(stroke
			(width 0.508)
			(type default)
		)
		(layer "In3.Cu")
	)
	(gr_line
		(start 391.592054 -9.947148)
		(end 392.430254 -9.947148)
		(stroke
			(width 0.2032)
			(type default)
		)
		(layer "In3.Cu")
	)
	(gr_line
		(start 391.592054 -9.847072)
		(end 392.430254 -9.847072)
		(stroke
			(width 0.2032)
			(type default)
		)
		(layer "In3.Cu")
	)
	(gr_line
		(start 391.592054 -8.160004)
		(end 392.227054 -8.160004)
		(stroke
			(width 0.508)
			(type default)
		)
		(layer "In3.Cu")
	)
	(gr_line
		(start 391.592054 -8.059928)
		(end 392.227054 -8.059928)
		(stroke
			(width 0.508)
			(type default)
		)
		(layer "In3.Cu")
	)
	(gr_line
		(start 391.592054 -5.747004)
		(end 392.430254 -5.747004)
		(stroke
			(width 0.2032)
			(type default)
		)
		(layer "In3.Cu")
	)
	(gr_line
		(start 391.592054 -5.646928)
		(end 392.430254 -5.646928)
		(stroke
			(width 0.2032)
			(type default)
		)
		(layer "In3.Cu")
	)
	(gr_line
		(start 391.617454 -12.360148)
		(end 391.617454 -10.175748)
		(stroke
			(width 0.254)
			(type default)
		)
		(layer "In3.Cu")
	)
	(gr_line
		(start 391.617454 -12.260072)
		(end 391.617454 -10.075672)
		(stroke
			(width 0.254)
			(type default)
		)
		(layer "In3.Cu")
	)
	(gr_line
		(start 391.617454 -10.175748)
		(end 392.100054 -10.175748)
		(stroke
			(width 0.254)
			(type default)
		)
		(layer "In3.Cu")
	)
	(gr_line
		(start 391.617454 -10.075672)
		(end 392.100054 -10.075672)
		(stroke
			(width 0.254)
			(type default)
		)
		(layer "In3.Cu")
	)
	(gr_line
		(start 391.617454 -9.997948)
		(end 392.354054 -9.997948)
		(stroke
			(width 0.254)
			(type default)
		)
		(layer "In3.Cu")
	)
	(gr_line
		(start 391.617454 -9.897872)
		(end 392.354054 -9.897872)
		(stroke
			(width 0.254)
			(type default)
		)
		(layer "In3.Cu")
	)
	(gr_line
		(start 391.617454 -8.160004)
		(end 391.617454 -5.975604)
		(stroke
			(width 0.254)
			(type default)
		)
		(layer "In3.Cu")
	)
	(gr_line
		(start 391.617454 -8.059928)
		(end 391.617454 -5.875528)
		(stroke
			(width 0.254)
			(type default)
		)
		(layer "In3.Cu")
	)
	(gr_line
		(start 391.617454 -5.975604)
		(end 392.100054 -5.975604)
		(stroke
			(width 0.254)
			(type default)
		)
		(layer "In3.Cu")
	)
	(gr_line
		(start 391.617454 -5.875528)
		(end 392.100054 -5.875528)
		(stroke
			(width 0.254)
			(type default)
		)
		(layer "In3.Cu")
	)
	(gr_line
		(start 391.617454 -5.797804)
		(end 392.354054 -5.797804)
		(stroke
			(width 0.254)
			(type default)
		)
		(layer "In3.Cu")
	)
	(gr_line
		(start 391.617454 -5.697728)
		(end 392.354054 -5.697728)
		(stroke
			(width 0.254)
			(type default)
		)
		(layer "In3.Cu")
	)
	(gr_line
		(start 391.635996 -10.110978)
		(end 392.270996 -10.110978)
		(stroke
			(width 0.508)
			(type default)
		)
		(layer "In3.Cu")
	)
	(gr_line
		(start 391.635996 -10.010902)
		(end 392.270996 -10.010902)
		(stroke
			(width 0.508)
			(type default)
		)
		(layer "In3.Cu")
	)
	(gr_line
		(start 391.635996 -5.910834)
		(end 392.270996 -5.910834)
		(stroke
			(width 0.508)
			(type default)
		)
		(layer "In3.Cu")
	)
	(gr_line
		(start 391.635996 -5.810758)
		(end 392.270996 -5.810758)
		(stroke
			(width 0.508)
			(type default)
		)
		(layer "In3.Cu")
	)
	(gr_line
		(start 391.642854 -12.360148)
		(end 392.277854 -12.360148)
		(stroke
			(width 0.508)
			(type default)
		)
		(layer "In3.Cu")
	)
	(gr_line
		(start 391.642854 -12.260072)
		(end 392.277854 -12.260072)
		(stroke
			(width 0.508)
			(type default)
		)
		(layer "In3.Cu")
	)
	(gr_line
		(start 391.642854 -12.233148)
		(end 391.642854 -10.251948)
		(stroke
			(width 0.762)
			(type default)
		)
		(layer "In3.Cu")
	)
	(gr_line
		(start 391.642854 -12.133072)
		(end 391.642854 -10.151872)
		(stroke
			(width 0.762)
			(type default)
		)
		(layer "In3.Cu")
	)
	(gr_line
		(start 391.642854 -10.251948)
		(end 392.277854 -10.251948)
		(stroke
			(width 0.508)
			(type default)
		)
		(layer "In3.Cu")
	)
	(gr_line
		(start 391.642854 -10.151872)
		(end 392.277854 -10.151872)
		(stroke
			(width 0.508)
			(type default)
		)
		(layer "In3.Cu")
	)
	(gr_line
		(start 391.642854 -8.160004)
		(end 392.277854 -8.160004)
		(stroke
			(width 0.508)
			(type default)
		)
		(layer "In3.Cu")
	)
	(gr_line
		(start 391.642854 -8.059928)
		(end 392.277854 -8.059928)
		(stroke
			(width 0.508)
			(type default)
		)
		(layer "In3.Cu")
	)
	(gr_line
		(start 391.642854 -8.033004)
		(end 391.642854 -6.051804)
		(stroke
			(width 0.762)
			(type default)
		)
		(layer "In3.Cu")
	)
	(gr_line
		(start 391.642854 -7.932928)
		(end 391.642854 -5.951728)
		(stroke
			(width 0.762)
			(type default)
		)
		(layer "In3.Cu")
	)
	(gr_line
		(start 391.642854 -6.051804)
		(end 392.277854 -6.051804)
		(stroke
			(width 0.508)
			(type default)
		)
		(layer "In3.Cu")
	)
	(gr_line
		(start 391.642854 -5.951728)
		(end 392.277854 -5.951728)
		(stroke
			(width 0.508)
			(type default)
		)
		(layer "In3.Cu")
	)
	(gr_line
		(start 391.693654 -12.283948)
		(end 391.693654 -10.251948)
		(stroke
			(width 0.254)
			(type default)
		)
		(layer "In3.Cu")
	)
	(gr_line
		(start 391.693654 -12.183872)
		(end 391.693654 -10.151872)
		(stroke
			(width 0.254)
			(type default)
		)
		(layer "In3.Cu")
	)
	(gr_line
		(start 391.693654 -10.251948)
		(end 392.023854 -10.251948)
		(stroke
			(width 0.254)
			(type default)
		)
		(layer "In3.Cu")
	)
	(gr_line
		(start 391.693654 -10.151872)
		(end 392.023854 -10.151872)
		(stroke
			(width 0.254)
			(type default)
		)
		(layer "In3.Cu")
	)
	(gr_line
		(start 391.693654 -8.083804)
		(end 391.693654 -6.051804)
		(stroke
			(width 0.254)
			(type default)
		)
		(layer "In3.Cu")
	)
	(gr_line
		(start 391.693654 -7.983728)
		(end 391.693654 -5.951728)
		(stroke
			(width 0.254)
			(type default)
		)
		(layer "In3.Cu")
	)
	(gr_line
		(start 391.693654 -6.051804)
		(end 392.023854 -6.051804)
		(stroke
			(width 0.254)
			(type default)
		)
		(layer "In3.Cu")
	)
	(gr_line
		(start 391.693654 -5.951728)
		(end 392.023854 -5.951728)
		(stroke
			(width 0.254)
			(type default)
		)
		(layer "In3.Cu")
	)
	(gr_line
		(start 391.795254 -12.207748)
		(end 391.795254 -10.404348)
		(stroke
			(width 0.254)
			(type default)
		)
		(layer "In3.Cu")
	)
	(gr_line
		(start 391.795254 -12.207748)
		(end 391.795254 -10.226548)
		(stroke
			(width 0.762)
			(type default)
		)
		(layer "In3.Cu")
	)
	(gr_line
		(start 391.795254 -12.107672)
		(end 391.795254 -10.304272)
		(stroke
			(width 0.254)
			(type default)
		)
		(layer "In3.Cu")
	)
	(gr_line
		(start 391.795254 -12.107672)
		(end 391.795254 -10.126472)
		(stroke
			(width 0.762)
			(type default)
		)
		(layer "In3.Cu")
	)
	(gr_line
		(start 391.795254 -10.404348)
		(end 391.896854 -10.404348)
		(stroke
			(width 0.254)
			(type default)
		)
		(layer "In3.Cu")
	)
	(gr_line
		(start 391.795254 -10.304272)
		(end 391.896854 -10.304272)
		(stroke
			(width 0.254)
			(type default)
		)
		(layer "In3.Cu")
	)
	(gr_line
		(start 391.795254 -8.007604)
		(end 391.795254 -6.204204)
		(stroke
			(width 0.254)
			(type default)
		)
		(layer "In3.Cu")
	)
	(gr_line
		(start 391.795254 -8.007604)
		(end 391.795254 -6.026404)
		(stroke
			(width 0.762)
			(type default)
		)
		(layer "In3.Cu")
	)
	(gr_line
		(start 391.795254 -7.907528)
		(end 391.795254 -6.104128)
		(stroke
			(width 0.254)
			(type default)
		)
		(layer "In3.Cu")
	)
	(gr_line
		(start 391.795254 -7.907528)
		(end 391.795254 -5.926328)
		(stroke
			(width 0.762)
			(type default)
		)
		(layer "In3.Cu")
	)
	(gr_line
		(start 391.795254 -6.204204)
		(end 391.896854 -6.204204)
		(stroke
			(width 0.254)
			(type default)
		)
		(layer "In3.Cu")
	)
	(gr_line
		(start 391.795254 -6.104128)
		(end 391.896854 -6.104128)
		(stroke
			(width 0.254)
			(type default)
		)
		(layer "In3.Cu")
	)
	(gr_line
		(start 391.850118 -23.69566)
		(end 393.120118 -23.69566)
		(stroke
			(width 0.7874)
			(type default)
		)
		(layer "In3.Cu")
	)
	(gr_line
		(start 391.896854 -12.309348)
		(end 391.846054 -12.309348)
		(stroke
			(width 0.254)
			(type default)
		)
		(layer "In3.Cu")
	)
	(gr_line
		(start 391.896854 -12.209272)
		(end 391.846054 -12.209272)
		(stroke
			(width 0.254)
			(type default)
		)
		(layer "In3.Cu")
	)
	(gr_line
		(start 391.896854 -10.404348)
		(end 391.896854 -12.309348)
		(stroke
			(width 0.254)
			(type default)
		)
		(layer "In3.Cu")
	)
	(gr_line
		(start 391.896854 -10.304272)
		(end 391.896854 -12.209272)
		(stroke
			(width 0.254)
			(type default)
		)
		(layer "In3.Cu")
	)
	(gr_line
		(start 391.896854 -8.109204)
		(end 391.846054 -8.109204)
		(stroke
			(width 0.254)
			(type default)
		)
		(layer "In3.Cu")
	)
	(gr_line
		(start 391.896854 -8.009128)
		(end 391.846054 -8.009128)
		(stroke
			(width 0.254)
			(type default)
		)
		(layer "In3.Cu")
	)
	(gr_line
		(start 391.896854 -6.204204)
		(end 391.896854 -8.109204)
		(stroke
			(width 0.254)
			(type default)
		)
		(layer "In3.Cu")
	)
	(gr_line
		(start 391.896854 -6.104128)
		(end 391.896854 -8.009128)
		(stroke
			(width 0.254)
			(type default)
		)
		(layer "In3.Cu")
	)
	(gr_line
		(start 391.947654 -12.233148)
		(end 391.947654 -10.251948)
		(stroke
			(width 0.762)
			(type default)
		)
		(layer "In3.Cu")
	)
	(gr_line
		(start 391.947654 -12.133072)
		(end 391.947654 -10.151872)
		(stroke
			(width 0.762)
			(type default)
		)
		(layer "In3.Cu")
	)
	(gr_line
		(start 391.947654 -8.033004)
		(end 391.947654 -6.051804)
		(stroke
			(width 0.762)
			(type default)
		)
		(layer "In3.Cu")
	)
	(gr_line
		(start 391.947654 -7.932928)
		(end 391.947654 -5.951728)
		(stroke
			(width 0.762)
			(type default)
		)
		(layer "In3.Cu")
	)
	(gr_line
		(start 392.023854 -12.207748)
		(end 391.795254 -12.207748)
		(stroke
			(width 0.254)
			(type default)
		)
		(layer "In3.Cu")
	)
	(gr_line
		(start 392.023854 -12.107672)
		(end 391.795254 -12.107672)
		(stroke
			(width 0.254)
			(type default)
		)
		(layer "In3.Cu")
	)
	(gr_line
		(start 392.023854 -10.251948)
		(end 392.023854 -12.207748)
		(stroke
			(width 0.254)
			(type default)
		)
		(layer "In3.Cu")
	)
	(gr_line
		(start 392.023854 -10.151872)
		(end 392.023854 -12.107672)
		(stroke
			(width 0.254)
			(type default)
		)
		(layer "In3.Cu")
	)
	(gr_line
		(start 392.023854 -8.007604)
		(end 391.795254 -8.007604)
		(stroke
			(width 0.254)
			(type default)
		)
		(layer "In3.Cu")
	)
	(gr_line
		(start 392.023854 -7.907528)
		(end 391.795254 -7.907528)
		(stroke
			(width 0.254)
			(type default)
		)
		(layer "In3.Cu")
	)
	(gr_line
		(start 392.023854 -6.051804)
		(end 392.023854 -8.007604)
		(stroke
			(width 0.254)
			(type default)
		)
		(layer "In3.Cu")
	)
	(gr_line
		(start 392.023854 -5.951728)
		(end 392.023854 -7.907528)
		(stroke
			(width 0.254)
			(type default)
		)
		(layer "In3.Cu")
	)
	(gr_line
		(start 392.074654 -12.563348)
		(end 392.074654 -12.512548)
		(stroke
			(width 0.1016)
			(type default)
		)
		(layer "In3.Cu")
	)
	(gr_line
		(start 392.074654 -12.563348)
		(end 392.481054 -12.563348)
		(stroke
			(width 0.1016)
			(type default)
		)
		(layer "In3.Cu")
	)
	(gr_line
		(start 392.074654 -12.512548)
		(end 391.312654 -12.512548)
		(stroke
			(width 0.1016)
			(type default)
		)
		(layer "In3.Cu")
	)
	(gr_line
		(start 392.074654 -12.463272)
		(end 392.074654 -12.412472)
		(stroke
			(width 0.1016)
			(type default)
		)
		(layer "In3.Cu")
	)
	(gr_line
		(start 392.074654 -12.463272)
		(end 392.481054 -12.463272)
		(stroke
			(width 0.1016)
			(type default)
		)
		(layer "In3.Cu")
	)
	(gr_line
		(start 392.074654 -12.412472)
		(end 391.312654 -12.412472)
		(stroke
			(width 0.1016)
			(type default)
		)
		(layer "In3.Cu")
	)
	(gr_line
		(start 392.074654 -12.233148)
		(end 392.074654 -10.251948)
		(stroke
			(width 0.762)
			(type default)
		)
		(layer "In3.Cu")
	)
	(gr_line
		(start 392.074654 -12.133072)
		(end 392.074654 -10.151872)
		(stroke
			(width 0.762)
			(type default)
		)
		(layer "In3.Cu")
	)
	(gr_line
		(start 392.074654 -8.363204)
		(end 392.074654 -8.312404)
		(stroke
			(width 0.1016)
			(type default)
		)
		(layer "In3.Cu")
	)
	(gr_line
		(start 392.074654 -8.363204)
		(end 392.481054 -8.363204)
		(stroke
			(width 0.1016)
			(type default)
		)
		(layer "In3.Cu")
	)
	(gr_line
		(start 392.074654 -8.312404)
		(end 391.312654 -8.312404)
		(stroke
			(width 0.1016)
			(type default)
		)
		(layer "In3.Cu")
	)
	(gr_line
		(start 392.074654 -8.263128)
		(end 392.074654 -8.212328)
		(stroke
			(width 0.1016)
			(type default)
		)
		(layer "In3.Cu")
	)
	(gr_line
		(start 392.074654 -8.263128)
		(end 392.481054 -8.263128)
		(stroke
			(width 0.1016)
			(type default)
		)
		(layer "In3.Cu")
	)
	(gr_line
		(start 392.074654 -8.212328)
		(end 391.312654 -8.212328)
		(stroke
			(width 0.1016)
			(type default)
		)
		(layer "In3.Cu")
	)
	(gr_line
		(start 392.074654 -8.033004)
		(end 392.074654 -6.051804)
		(stroke
			(width 0.762)
			(type default)
		)
		(layer "In3.Cu")
	)
	(gr_line
		(start 392.074654 -7.932928)
		(end 392.074654 -5.951728)
		(stroke
			(width 0.762)
			(type default)
		)
		(layer "In3.Cu")
	)
	(gr_line
		(start 392.100054 -12.283948)
		(end 391.693654 -12.283948)
		(stroke
			(width 0.254)
			(type default)
		)
		(layer "In3.Cu")
	)
	(gr_line
		(start 392.100054 -12.183872)
		(end 391.693654 -12.183872)
		(stroke
			(width 0.254)
			(type default)
		)
		(layer "In3.Cu")
	)
	(gr_line
		(start 392.100054 -10.175748)
		(end 392.100054 -12.283948)
		(stroke
			(width 0.254)
			(type default)
		)
		(layer "In3.Cu")
	)
	(gr_line
		(start 392.100054 -10.075672)
		(end 392.100054 -12.183872)
		(stroke
			(width 0.254)
			(type default)
		)
		(layer "In3.Cu")
	)
	(gr_line
		(start 392.100054 -8.083804)
		(end 391.693654 -8.083804)
		(stroke
			(width 0.254)
			(type default)
		)
		(layer "In3.Cu")
	)
	(gr_line
		(start 392.100054 -7.983728)
		(end 391.693654 -7.983728)
		(stroke
			(width 0.254)
			(type default)
		)
		(layer "In3.Cu")
	)
	(gr_line
		(start 392.100054 -5.975604)
		(end 392.100054 -8.083804)
		(stroke
			(width 0.254)
			(type default)
		)
		(layer "In3.Cu")
	)
	(gr_line
		(start 392.100054 -5.875528)
		(end 392.100054 -7.983728)
		(stroke
			(width 0.254)
			(type default)
		)
		(layer "In3.Cu")
	)
	(gr_line
		(start 392.150854 -12.233148)
		(end 392.150854 -10.251948)
		(stroke
			(width 0.762)
			(type default)
		)
		(layer "In3.Cu")
	)
	(gr_line
		(start 392.150854 -12.133072)
		(end 392.150854 -10.151872)
		(stroke
			(width 0.762)
			(type default)
		)
		(layer "In3.Cu")
	)
	(gr_line
		(start 392.150854 -8.033004)
		(end 392.150854 -6.051804)
		(stroke
			(width 0.762)
			(type default)
		)
		(layer "In3.Cu")
	)
	(gr_line
		(start 392.150854 -7.932928)
		(end 392.150854 -5.951728)
		(stroke
			(width 0.762)
			(type default)
		)
		(layer "In3.Cu")
	)
	(gr_line
		(start 392.176254 -12.360148)
		(end 391.617454 -12.360148)
		(stroke
			(width 0.254)
			(type default)
		)
		(layer "In3.Cu")
	)
	(gr_line
		(start 392.176254 -12.260072)
		(end 391.617454 -12.260072)
		(stroke
			(width 0.254)
			(type default)
		)
		(layer "In3.Cu")
	)
	(gr_line
		(start 392.176254 -10.124948)
		(end 392.176254 -12.360148)
		(stroke
			(width 0.254)
			(type default)
		)
		(layer "In3.Cu")
	)
	(gr_line
		(start 392.176254 -10.024872)
		(end 392.176254 -12.260072)
		(stroke
			(width 0.254)
			(type default)
		)
		(layer "In3.Cu")
	)
	(gr_line
		(start 392.176254 -8.160004)
		(end 391.617454 -8.160004)
		(stroke
			(width 0.254)
			(type default)
		)
		(layer "In3.Cu")
	)
	(gr_line
		(start 392.176254 -8.059928)
		(end 391.617454 -8.059928)
		(stroke
			(width 0.254)
			(type default)
		)
		(layer "In3.Cu")
	)
	(gr_line
		(start 392.176254 -5.924804)
		(end 392.176254 -8.160004)
		(stroke
			(width 0.254)
			(type default)
		)
		(layer "In3.Cu")
	)
	(gr_line
		(start 392.176254 -5.824728)
		(end 392.176254 -8.059928)
		(stroke
			(width 0.254)
			(type default)
		)
		(layer "In3.Cu")
	)
	(gr_line
		(start 392.252454 -12.385548)
		(end 391.541254 -12.385548)
		(stroke
			(width 0.254)
			(type default)
		)
		(layer "In3.Cu")
	)
	(gr_line
		(start 392.252454 -12.285472)
		(end 391.541254 -12.285472)
		(stroke
			(width 0.254)
			(type default)
		)
		(layer "In3.Cu")
	)
	(gr_line
		(start 392.252454 -10.048748)
		(end 392.252454 -12.385548)
		(stroke
			(width 0.254)
			(type default)
		)
		(layer "In3.Cu")
	)
	(gr_line
		(start 392.252454 -9.948672)
		(end 392.252454 -12.285472)
		(stroke
			(width 0.254)
			(type default)
		)
		(layer "In3.Cu")
	)
	(gr_line
		(start 392.252454 -8.185404)
		(end 391.541254 -8.185404)
		(stroke
			(width 0.254)
			(type default)
		)
		(layer "In3.Cu")
	)
	(gr_line
		(start 392.252454 -8.085328)
		(end 391.541254 -8.085328)
		(stroke
			(width 0.254)
			(type default)
		)
		(layer "In3.Cu")
	)
	(gr_line
		(start 392.252454 -5.848604)
		(end 392.252454 -8.185404)
		(stroke
			(width 0.254)
			(type default)
		)
		(layer "In3.Cu")
	)
	(gr_line
		(start 392.252454 -5.748528)
		(end 392.252454 -8.085328)
		(stroke
			(width 0.254)
			(type default)
		)
		(layer "In3.Cu")
	)
	(gr_line
		(start 392.277854 -12.512548)
		(end 391.287254 -12.512548)
		(stroke
			(width 0.1016)
			(type default)
		)
		(layer "In3.Cu")
	)
	(gr_line
		(start 392.277854 -12.436348)
		(end 391.465054 -12.436348)
		(stroke
			(width 0.254)
			(type default)
		)
		(layer "In3.Cu")
	)
	(gr_line
		(start 392.277854 -12.412472)
		(end 391.287254 -12.412472)
		(stroke
			(width 0.1016)
			(type default)
		)
		(layer "In3.Cu")
	)
	(gr_line
		(start 392.277854 -12.336272)
		(end 391.465054 -12.336272)
		(stroke
			(width 0.254)
			(type default)
		)
		(layer "In3.Cu")
	)
	(gr_line
		(start 392.277854 -10.023348)
		(end 392.277854 -12.436348)
		(stroke
			(width 0.254)
			(type default)
		)
		(layer "In3.Cu")
	)
	(gr_line
		(start 392.277854 -9.923272)
		(end 392.277854 -12.336272)
		(stroke
			(width 0.254)
			(type default)
		)
		(layer "In3.Cu")
	)
	(gr_line
		(start 392.277854 -8.312404)
		(end 391.287254 -8.312404)
		(stroke
			(width 0.1016)
			(type default)
		)
		(layer "In3.Cu")
	)
	(gr_line
		(start 392.277854 -8.236204)
		(end 391.465054 -8.236204)
		(stroke
			(width 0.254)
			(type default)
		)
		(layer "In3.Cu")
	)
	(gr_line
		(start 392.277854 -8.212328)
		(end 391.287254 -8.212328)
		(stroke
			(width 0.1016)
			(type default)
		)
		(layer "In3.Cu")
	)
	(gr_line
		(start 392.277854 -8.136128)
		(end 391.465054 -8.136128)
		(stroke
			(width 0.254)
			(type default)
		)
		(layer "In3.Cu")
	)
	(gr_line
		(start 392.277854 -5.823204)
		(end 392.277854 -8.236204)
		(stroke
			(width 0.254)
			(type default)
		)
		(layer "In3.Cu")
	)
	(gr_line
		(start 392.277854 -5.723128)
		(end 392.277854 -8.136128)
		(stroke
			(width 0.254)
			(type default)
		)
		(layer "In3.Cu")
	)
	(gr_line
		(start 392.303254 -12.461748)
		(end 391.439654 -12.461748)
		(stroke
			(width 0.254)
			(type default)
		)
		(layer "In3.Cu")
	)
	(gr_line
		(start 392.303254 -12.361672)
		(end 391.439654 -12.361672)
		(stroke
			(width 0.254)
			(type default)
		)
		(layer "In3.Cu")
	)
	(gr_line
		(start 392.303254 -9.997948)
		(end 392.303254 -12.461748)
		(stroke
			(width 0.254)
			(type default)
		)
		(layer "In3.Cu")
	)
	(gr_line
		(start 392.303254 -9.897872)
		(end 392.303254 -12.361672)
		(stroke
			(width 0.254)
			(type default)
		)
		(layer "In3.Cu")
	)
	(gr_line
		(start 392.303254 -8.261604)
		(end 391.439654 -8.261604)
		(stroke
			(width 0.254)
			(type default)
		)
		(layer "In3.Cu")
	)
	(gr_line
		(start 392.303254 -8.161528)
		(end 391.439654 -8.161528)
		(stroke
			(width 0.254)
			(type default)
		)
		(layer "In3.Cu")
	)
	(gr_line
		(start 392.303254 -5.797804)
		(end 392.303254 -8.261604)
		(stroke
			(width 0.254)
			(type default)
		)
		(layer "In3.Cu")
	)
	(gr_line
		(start 392.303254 -5.697728)
		(end 392.303254 -8.161528)
		(stroke
			(width 0.254)
			(type default)
		)
		(layer "In3.Cu")
	)
	(gr_line
		(start 392.354054 -12.487148)
		(end 391.414254 -12.487148)
		(stroke
			(width 0.254)
			(type default)
		)
		(layer "In3.Cu")
	)
	(gr_line
		(start 392.354054 -12.387072)
		(end 391.414254 -12.387072)
		(stroke
			(width 0.254)
			(type default)
		)
		(layer "In3.Cu")
	)
	(gr_line
		(start 392.354054 -9.997948)
		(end 392.354054 -12.487148)
		(stroke
			(width 0.254)
			(type default)
		)
		(layer "In3.Cu")
	)
	(gr_line
		(start 392.354054 -9.897872)
		(end 392.354054 -12.387072)
		(stroke
			(width 0.254)
			(type default)
		)
		(layer "In3.Cu")
	)
	(gr_line
		(start 392.354054 -8.287004)
		(end 391.414254 -8.287004)
		(stroke
			(width 0.254)
			(type default)
		)
		(layer "In3.Cu")
	)
	(gr_line
		(start 392.354054 -8.186928)
		(end 391.414254 -8.186928)
		(stroke
			(width 0.254)
			(type default)
		)
		(layer "In3.Cu")
	)
	(gr_line
		(start 392.354054 -5.797804)
		(end 392.354054 -8.287004)
		(stroke
			(width 0.254)
			(type default)
		)
		(layer "In3.Cu")
	)
	(gr_line
		(start 392.354054 -5.697728)
		(end 392.354054 -8.186928)
		(stroke
			(width 0.254)
			(type default)
		)
		(layer "In3.Cu")
	)
	(gr_line
		(start 392.379454 -12.487148)
		(end 391.414254 -12.487148)
		(stroke
			(width 0.2032)
			(type default)
		)
		(layer "In3.Cu")
	)
	(gr_line
		(start 392.379454 -12.387072)
		(end 391.414254 -12.387072)
		(stroke
			(width 0.2032)
			(type default)
		)
		(layer "In3.Cu")
	)
	(gr_line
		(start 392.379454 -9.947148)
		(end 392.379454 -12.487148)
		(stroke
			(width 0.2032)
			(type default)
		)
		(layer "In3.Cu")
	)
	(gr_line
		(start 392.379454 -9.847072)
		(end 392.379454 -12.387072)
		(stroke
			(width 0.2032)
			(type default)
		)
		(layer "In3.Cu")
	)
	(gr_line
		(start 392.379454 -8.287004)
		(end 391.414254 -8.287004)
		(stroke
			(width 0.2032)
			(type default)
		)
		(layer "In3.Cu")
	)
	(gr_line
		(start 392.379454 -8.186928)
		(end 391.414254 -8.186928)
		(stroke
			(width 0.2032)
			(type default)
		)
		(layer "In3.Cu")
	)
	(gr_line
		(start 392.379454 -5.747004)
		(end 392.379454 -8.287004)
		(stroke
			(width 0.2032)
			(type default)
		)
		(layer "In3.Cu")
	)
	(gr_line
		(start 392.379454 -5.646928)
		(end 392.379454 -8.186928)
		(stroke
			(width 0.2032)
			(type default)
		)
		(layer "In3.Cu")
	)
	(gr_line
		(start 392.430254 -12.512548)
		(end 391.363454 -12.512548)
		(stroke
			(width 0.2032)
			(type default)
		)
		(layer "In3.Cu")
	)
	(gr_line
		(start 392.430254 -12.412472)
		(end 391.363454 -12.412472)
		(stroke
			(width 0.2032)
			(type default)
		)
		(layer "In3.Cu")
	)
	(gr_line
		(start 392.430254 -9.947148)
		(end 392.430254 -12.512548)
		(stroke
			(width 0.2032)
			(type default)
		)
		(layer "In3.Cu")
	)
	(gr_line
		(start 392.430254 -9.847072)
		(end 392.430254 -12.412472)
		(stroke
			(width 0.2032)
			(type default)
		)
		(layer "In3.Cu")
	)
	(gr_line
		(start 392.430254 -8.312404)
		(end 391.363454 -8.312404)
		(stroke
			(width 0.2032)
			(type default)
		)
		(layer "In3.Cu")
	)
	(gr_line
		(start 392.430254 -8.212328)
		(end 391.363454 -8.212328)
		(stroke
			(width 0.2032)
			(type default)
		)
		(layer "In3.Cu")
	)
	(gr_line
		(start 392.430254 -5.747004)
		(end 392.430254 -8.312404)
		(stroke
			(width 0.2032)
			(type default)
		)
		(layer "In3.Cu")
	)
	(gr_line
		(start 392.430254 -5.646928)
		(end 392.430254 -8.212328)
		(stroke
			(width 0.2032)
			(type default)
		)
		(layer "In3.Cu")
	)
	(gr_line
		(start 392.455654 -12.512548)
		(end 391.338054 -12.512548)
		(stroke
			(width 0.1016)
			(type default)
		)
		(layer "In3.Cu")
	)
	(gr_line
		(start 392.455654 -12.412472)
		(end 391.338054 -12.412472)
		(stroke
			(width 0.1016)
			(type default)
		)
		(layer "In3.Cu")
	)
	(gr_line
		(start 392.455654 -9.921748)
		(end 392.455654 -12.512548)
		(stroke
			(width 0.1016)
			(type default)
		)
		(layer "In3.Cu")
	)
	(gr_line
		(start 392.455654 -9.821672)
		(end 392.455654 -12.412472)
		(stroke
			(width 0.1016)
			(type default)
		)
		(layer "In3.Cu")
	)
	(gr_line
		(start 392.455654 -8.312404)
		(end 391.338054 -8.312404)
		(stroke
			(width 0.1016)
			(type default)
		)
		(layer "In3.Cu")
	)
	(gr_line
		(start 392.455654 -8.212328)
		(end 391.338054 -8.212328)
		(stroke
			(width 0.1016)
			(type default)
		)
		(layer "In3.Cu")
	)
	(gr_line
		(start 392.455654 -5.721604)
		(end 392.455654 -8.312404)
		(stroke
			(width 0.1016)
			(type default)
		)
		(layer "In3.Cu")
	)
	(gr_line
		(start 392.455654 -5.621528)
		(end 392.455654 -8.212328)
		(stroke
			(width 0.1016)
			(type default)
		)
		(layer "In3.Cu")
	)
	(gr_line
		(start 392.481054 -12.563348)
		(end 392.074654 -12.563348)
		(stroke
			(width 0.1016)
			(type default)
		)
		(layer "In3.Cu")
	)
	(gr_line
		(start 392.481054 -12.563348)
		(end 392.481054 -9.896348)
		(stroke
			(width 0.1016)
			(type default)
		)
		(layer "In3.Cu")
	)
	(gr_line
		(start 392.481054 -12.463272)
		(end 392.074654 -12.463272)
		(stroke
			(width 0.1016)
			(type default)
		)
		(layer "In3.Cu")
	)
	(gr_line
		(start 392.481054 -12.463272)
		(end 392.481054 -9.796272)
		(stroke
			(width 0.1016)
			(type default)
		)
		(layer "In3.Cu")
	)
	(gr_line
		(start 392.481054 -9.896348)
		(end 391.287254 -9.896348)
		(stroke
			(width 0.1016)
			(type default)
		)
		(layer "In3.Cu")
	)
	(gr_line
		(start 392.481054 -9.896348)
		(end 392.481054 -12.563348)
		(stroke
			(width 0.1016)
			(type default)
		)
		(layer "In3.Cu")
	)
	(gr_line
		(start 392.481054 -9.796272)
		(end 391.287254 -9.796272)
		(stroke
			(width 0.1016)
			(type default)
		)
		(layer "In3.Cu")
	)
	(gr_line
		(start 392.481054 -9.796272)
		(end 392.481054 -12.463272)
		(stroke
			(width 0.1016)
			(type default)
		)
		(layer "In3.Cu")
	)
	(gr_line
		(start 392.481054 -8.363204)
		(end 392.074654 -8.363204)
		(stroke
			(width 0.1016)
			(type default)
		)
		(layer "In3.Cu")
	)
	(gr_line
		(start 392.481054 -8.363204)
		(end 392.481054 -5.696204)
		(stroke
			(width 0.1016)
			(type default)
		)
		(layer "In3.Cu")
	)
	(gr_line
		(start 392.481054 -8.263128)
		(end 392.074654 -8.263128)
		(stroke
			(width 0.1016)
			(type default)
		)
		(layer "In3.Cu")
	)
	(gr_line
		(start 392.481054 -8.263128)
		(end 392.481054 -5.596128)
		(stroke
			(width 0.1016)
			(type default)
		)
		(layer "In3.Cu")
	)
	(gr_line
		(start 392.481054 -5.696204)
		(end 391.287254 -5.696204)
		(stroke
			(width 0.1016)
			(type default)
		)
		(layer "In3.Cu")
	)
	(gr_line
		(start 392.481054 -5.696204)
		(end 392.481054 -8.363204)
		(stroke
			(width 0.1016)
			(type default)
		)
		(layer "In3.Cu")
	)
	(gr_line
		(start 392.481054 -5.596128)
		(end 391.287254 -5.596128)
		(stroke
			(width 0.1016)
			(type default)
		)
		(layer "In3.Cu")
	)
	(gr_line
		(start 392.481054 -5.596128)
		(end 392.481054 -8.263128)
		(stroke
			(width 0.1016)
			(type default)
		)
		(layer "In3.Cu")
	)
	(gr_line
		(start 392.719814 -31.98622)
		(end 391.449814 -31.98622)
		(stroke
			(width 0.7874)
			(type default)
		)
		(layer "In3.Cu")
	)
	(gr_line
		(start 393.28725 -13.8176)
		(end 394.07465 -13.8176)
		(stroke
			(width 0.1016)
			(type default)
		)
		(layer "In3.Cu")
	)
	(gr_line
		(start 393.28725 -13.7668)
		(end 393.28725 -11.1506)
		(stroke
			(width 0.1016)
			(type default)
		)
		(layer "In3.Cu")
	)
	(gr_line
		(start 393.28725 -11.1506)
		(end 393.28725 -13.8176)
		(stroke
			(width 0.1016)
			(type default)
		)
		(layer "In3.Cu")
	)
	(gr_line
		(start 393.28725 -11.1506)
		(end 394.48105 -11.1506)
		(stroke
			(width 0.1016)
			(type default)
		)
		(layer "In3.Cu")
	)
	(gr_line
		(start 393.28725 -9.617456)
		(end 394.07465 -9.617456)
		(stroke
			(width 0.1016)
			(type default)
		)
		(layer "In3.Cu")
	)
	(gr_line
		(start 393.28725 -9.566656)
		(end 393.28725 -6.950456)
		(stroke
			(width 0.1016)
			(type default)
		)
		(layer "In3.Cu")
	)
	(gr_line
		(start 393.28725 -6.950456)
		(end 393.28725 -9.617456)
		(stroke
			(width 0.1016)
			(type default)
		)
		(layer "In3.Cu")
	)
	(gr_line
		(start 393.28725 -6.950456)
		(end 394.48105 -6.950456)
		(stroke
			(width 0.1016)
			(type default)
		)
		(layer "In3.Cu")
	)
	(gr_line
		(start 393.28725 -5.417312)
		(end 394.07465 -5.417312)
		(stroke
			(width 0.1016)
			(type default)
		)
		(layer "In3.Cu")
	)
	(gr_line
		(start 393.28725 -5.366512)
		(end 393.28725 -2.750312)
		(stroke
			(width 0.1016)
			(type default)
		)
		(layer "In3.Cu")
	)
	(gr_line
		(start 393.28725 -2.750312)
		(end 393.28725 -5.417312)
		(stroke
			(width 0.1016)
			(type default)
		)
		(layer "In3.Cu")
	)
	(gr_line
		(start 393.28725 -2.750312)
		(end 394.48105 -2.750312)
		(stroke
			(width 0.1016)
			(type default)
		)
		(layer "In3.Cu")
	)
	(gr_line
		(start 393.31265 -13.7668)
		(end 393.31265 -11.176)
		(stroke
			(width 0.1016)
			(type default)
		)
		(layer "In3.Cu")
	)
	(gr_line
		(start 393.31265 -11.176)
		(end 394.45565 -11.176)
		(stroke
			(width 0.1016)
			(type default)
		)
		(layer "In3.Cu")
	)
	(gr_line
		(start 393.31265 -9.566656)
		(end 393.31265 -6.975856)
		(stroke
			(width 0.1016)
			(type default)
		)
		(layer "In3.Cu")
	)
	(gr_line
		(start 393.31265 -6.975856)
		(end 394.45565 -6.975856)
		(stroke
			(width 0.1016)
			(type default)
		)
		(layer "In3.Cu")
	)
	(gr_line
		(start 393.31265 -5.366512)
		(end 393.31265 -2.775712)
		(stroke
			(width 0.1016)
			(type default)
		)
		(layer "In3.Cu")
	)
	(gr_line
		(start 393.31265 -2.775712)
		(end 394.45565 -2.775712)
		(stroke
			(width 0.1016)
			(type default)
		)
		(layer "In3.Cu")
	)
	(gr_line
		(start 393.33805 -13.7668)
		(end 393.33805 -11.2014)
		(stroke
			(width 0.1016)
			(type default)
		)
		(layer "In3.Cu")
	)
	(gr_line
		(start 393.33805 -11.2014)
		(end 393.59205 -11.2014)
		(stroke
			(width 0.1016)
			(type default)
		)
		(layer "In3.Cu")
	)
	(gr_line
		(start 393.33805 -9.566656)
		(end 393.33805 -7.001256)
		(stroke
			(width 0.1016)
			(type default)
		)
		(layer "In3.Cu")
	)
	(gr_line
		(start 393.33805 -7.001256)
		(end 393.59205 -7.001256)
		(stroke
			(width 0.1016)
			(type default)
		)
		(layer "In3.Cu")
	)
	(gr_line
		(start 393.33805 -5.366512)
		(end 393.33805 -2.801112)
		(stroke
			(width 0.1016)
			(type default)
		)
		(layer "In3.Cu")
	)
	(gr_line
		(start 393.33805 -2.801112)
		(end 393.59205 -2.801112)
		(stroke
			(width 0.1016)
			(type default)
		)
		(layer "In3.Cu")
	)
	(gr_line
		(start 393.36345 -13.7668)
		(end 393.36345 -11.2014)
		(stroke
			(width 0.2032)
			(type default)
		)
		(layer "In3.Cu")
	)
	(gr_line
		(start 393.36345 -11.2014)
		(end 394.37945 -11.2014)
		(stroke
			(width 0.2032)
			(type default)
		)
		(layer "In3.Cu")
	)
	(gr_line
		(start 393.36345 -9.566656)
		(end 393.36345 -7.001256)
		(stroke
			(width 0.2032)
			(type default)
		)
		(layer "In3.Cu")
	)
	(gr_line
		(start 393.36345 -7.001256)
		(end 394.37945 -7.001256)
		(stroke
			(width 0.2032)
			(type default)
		)
		(layer "In3.Cu")
	)
	(gr_line
		(start 393.36345 -5.366512)
		(end 393.36345 -2.801112)
		(stroke
			(width 0.2032)
			(type default)
		)
		(layer "In3.Cu")
	)
	(gr_line
		(start 393.36345 -2.801112)
		(end 394.37945 -2.801112)
		(stroke
			(width 0.2032)
			(type default)
		)
		(layer "In3.Cu")
	)
	(gr_line
		(start 393.41425 -13.7414)
		(end 393.41425 -11.2522)
		(stroke
			(width 0.2032)
			(type default)
		)
		(layer "In3.Cu")
	)
	(gr_line
		(start 393.41425 -13.7414)
		(end 393.41425 -11.2522)
		(stroke
			(width 0.254)
			(type default)
		)
		(layer "In3.Cu")
	)
	(gr_line
		(start 393.41425 -11.2522)
		(end 393.61745 -11.2522)
		(stroke
			(width 0.2032)
			(type default)
		)
		(layer "In3.Cu")
	)
	(gr_line
		(start 393.41425 -11.2522)
		(end 394.30325 -11.2522)
		(stroke
			(width 0.254)
			(type default)
		)
		(layer "In3.Cu")
	)
	(gr_line
		(start 393.41425 -9.541256)
		(end 393.41425 -7.052056)
		(stroke
			(width 0.2032)
			(type default)
		)
		(layer "In3.Cu")
	)
	(gr_line
		(start 393.41425 -9.541256)
		(end 393.41425 -7.052056)
		(stroke
			(width 0.254)
			(type default)
		)
		(layer "In3.Cu")
	)
	(gr_line
		(start 393.41425 -7.052056)
		(end 393.61745 -7.052056)
		(stroke
			(width 0.2032)
			(type default)
		)
		(layer "In3.Cu")
	)
	(gr_line
		(start 393.41425 -7.052056)
		(end 394.30325 -7.052056)
		(stroke
			(width 0.254)
			(type default)
		)
		(layer "In3.Cu")
	)
	(gr_line
		(start 393.41425 -5.341112)
		(end 393.41425 -2.851912)
		(stroke
			(width 0.2032)
			(type default)
		)
		(layer "In3.Cu")
	)
	(gr_line
		(start 393.41425 -5.341112)
		(end 393.41425 -2.851912)
		(stroke
			(width 0.254)
			(type default)
		)
		(layer "In3.Cu")
	)
	(gr_line
		(start 393.41425 -2.851912)
		(end 393.61745 -2.851912)
		(stroke
			(width 0.2032)
			(type default)
		)
		(layer "In3.Cu")
	)
	(gr_line
		(start 393.41425 -2.851912)
		(end 394.30325 -2.851912)
		(stroke
			(width 0.254)
			(type default)
		)
		(layer "In3.Cu")
	)
	(gr_line
		(start 393.43965 -13.716)
		(end 393.43965 -11.2776)
		(stroke
			(width 0.254)
			(type default)
		)
		(layer "In3.Cu")
	)
	(gr_line
		(start 393.43965 -11.2776)
		(end 394.27785 -11.2776)
		(stroke
			(width 0.254)
			(type default)
		)
		(layer "In3.Cu")
	)
	(gr_line
		(start 393.43965 -9.515856)
		(end 393.43965 -7.077456)
		(stroke
			(width 0.254)
			(type default)
		)
		(layer "In3.Cu")
	)
	(gr_line
		(start 393.43965 -7.077456)
		(end 394.27785 -7.077456)
		(stroke
			(width 0.254)
			(type default)
		)
		(layer "In3.Cu")
	)
	(gr_line
		(start 393.43965 -5.315712)
		(end 393.43965 -2.877312)
		(stroke
			(width 0.254)
			(type default)
		)
		(layer "In3.Cu")
	)
	(gr_line
		(start 393.43965 -2.877312)
		(end 394.27785 -2.877312)
		(stroke
			(width 0.254)
			(type default)
		)
		(layer "In3.Cu")
	)
	(gr_line
		(start 393.46505 -13.6906)
		(end 393.46505 -11.303)
		(stroke
			(width 0.254)
			(type default)
		)
		(layer "In3.Cu")
	)
	(gr_line
		(start 393.46505 -11.303)
		(end 394.25245 -11.303)
		(stroke
			(width 0.254)
			(type default)
		)
		(layer "In3.Cu")
	)
	(gr_line
		(start 393.46505 -9.490456)
		(end 393.46505 -7.102856)
		(stroke
			(width 0.254)
			(type default)
		)
		(layer "In3.Cu")
	)
	(gr_line
		(start 393.46505 -7.102856)
		(end 394.25245 -7.102856)
		(stroke
			(width 0.254)
			(type default)
		)
		(layer "In3.Cu")
	)
	(gr_line
		(start 393.46505 -5.290312)
		(end 393.46505 -2.902712)
		(stroke
			(width 0.254)
			(type default)
		)
		(layer "In3.Cu")
	)
	(gr_line
		(start 393.46505 -2.902712)
		(end 394.25245 -2.902712)
		(stroke
			(width 0.254)
			(type default)
		)
		(layer "In3.Cu")
	)
	(gr_line
		(start 393.49045 -13.6144)
		(end 394.12545 -13.6144)
		(stroke
			(width 0.508)
			(type default)
		)
		(layer "In3.Cu")
	)
	(gr_line
		(start 393.49045 -11.43)
		(end 394.12545 -11.43)
		(stroke
			(width 0.508)
			(type default)
		)
		(layer "In3.Cu")
	)
	(gr_line
		(start 393.49045 -11.3792)
		(end 394.12545 -11.3792)
		(stroke
			(width 0.508)
			(type default)
		)
		(layer "In3.Cu")
	)
	(gr_line
		(start 393.49045 -9.414256)
		(end 394.12545 -9.414256)
		(stroke
			(width 0.508)
			(type default)
		)
		(layer "In3.Cu")
	)
	(gr_line
		(start 393.49045 -7.229856)
		(end 394.12545 -7.229856)
		(stroke
			(width 0.508)
			(type default)
		)
		(layer "In3.Cu")
	)
	(gr_line
		(start 393.49045 -7.179056)
		(end 394.12545 -7.179056)
		(stroke
			(width 0.508)
			(type default)
		)
		(layer "In3.Cu")
	)
	(gr_line
		(start 393.49045 -5.214112)
		(end 394.12545 -5.214112)
		(stroke
			(width 0.508)
			(type default)
		)
		(layer "In3.Cu")
	)
	(gr_line
		(start 393.49045 -3.029712)
		(end 394.12545 -3.029712)
		(stroke
			(width 0.508)
			(type default)
		)
		(layer "In3.Cu")
	)
	(gr_line
		(start 393.49045 -2.978912)
		(end 394.12545 -2.978912)
		(stroke
			(width 0.508)
			(type default)
		)
		(layer "In3.Cu")
	)
	(gr_line
		(start 393.51585 -11.684)
		(end 394.15085 -11.684)
		(stroke
			(width 0.508)
			(type default)
		)
		(layer "In3.Cu")
	)
	(gr_line
		(start 393.51585 -7.483856)
		(end 394.15085 -7.483856)
		(stroke
			(width 0.508)
			(type default)
		)
		(layer "In3.Cu")
	)
	(gr_line
		(start 393.51585 -3.283712)
		(end 394.15085 -3.283712)
		(stroke
			(width 0.508)
			(type default)
		)
		(layer "In3.Cu")
	)
	(gr_line
		(start 393.54125 -13.6398)
		(end 393.54125 -11.3792)
		(stroke
			(width 0.254)
			(type default)
		)
		(layer "In3.Cu")
	)
	(gr_line
		(start 393.54125 -13.4874)
		(end 394.17625 -13.4874)
		(stroke
			(width 0.508)
			(type default)
		)
		(layer "In3.Cu")
	)
	(gr_line
		(start 393.54125 -11.3792)
		(end 394.17625 -11.3792)
		(stroke
			(width 0.254)
			(type default)
		)
		(layer "In3.Cu")
	)
	(gr_line
		(start 393.54125 -9.439656)
		(end 393.54125 -7.179056)
		(stroke
			(width 0.254)
			(type default)
		)
		(layer "In3.Cu")
	)
	(gr_line
		(start 393.54125 -9.287256)
		(end 394.17625 -9.287256)
		(stroke
			(width 0.508)
			(type default)
		)
		(layer "In3.Cu")
	)
	(gr_line
		(start 393.54125 -7.179056)
		(end 394.17625 -7.179056)
		(stroke
			(width 0.254)
			(type default)
		)
		(layer "In3.Cu")
	)
	(gr_line
		(start 393.54125 -5.239512)
		(end 393.54125 -2.978912)
		(stroke
			(width 0.254)
			(type default)
		)
		(layer "In3.Cu")
	)
	(gr_line
		(start 393.54125 -5.087112)
		(end 394.17625 -5.087112)
		(stroke
			(width 0.508)
			(type default)
		)
		(layer "In3.Cu")
	)
	(gr_line
		(start 393.54125 -2.978912)
		(end 394.17625 -2.978912)
		(stroke
			(width 0.254)
			(type default)
		)
		(layer "In3.Cu")
	)
	(gr_line
		(start 393.56665 -13.335)
		(end 394.20165 -13.335)
		(stroke
			(width 0.508)
			(type default)
		)
		(layer "In3.Cu")
	)
	(gr_line
		(start 393.56665 -9.134856)
		(end 394.20165 -9.134856)
		(stroke
			(width 0.508)
			(type default)
		)
		(layer "In3.Cu")
	)
	(gr_line
		(start 393.56665 -4.934712)
		(end 394.20165 -4.934712)
		(stroke
			(width 0.508)
			(type default)
		)
		(layer "In3.Cu")
	)
	(gr_line
		(start 393.59205 -13.6144)
		(end 394.22705 -13.6144)
		(stroke
			(width 0.508)
			(type default)
		)
		(layer "In3.Cu")
	)
	(gr_line
		(start 393.59205 -11.2014)
		(end 394.43025 -11.2014)
		(stroke
			(width 0.2032)
			(type default)
		)
		(layer "In3.Cu")
	)
	(gr_line
		(start 393.59205 -9.414256)
		(end 394.22705 -9.414256)
		(stroke
			(width 0.508)
			(type default)
		)
		(layer "In3.Cu")
	)
	(gr_line
		(start 393.59205 -7.001256)
		(end 394.43025 -7.001256)
		(stroke
			(width 0.2032)
			(type default)
		)
		(layer "In3.Cu")
	)
	(gr_line
		(start 393.59205 -5.214112)
		(end 394.22705 -5.214112)
		(stroke
			(width 0.508)
			(type default)
		)
		(layer "In3.Cu")
	)
	(gr_line
		(start 393.59205 -2.801112)
		(end 394.43025 -2.801112)
		(stroke
			(width 0.2032)
			(type default)
		)
		(layer "In3.Cu")
	)
	(gr_line
		(start 393.61745 -13.6144)
		(end 393.61745 -11.43)
		(stroke
			(width 0.254)
			(type default)
		)
		(layer "In3.Cu")
	)
	(gr_line
		(start 393.61745 -11.43)
		(end 394.10005 -11.43)
		(stroke
			(width 0.254)
			(type default)
		)
		(layer "In3.Cu")
	)
	(gr_line
		(start 393.61745 -11.2522)
		(end 394.35405 -11.2522)
		(stroke
			(width 0.254)
			(type default)
		)
		(layer "In3.Cu")
	)
	(gr_line
		(start 393.61745 -9.414256)
		(end 393.61745 -7.229856)
		(stroke
			(width 0.254)
			(type default)
		)
		(layer "In3.Cu")
	)
	(gr_line
		(start 393.61745 -7.229856)
		(end 394.10005 -7.229856)
		(stroke
			(width 0.254)
			(type default)
		)
		(layer "In3.Cu")
	)
	(gr_line
		(start 393.61745 -7.052056)
		(end 394.35405 -7.052056)
		(stroke
			(width 0.254)
			(type default)
		)
		(layer "In3.Cu")
	)
	(gr_line
		(start 393.61745 -5.214112)
		(end 393.61745 -3.029712)
		(stroke
			(width 0.254)
			(type default)
		)
		(layer "In3.Cu")
	)
	(gr_line
		(start 393.61745 -3.029712)
		(end 394.10005 -3.029712)
		(stroke
			(width 0.254)
			(type default)
		)
		(layer "In3.Cu")
	)
	(gr_line
		(start 393.61745 -2.851912)
		(end 394.35405 -2.851912)
		(stroke
			(width 0.254)
			(type default)
		)
		(layer "In3.Cu")
	)
	(gr_line
		(start 393.635992 -11.36523)
		(end 394.270992 -11.36523)
		(stroke
			(width 0.508)
			(type default)
		)
		(layer "In3.Cu")
	)
	(gr_line
		(start 393.635992 -7.165086)
		(end 394.270992 -7.165086)
		(stroke
			(width 0.508)
			(type default)
		)
		(layer "In3.Cu")
	)
	(gr_line
		(start 393.635992 -2.964942)
		(end 394.270992 -2.964942)
		(stroke
			(width 0.508)
			(type default)
		)
		(layer "In3.Cu")
	)
	(gr_line
		(start 393.64285 -13.6144)
		(end 394.27785 -13.6144)
		(stroke
			(width 0.508)
			(type default)
		)
		(layer "In3.Cu")
	)
	(gr_line
		(start 393.64285 -13.4874)
		(end 393.64285 -11.5062)
		(stroke
			(width 0.762)
			(type default)
		)
		(layer "In3.Cu")
	)
	(gr_line
		(start 393.64285 -11.5062)
		(end 394.27785 -11.5062)
		(stroke
			(width 0.508)
			(type default)
		)
		(layer "In3.Cu")
	)
	(gr_line
		(start 393.64285 -9.414256)
		(end 394.27785 -9.414256)
		(stroke
			(width 0.508)
			(type default)
		)
		(layer "In3.Cu")
	)
	(gr_line
		(start 393.64285 -9.287256)
		(end 393.64285 -7.306056)
		(stroke
			(width 0.762)
			(type default)
		)
		(layer "In3.Cu")
	)
	(gr_line
		(start 393.64285 -7.306056)
		(end 394.27785 -7.306056)
		(stroke
			(width 0.508)
			(type default)
		)
		(layer "In3.Cu")
	)
	(gr_line
		(start 393.64285 -5.214112)
		(end 394.27785 -5.214112)
		(stroke
			(width 0.508)
			(type default)
		)
		(layer "In3.Cu")
	)
	(gr_line
		(start 393.64285 -5.087112)
		(end 393.64285 -3.105912)
		(stroke
			(width 0.762)
			(type default)
		)
		(layer "In3.Cu")
	)
	(gr_line
		(start 393.64285 -3.105912)
		(end 394.27785 -3.105912)
		(stroke
			(width 0.508)
			(type default)
		)
		(layer "In3.Cu")
	)
	(gr_line
		(start 393.69365 -13.5382)
		(end 393.69365 -11.5062)
		(stroke
			(width 0.254)
			(type default)
		)
		(layer "In3.Cu")
	)
	(gr_line
		(start 393.69365 -11.5062)
		(end 394.02385 -11.5062)
		(stroke
			(width 0.254)
			(type default)
		)
		(layer "In3.Cu")
	)
	(gr_line
		(start 393.69365 -9.338056)
		(end 393.69365 -7.306056)
		(stroke
			(width 0.254)
			(type default)
		)
		(layer "In3.Cu")
	)
	(gr_line
		(start 393.69365 -7.306056)
		(end 394.02385 -7.306056)
		(stroke
			(width 0.254)
			(type default)
		)
		(layer "In3.Cu")
	)
	(gr_line
		(start 393.69365 -5.137912)
		(end 393.69365 -3.105912)
		(stroke
			(width 0.254)
			(type default)
		)
		(layer "In3.Cu")
	)
	(gr_line
		(start 393.69365 -3.105912)
		(end 394.02385 -3.105912)
		(stroke
			(width 0.254)
			(type default)
		)
		(layer "In3.Cu")
	)
	(gr_line
		(start 393.79525 -13.462)
		(end 393.79525 -11.6586)
		(stroke
			(width 0.254)
			(type default)
		)
		(layer "In3.Cu")
	)
	(gr_line
		(start 393.79525 -13.462)
		(end 393.79525 -11.4808)
		(stroke
			(width 0.762)
			(type default)
		)
		(layer "In3.Cu")
	)
	(gr_line
		(start 393.79525 -11.6586)
		(end 393.89685 -11.6586)
		(stroke
			(width 0.254)
			(type default)
		)
		(layer "In3.Cu")
	)
	(gr_line
		(start 393.79525 -9.261856)
		(end 393.79525 -7.458456)
		(stroke
			(width 0.254)
			(type default)
		)
		(layer "In3.Cu")
	)
	(gr_line
		(start 393.79525 -9.261856)
		(end 393.79525 -7.280656)
		(stroke
			(width 0.762)
			(type default)
		)
		(layer "In3.Cu")
	)
	(gr_line
		(start 393.79525 -7.458456)
		(end 393.89685 -7.458456)
		(stroke
			(width 0.254)
			(type default)
		)
		(layer "In3.Cu")
	)
	(gr_line
		(start 393.79525 -5.061712)
		(end 393.79525 -3.258312)
		(stroke
			(width 0.254)
			(type default)
		)
		(layer "In3.Cu")
	)
	(gr_line
		(start 393.79525 -5.061712)
		(end 393.79525 -3.080512)
		(stroke
			(width 0.762)
			(type default)
		)
		(layer "In3.Cu")
	)
	(gr_line
		(start 393.79525 -3.258312)
		(end 393.89685 -3.258312)
		(stroke
			(width 0.254)
			(type default)
		)
		(layer "In3.Cu")
	)
	(gr_line
		(start 393.89685 -13.5636)
		(end 393.84605 -13.5636)
		(stroke
			(width 0.254)
			(type default)
		)
		(layer "In3.Cu")
	)
	(gr_line
		(start 393.89685 -11.6586)
		(end 393.89685 -13.5636)
		(stroke
			(width 0.254)
			(type default)
		)
		(layer "In3.Cu")
	)
	(gr_line
		(start 393.89685 -9.363456)
		(end 393.84605 -9.363456)
		(stroke
			(width 0.254)
			(type default)
		)
		(layer "In3.Cu")
	)
	(gr_line
		(start 393.89685 -7.458456)
		(end 393.89685 -9.363456)
		(stroke
			(width 0.254)
			(type default)
		)
		(layer "In3.Cu")
	)
	(gr_line
		(start 393.89685 -5.163312)
		(end 393.84605 -5.163312)
		(stroke
			(width 0.254)
			(type default)
		)
		(layer "In3.Cu")
	)
	(gr_line
		(start 393.89685 -3.258312)
		(end 393.89685 -5.163312)
		(stroke
			(width 0.254)
			(type default)
		)
		(layer "In3.Cu")
	)
	(gr_line
		(start 393.94765 -13.4874)
		(end 393.94765 -11.5062)
		(stroke
			(width 0.762)
			(type default)
		)
		(layer "In3.Cu")
	)
	(gr_line
		(start 393.94765 -9.287256)
		(end 393.94765 -7.306056)
		(stroke
			(width 0.762)
			(type default)
		)
		(layer "In3.Cu")
	)
	(gr_line
		(start 393.94765 -5.087112)
		(end 393.94765 -3.105912)
		(stroke
			(width 0.762)
			(type default)
		)
		(layer "In3.Cu")
	)
	(gr_line
		(start 394.02385 -13.462)
		(end 393.79525 -13.462)
		(stroke
			(width 0.254)
			(type default)
		)
		(layer "In3.Cu")
	)
	(gr_line
		(start 394.02385 -11.5062)
		(end 394.02385 -13.462)
		(stroke
			(width 0.254)
			(type default)
		)
		(layer "In3.Cu")
	)
	(gr_line
		(start 394.02385 -9.261856)
		(end 393.79525 -9.261856)
		(stroke
			(width 0.254)
			(type default)
		)
		(layer "In3.Cu")
	)
	(gr_line
		(start 394.02385 -7.306056)
		(end 394.02385 -9.261856)
		(stroke
			(width 0.254)
			(type default)
		)
		(layer "In3.Cu")
	)
	(gr_line
		(start 394.02385 -5.061712)
		(end 393.79525 -5.061712)
		(stroke
			(width 0.254)
			(type default)
		)
		(layer "In3.Cu")
	)
	(gr_line
		(start 394.02385 -3.105912)
		(end 394.02385 -5.061712)
		(stroke
			(width 0.254)
			(type default)
		)
		(layer "In3.Cu")
	)
	(gr_line
		(start 394.07465 -13.8176)
		(end 394.07465 -13.7668)
		(stroke
			(width 0.1016)
			(type default)
		)
		(layer "In3.Cu")
	)
	(gr_line
		(start 394.07465 -13.8176)
		(end 394.48105 -13.8176)
		(stroke
			(width 0.1016)
			(type default)
		)
		(layer "In3.Cu")
	)
	(gr_line
		(start 394.07465 -13.7668)
		(end 393.31265 -13.7668)
		(stroke
			(width 0.1016)
			(type default)
		)
		(layer "In3.Cu")
	)
	(gr_line
		(start 394.07465 -13.4874)
		(end 394.07465 -11.5062)
		(stroke
			(width 0.762)
			(type default)
		)
		(layer "In3.Cu")
	)
	(gr_line
		(start 394.07465 -9.617456)
		(end 394.07465 -9.566656)
		(stroke
			(width 0.1016)
			(type default)
		)
		(layer "In3.Cu")
	)
	(gr_line
		(start 394.07465 -9.617456)
		(end 394.48105 -9.617456)
		(stroke
			(width 0.1016)
			(type default)
		)
		(layer "In3.Cu")
	)
	(gr_line
		(start 394.07465 -9.566656)
		(end 393.31265 -9.566656)
		(stroke
			(width 0.1016)
			(type default)
		)
		(layer "In3.Cu")
	)
	(gr_line
		(start 394.07465 -9.287256)
		(end 394.07465 -7.306056)
		(stroke
			(width 0.762)
			(type default)
		)
		(layer "In3.Cu")
	)
	(gr_line
		(start 394.07465 -5.417312)
		(end 394.07465 -5.366512)
		(stroke
			(width 0.1016)
			(type default)
		)
		(layer "In3.Cu")
	)
	(gr_line
		(start 394.07465 -5.417312)
		(end 394.48105 -5.417312)
		(stroke
			(width 0.1016)
			(type default)
		)
		(layer "In3.Cu")
	)
	(gr_line
		(start 394.07465 -5.366512)
		(end 393.31265 -5.366512)
		(stroke
			(width 0.1016)
			(type default)
		)
		(layer "In3.Cu")
	)
	(gr_line
		(start 394.07465 -5.087112)
		(end 394.07465 -3.105912)
		(stroke
			(width 0.762)
			(type default)
		)
		(layer "In3.Cu")
	)
	(gr_line
		(start 394.10005 -13.5382)
		(end 393.69365 -13.5382)
		(stroke
			(width 0.254)
			(type default)
		)
		(layer "In3.Cu")
	)
	(gr_line
		(start 394.10005 -11.43)
		(end 394.10005 -13.5382)
		(stroke
			(width 0.254)
			(type default)
		)
		(layer "In3.Cu")
	)
	(gr_line
		(start 394.10005 -9.338056)
		(end 393.69365 -9.338056)
		(stroke
			(width 0.254)
			(type default)
		)
		(layer "In3.Cu")
	)
	(gr_line
		(start 394.10005 -7.229856)
		(end 394.10005 -9.338056)
		(stroke
			(width 0.254)
			(type default)
		)
		(layer "In3.Cu")
	)
	(gr_line
		(start 394.10005 -5.137912)
		(end 393.69365 -5.137912)
		(stroke
			(width 0.254)
			(type default)
		)
		(layer "In3.Cu")
	)
	(gr_line
		(start 394.10005 -3.029712)
		(end 394.10005 -5.137912)
		(stroke
			(width 0.254)
			(type default)
		)
		(layer "In3.Cu")
	)
	(gr_line
		(start 394.15085 -13.4874)
		(end 394.15085 -11.5062)
		(stroke
			(width 0.762)
			(type default)
		)
		(layer "In3.Cu")
	)
	(gr_line
		(start 394.15085 -9.287256)
		(end 394.15085 -7.306056)
		(stroke
			(width 0.762)
			(type default)
		)
		(layer "In3.Cu")
	)
	(gr_line
		(start 394.15085 -5.087112)
		(end 394.15085 -3.105912)
		(stroke
			(width 0.762)
			(type default)
		)
		(layer "In3.Cu")
	)
	(gr_line
		(start 394.17625 -13.6144)
		(end 393.61745 -13.6144)
		(stroke
			(width 0.254)
			(type default)
		)
		(layer "In3.Cu")
	)
	(gr_line
		(start 394.17625 -11.3792)
		(end 394.17625 -13.6144)
		(stroke
			(width 0.254)
			(type default)
		)
		(layer "In3.Cu")
	)
	(gr_line
		(start 394.17625 -9.414256)
		(end 393.61745 -9.414256)
		(stroke
			(width 0.254)
			(type default)
		)
		(layer "In3.Cu")
	)
	(gr_line
		(start 394.17625 -7.179056)
		(end 394.17625 -9.414256)
		(stroke
			(width 0.254)
			(type default)
		)
		(layer "In3.Cu")
	)
	(gr_line
		(start 394.17625 -5.214112)
		(end 393.61745 -5.214112)
		(stroke
			(width 0.254)
			(type default)
		)
		(layer "In3.Cu")
	)
	(gr_line
		(start 394.17625 -2.978912)
		(end 394.17625 -5.214112)
		(stroke
			(width 0.254)
			(type default)
		)
		(layer "In3.Cu")
	)
	(gr_line
		(start 394.25245 -13.6398)
		(end 393.54125 -13.6398)
		(stroke
			(width 0.254)
			(type default)
		)
		(layer "In3.Cu")
	)
	(gr_line
		(start 394.25245 -11.303)
		(end 394.25245 -13.6398)
		(stroke
			(width 0.254)
			(type default)
		)
		(layer "In3.Cu")
	)
	(gr_line
		(start 394.25245 -9.439656)
		(end 393.54125 -9.439656)
		(stroke
			(width 0.254)
			(type default)
		)
		(layer "In3.Cu")
	)
	(gr_line
		(start 394.25245 -7.102856)
		(end 394.25245 -9.439656)
		(stroke
			(width 0.254)
			(type default)
		)
		(layer "In3.Cu")
	)
	(gr_line
		(start 394.25245 -5.239512)
		(end 393.54125 -5.239512)
		(stroke
			(width 0.254)
			(type default)
		)
		(layer "In3.Cu")
	)
	(gr_line
		(start 394.25245 -2.902712)
		(end 394.25245 -5.239512)
		(stroke
			(width 0.254)
			(type default)
		)
		(layer "In3.Cu")
	)
	(gr_line
		(start 394.27785 -13.7668)
		(end 393.28725 -13.7668)
		(stroke
			(width 0.1016)
			(type default)
		)
		(layer "In3.Cu")
	)
	(gr_line
		(start 394.27785 -13.6906)
		(end 393.46505 -13.6906)
		(stroke
			(width 0.254)
			(type default)
		)
		(layer "In3.Cu")
	)
	(gr_line
		(start 394.27785 -11.2776)
		(end 394.27785 -13.6906)
		(stroke
			(width 0.254)
			(type default)
		)
		(layer "In3.Cu")
	)
	(gr_line
		(start 394.27785 -9.566656)
		(end 393.28725 -9.566656)
		(stroke
			(width 0.1016)
			(type default)
		)
		(layer "In3.Cu")
	)
	(gr_line
		(start 394.27785 -9.490456)
		(end 393.46505 -9.490456)
		(stroke
			(width 0.254)
			(type default)
		)
		(layer "In3.Cu")
	)
	(gr_line
		(start 394.27785 -7.077456)
		(end 394.27785 -9.490456)
		(stroke
			(width 0.254)
			(type default)
		)
		(layer "In3.Cu")
	)
	(gr_line
		(start 394.27785 -5.366512)
		(end 393.28725 -5.366512)
		(stroke
			(width 0.1016)
			(type default)
		)
		(layer "In3.Cu")
	)
	(gr_line
		(start 394.27785 -5.290312)
		(end 393.46505 -5.290312)
		(stroke
			(width 0.254)
			(type default)
		)
		(layer "In3.Cu")
	)
	(gr_line
		(start 394.27785 -2.877312)
		(end 394.27785 -5.290312)
		(stroke
			(width 0.254)
			(type default)
		)
		(layer "In3.Cu")
	)
	(gr_line
		(start 394.30325 -13.716)
		(end 393.43965 -13.716)
		(stroke
			(width 0.254)
			(type default)
		)
		(layer "In3.Cu")
	)
	(gr_line
		(start 394.30325 -11.2522)
		(end 394.30325 -13.716)
		(stroke
			(width 0.254)
			(type default)
		)
		(layer "In3.Cu")
	)
	(gr_line
		(start 394.30325 -9.515856)
		(end 393.43965 -9.515856)
		(stroke
			(width 0.254)
			(type default)
		)
		(layer "In3.Cu")
	)
	(gr_line
		(start 394.30325 -7.052056)
		(end 394.30325 -9.515856)
		(stroke
			(width 0.254)
			(type default)
		)
		(layer "In3.Cu")
	)
	(gr_line
		(start 394.30325 -5.315712)
		(end 393.43965 -5.315712)
		(stroke
			(width 0.254)
			(type default)
		)
		(layer "In3.Cu")
	)
	(gr_line
		(start 394.30325 -2.851912)
		(end 394.30325 -5.315712)
		(stroke
			(width 0.254)
			(type default)
		)
		(layer "In3.Cu")
	)
	(gr_line
		(start 394.35405 -13.7414)
		(end 393.41425 -13.7414)
		(stroke
			(width 0.254)
			(type default)
		)
		(layer "In3.Cu")
	)
	(gr_line
		(start 394.35405 -11.2522)
		(end 394.35405 -13.7414)
		(stroke
			(width 0.254)
			(type default)
		)
		(layer "In3.Cu")
	)
	(gr_line
		(start 394.35405 -9.541256)
		(end 393.41425 -9.541256)
		(stroke
			(width 0.254)
			(type default)
		)
		(layer "In3.Cu")
	)
	(gr_line
		(start 394.35405 -7.052056)
		(end 394.35405 -9.541256)
		(stroke
			(width 0.254)
			(type default)
		)
		(layer "In3.Cu")
	)
	(gr_line
		(start 394.35405 -5.341112)
		(end 393.41425 -5.341112)
		(stroke
			(width 0.254)
			(type default)
		)
		(layer "In3.Cu")
	)
	(gr_line
		(start 394.35405 -2.851912)
		(end 394.35405 -5.341112)
		(stroke
			(width 0.254)
			(type default)
		)
		(layer "In3.Cu")
	)
	(gr_line
		(start 394.37945 -13.7414)
		(end 393.41425 -13.7414)
		(stroke
			(width 0.2032)
			(type default)
		)
		(layer "In3.Cu")
	)
	(gr_line
		(start 394.37945 -11.2014)
		(end 394.37945 -13.7414)
		(stroke
			(width 0.2032)
			(type default)
		)
		(layer "In3.Cu")
	)
	(gr_line
		(start 394.37945 -9.541256)
		(end 393.41425 -9.541256)
		(stroke
			(width 0.2032)
			(type default)
		)
		(layer "In3.Cu")
	)
	(gr_line
		(start 394.37945 -7.001256)
		(end 394.37945 -9.541256)
		(stroke
			(width 0.2032)
			(type default)
		)
		(layer "In3.Cu")
	)
	(gr_line
		(start 394.37945 -5.341112)
		(end 393.41425 -5.341112)
		(stroke
			(width 0.2032)
			(type default)
		)
		(layer "In3.Cu")
	)
	(gr_line
		(start 394.37945 -2.801112)
		(end 394.37945 -5.341112)
		(stroke
			(width 0.2032)
			(type default)
		)
		(layer "In3.Cu")
	)
	(gr_line
		(start 394.43025 -13.7668)
		(end 393.36345 -13.7668)
		(stroke
			(width 0.2032)
			(type default)
		)
		(layer "In3.Cu")
	)
	(gr_line
		(start 394.43025 -11.2014)
		(end 394.43025 -13.7668)
		(stroke
			(width 0.2032)
			(type default)
		)
		(layer "In3.Cu")
	)
	(gr_line
		(start 394.43025 -9.566656)
		(end 393.36345 -9.566656)
		(stroke
			(width 0.2032)
			(type default)
		)
		(layer "In3.Cu")
	)
	(gr_line
		(start 394.43025 -7.001256)
		(end 394.43025 -9.566656)
		(stroke
			(width 0.2032)
			(type default)
		)
		(layer "In3.Cu")
	)
	(gr_line
		(start 394.43025 -5.366512)
		(end 393.36345 -5.366512)
		(stroke
			(width 0.2032)
			(type default)
		)
		(layer "In3.Cu")
	)
	(gr_line
		(start 394.43025 -2.801112)
		(end 394.43025 -5.366512)
		(stroke
			(width 0.2032)
			(type default)
		)
		(layer "In3.Cu")
	)
	(gr_line
		(start 394.45565 -13.7668)
		(end 393.33805 -13.7668)
		(stroke
			(width 0.1016)
			(type default)
		)
		(layer "In3.Cu")
	)
	(gr_line
		(start 394.45565 -11.176)
		(end 394.45565 -13.7668)
		(stroke
			(width 0.1016)
			(type default)
		)
		(layer "In3.Cu")
	)
	(gr_line
		(start 394.45565 -9.566656)
		(end 393.33805 -9.566656)
		(stroke
			(width 0.1016)
			(type default)
		)
		(layer "In3.Cu")
	)
	(gr_line
		(start 394.45565 -6.975856)
		(end 394.45565 -9.566656)
		(stroke
			(width 0.1016)
			(type default)
		)
		(layer "In3.Cu")
	)
	(gr_line
		(start 394.45565 -5.366512)
		(end 393.33805 -5.366512)
		(stroke
			(width 0.1016)
			(type default)
		)
		(layer "In3.Cu")
	)
	(gr_line
		(start 394.45565 -2.775712)
		(end 394.45565 -5.366512)
		(stroke
			(width 0.1016)
			(type default)
		)
		(layer "In3.Cu")
	)
	(gr_line
		(start 394.48105 -13.8176)
		(end 394.07465 -13.8176)
		(stroke
			(width 0.1016)
			(type default)
		)
		(layer "In3.Cu")
	)
	(gr_line
		(start 394.48105 -13.8176)
		(end 394.48105 -11.1506)
		(stroke
			(width 0.1016)
			(type default)
		)
		(layer "In3.Cu")
	)
	(gr_line
		(start 394.48105 -11.1506)
		(end 393.28725 -11.1506)
		(stroke
			(width 0.1016)
			(type default)
		)
		(layer "In3.Cu")
	)
	(gr_line
		(start 394.48105 -11.1506)
		(end 394.48105 -13.8176)
		(stroke
			(width 0.1016)
			(type default)
		)
		(layer "In3.Cu")
	)
	(gr_line
		(start 394.48105 -9.617456)
		(end 394.07465 -9.617456)
		(stroke
			(width 0.1016)
			(type default)
		)
		(layer "In3.Cu")
	)
	(gr_line
		(start 394.48105 -9.617456)
		(end 394.48105 -6.950456)
		(stroke
			(width 0.1016)
			(type default)
		)
		(layer "In3.Cu")
	)
	(gr_line
		(start 394.48105 -6.950456)
		(end 393.28725 -6.950456)
		(stroke
			(width 0.1016)
			(type default)
		)
		(layer "In3.Cu")
	)
	(gr_line
		(start 394.48105 -6.950456)
		(end 394.48105 -9.617456)
		(stroke
			(width 0.1016)
			(type default)
		)
		(layer "In3.Cu")
	)
	(gr_line
		(start 394.48105 -5.417312)
		(end 394.07465 -5.417312)
		(stroke
			(width 0.1016)
			(type default)
		)
		(layer "In3.Cu")
	)
	(gr_line
		(start 394.48105 -5.417312)
		(end 394.48105 -2.750312)
		(stroke
			(width 0.1016)
			(type default)
		)
		(layer "In3.Cu")
	)
	(gr_line
		(start 394.48105 -2.750312)
		(end 393.28725 -2.750312)
		(stroke
			(width 0.1016)
			(type default)
		)
		(layer "In3.Cu")
	)
	(gr_line
		(start 394.48105 -2.750312)
		(end 394.48105 -5.417312)
		(stroke
			(width 0.1016)
			(type default)
		)
		(layer "In3.Cu")
	)
	(gr_line
		(start 395.14526 -32.9184)
		(end 393.87526 -32.9184)
		(stroke
			(width 0.7874)
			(type default)
		)
		(layer "In3.Cu")
	)
	(gr_line
		(start 395.287246 -12.563348)
		(end 396.074646 -12.563348)
		(stroke
			(width 0.1016)
			(type default)
		)
		(layer "In3.Cu")
	)
	(gr_line
		(start 395.287246 -12.512548)
		(end 395.287246 -9.896348)
		(stroke
			(width 0.1016)
			(type default)
		)
		(layer "In3.Cu")
	)
	(gr_line
		(start 395.287246 -12.463272)
		(end 396.074646 -12.463272)
		(stroke
			(width 0.1016)
			(type default)
		)
		(layer "In3.Cu")
	)
	(gr_line
		(start 395.287246 -12.412472)
		(end 395.287246 -9.796272)
		(stroke
			(width 0.1016)
			(type default)
		)
		(layer "In3.Cu")
	)
	(gr_line
		(start 395.287246 -9.896348)
		(end 395.287246 -12.563348)
		(stroke
			(width 0.1016)
			(type default)
		)
		(layer "In3.Cu")
	)
	(gr_line
		(start 395.287246 -9.896348)
		(end 396.481046 -9.896348)
		(stroke
			(width 0.1016)
			(type default)
		)
		(layer "In3.Cu")
	)
	(gr_line
		(start 395.287246 -9.796272)
		(end 395.287246 -12.463272)
		(stroke
			(width 0.1016)
			(type default)
		)
		(layer "In3.Cu")
	)
	(gr_line
		(start 395.287246 -9.796272)
		(end 396.481046 -9.796272)
		(stroke
			(width 0.1016)
			(type default)
		)
		(layer "In3.Cu")
	)
	(gr_line
		(start 395.287246 -8.363204)
		(end 396.074646 -8.363204)
		(stroke
			(width 0.1016)
			(type default)
		)
		(layer "In3.Cu")
	)
	(gr_line
		(start 395.287246 -8.312404)
		(end 395.287246 -5.696204)
		(stroke
			(width 0.1016)
			(type default)
		)
		(layer "In3.Cu")
	)
	(gr_line
		(start 395.287246 -8.263128)
		(end 396.074646 -8.263128)
		(stroke
			(width 0.1016)
			(type default)
		)
		(layer "In3.Cu")
	)
	(gr_line
		(start 395.287246 -8.212328)
		(end 395.287246 -5.596128)
		(stroke
			(width 0.1016)
			(type default)
		)
		(layer "In3.Cu")
	)
	(gr_line
		(start 395.287246 -5.696204)
		(end 395.287246 -8.363204)
		(stroke
			(width 0.1016)
			(type default)
		)
		(layer "In3.Cu")
	)
	(gr_line
		(start 395.287246 -5.696204)
		(end 396.481046 -5.696204)
		(stroke
			(width 0.1016)
			(type default)
		)
		(layer "In3.Cu")
	)
	(gr_line
		(start 395.287246 -5.596128)
		(end 395.287246 -8.263128)
		(stroke
			(width 0.1016)
			(type default)
		)
		(layer "In3.Cu")
	)
	(gr_line
		(start 395.287246 -5.596128)
		(end 396.481046 -5.596128)
		(stroke
			(width 0.1016)
			(type default)
		)
		(layer "In3.Cu")
	)
	(gr_line
		(start 395.287246 -4.16306)
		(end 396.074646 -4.16306)
		(stroke
			(width 0.1016)
			(type default)
		)
		(layer "In3.Cu")
	)
	(gr_line
		(start 395.287246 -4.11226)
		(end 395.287246 -1.49606)
		(stroke
			(width 0.1016)
			(type default)
		)
		(layer "In3.Cu")
	)
	(gr_line
		(start 395.287246 -4.062984)
		(end 396.074646 -4.062984)
		(stroke
			(width 0.1016)
			(type default)
		)
		(layer "In3.Cu")
	)
	(gr_line
		(start 395.287246 -4.012184)
		(end 395.287246 -1.395984)
		(stroke
			(width 0.1016)
			(type default)
		)
		(layer "In3.Cu")
	)
	(gr_line
		(start 395.287246 -1.49606)
		(end 395.287246 -4.16306)
		(stroke
			(width 0.1016)
			(type default)
		)
		(layer "In3.Cu")
	)
	(gr_line
		(start 395.287246 -1.49606)
		(end 396.481046 -1.49606)
		(stroke
			(width 0.1016)
			(type default)
		)
		(layer "In3.Cu")
	)
	(gr_line
		(start 395.287246 -1.395984)
		(end 395.287246 -4.062984)
		(stroke
			(width 0.1016)
			(type default)
		)
		(layer "In3.Cu")
	)
	(gr_line
		(start 395.287246 -1.395984)
		(end 396.481046 -1.395984)
		(stroke
			(width 0.1016)
			(type default)
		)
		(layer "In3.Cu")
	)
	(gr_line
		(start 395.312646 -12.512548)
		(end 395.312646 -9.921748)
		(stroke
			(width 0.1016)
			(type default)
		)
		(layer "In3.Cu")
	)
	(gr_line
		(start 395.312646 -12.412472)
		(end 395.312646 -9.821672)
		(stroke
			(width 0.1016)
			(type default)
		)
		(layer "In3.Cu")
	)
	(gr_line
		(start 395.312646 -9.921748)
		(end 396.455646 -9.921748)
		(stroke
			(width 0.1016)
			(type default)
		)
		(layer "In3.Cu")
	)
	(gr_line
		(start 395.312646 -9.821672)
		(end 396.455646 -9.821672)
		(stroke
			(width 0.1016)
			(type default)
		)
		(layer "In3.Cu")
	)
	(gr_line
		(start 395.312646 -8.312404)
		(end 395.312646 -5.721604)
		(stroke
			(width 0.1016)
			(type default)
		)
		(layer "In3.Cu")
	)
	(gr_line
		(start 395.312646 -8.212328)
		(end 395.312646 -5.621528)
		(stroke
			(width 0.1016)
			(type default)
		)
		(layer "In3.Cu")
	)
	(gr_line
		(start 395.312646 -5.721604)
		(end 396.455646 -5.721604)
		(stroke
			(width 0.1016)
			(type default)
		)
		(layer "In3.Cu")
	)
	(gr_line
		(start 395.312646 -5.621528)
		(end 396.455646 -5.621528)
		(stroke
			(width 0.1016)
			(type default)
		)
		(layer "In3.Cu")
	)
	(gr_line
		(start 395.312646 -4.11226)
		(end 395.312646 -1.52146)
		(stroke
			(width 0.1016)
			(type default)
		)
		(layer "In3.Cu")
	)
	(gr_line
		(start 395.312646 -4.012184)
		(end 395.312646 -1.421384)
		(stroke
			(width 0.1016)
			(type default)
		)
		(layer "In3.Cu")
	)
	(gr_line
		(start 395.312646 -1.52146)
		(end 396.455646 -1.52146)
		(stroke
			(width 0.1016)
			(type default)
		)
		(layer "In3.Cu")
	)
	(gr_line
		(start 395.312646 -1.421384)
		(end 396.455646 -1.421384)
		(stroke
			(width 0.1016)
			(type default)
		)
		(layer "In3.Cu")
	)
	(gr_line
		(start 395.338046 -12.512548)
		(end 395.338046 -9.947148)
		(stroke
			(width 0.1016)
			(type default)
		)
		(layer "In3.Cu")
	)
	(gr_line
		(start 395.338046 -12.412472)
		(end 395.338046 -9.847072)
		(stroke
			(width 0.1016)
			(type default)
		)
		(layer "In3.Cu")
	)
	(gr_line
		(start 395.338046 -9.947148)
		(end 395.592046 -9.947148)
		(stroke
			(width 0.1016)
			(type default)
		)
		(layer "In3.Cu")
	)
	(gr_line
		(start 395.338046 -9.847072)
		(end 395.592046 -9.847072)
		(stroke
			(width 0.1016)
			(type default)
		)
		(layer "In3.Cu")
	)
	(gr_line
		(start 395.338046 -8.312404)
		(end 395.338046 -5.747004)
		(stroke
			(width 0.1016)
			(type default)
		)
		(layer "In3.Cu")
	)
	(gr_line
		(start 395.338046 -8.212328)
		(end 395.338046 -5.646928)
		(stroke
			(width 0.1016)
			(type default)
		)
		(layer "In3.Cu")
	)
	(gr_line
		(start 395.338046 -5.747004)
		(end 395.592046 -5.747004)
		(stroke
			(width 0.1016)
			(type default)
		)
		(layer "In3.Cu")
	)
	(gr_line
		(start 395.338046 -5.646928)
		(end 395.592046 -5.646928)
		(stroke
			(width 0.1016)
			(type default)
		)
		(layer "In3.Cu")
	)
	(gr_line
		(start 395.338046 -4.11226)
		(end 395.338046 -1.54686)
		(stroke
			(width 0.1016)
			(type default)
		)
		(layer "In3.Cu")
	)
	(gr_line
		(start 395.338046 -4.012184)
		(end 395.338046 -1.446784)
		(stroke
			(width 0.1016)
			(type default)
		)
		(layer "In3.Cu")
	)
	(gr_line
		(start 395.338046 -1.54686)
		(end 395.592046 -1.54686)
		(stroke
			(width 0.1016)
			(type default)
		)
		(layer "In3.Cu")
	)
	(gr_line
		(start 395.338046 -1.446784)
		(end 395.592046 -1.446784)
		(stroke
			(width 0.1016)
			(type default)
		)
		(layer "In3.Cu")
	)
	(gr_line
		(start 395.363446 -12.512548)
		(end 395.363446 -9.947148)
		(stroke
			(width 0.2032)
			(type default)
		)
		(layer "In3.Cu")
	)
	(gr_line
		(start 395.363446 -12.412472)
		(end 395.363446 -9.847072)
		(stroke
			(width 0.2032)
			(type default)
		)
		(layer "In3.Cu")
	)
	(gr_line
		(start 395.363446 -9.947148)
		(end 396.379446 -9.947148)
		(stroke
			(width 0.2032)
			(type default)
		)
		(layer "In3.Cu")
	)
	(gr_line
		(start 395.363446 -9.847072)
		(end 396.379446 -9.847072)
		(stroke
			(width 0.2032)
			(type default)
		)
		(layer "In3.Cu")
	)
	(gr_line
		(start 395.363446 -8.312404)
		(end 395.363446 -5.747004)
		(stroke
			(width 0.2032)
			(type default)
		)
		(layer "In3.Cu")
	)
	(gr_line
		(start 395.363446 -8.212328)
		(end 395.363446 -5.646928)
		(stroke
			(width 0.2032)
			(type default)
		)
		(layer "In3.Cu")
	)
	(gr_line
		(start 395.363446 -5.747004)
		(end 396.379446 -5.747004)
		(stroke
			(width 0.2032)
			(type default)
		)
		(layer "In3.Cu")
	)
	(gr_line
		(start 395.363446 -5.646928)
		(end 396.379446 -5.646928)
		(stroke
			(width 0.2032)
			(type default)
		)
		(layer "In3.Cu")
	)
	(gr_line
		(start 395.363446 -4.11226)
		(end 395.363446 -1.54686)
		(stroke
			(width 0.2032)
			(type default)
		)
		(layer "In3.Cu")
	)
	(gr_line
		(start 395.363446 -4.012184)
		(end 395.363446 -1.446784)
		(stroke
			(width 0.2032)
			(type default)
		)
		(layer "In3.Cu")
	)
	(gr_line
		(start 395.363446 -1.54686)
		(end 396.379446 -1.54686)
		(stroke
			(width 0.2032)
			(type default)
		)
		(layer "In3.Cu")
	)
	(gr_line
		(start 395.363446 -1.446784)
		(end 396.379446 -1.446784)
		(stroke
			(width 0.2032)
			(type default)
		)
		(layer "In3.Cu")
	)
	(gr_line
		(start 395.414246 -12.487148)
		(end 395.414246 -9.997948)
		(stroke
			(width 0.2032)
			(type default)
		)
		(layer "In3.Cu")
	)
	(gr_line
		(start 395.414246 -12.487148)
		(end 395.414246 -9.997948)
		(stroke
			(width 0.254)
			(type default)
		)
		(layer "In3.Cu")
	)
	(gr_line
		(start 395.414246 -12.387072)
		(end 395.414246 -9.897872)
		(stroke
			(width 0.2032)
			(type default)
		)
		(layer "In3.Cu")
	)
	(gr_line
		(start 395.414246 -12.387072)
		(end 395.414246 -9.897872)
		(stroke
			(width 0.254)
			(type default)
		)
		(layer "In3.Cu")
	)
	(gr_line
		(start 395.414246 -9.997948)
		(end 395.617446 -9.997948)
		(stroke
			(width 0.2032)
			(type default)
		)
		(layer "In3.Cu")
	)
	(gr_line
		(start 395.414246 -9.997948)
		(end 396.303246 -9.997948)
		(stroke
			(width 0.254)
			(type default)
		)
		(layer "In3.Cu")
	)
	(gr_line
		(start 395.414246 -9.897872)
		(end 395.617446 -9.897872)
		(stroke
			(width 0.2032)
			(type default)
		)
		(layer "In3.Cu")
	)
	(gr_line
		(start 395.414246 -9.897872)
		(end 396.303246 -9.897872)
		(stroke
			(width 0.254)
			(type default)
		)
		(layer "In3.Cu")
	)
	(gr_line
		(start 395.414246 -8.287004)
		(end 395.414246 -5.797804)
		(stroke
			(width 0.2032)
			(type default)
		)
		(layer "In3.Cu")
	)
	(gr_line
		(start 395.414246 -8.287004)
		(end 395.414246 -5.797804)
		(stroke
			(width 0.254)
			(type default)
		)
		(layer "In3.Cu")
	)
	(gr_line
		(start 395.414246 -8.186928)
		(end 395.414246 -5.697728)
		(stroke
			(width 0.2032)
			(type default)
		)
		(layer "In3.Cu")
	)
	(gr_line
		(start 395.414246 -8.186928)
		(end 395.414246 -5.697728)
		(stroke
			(width 0.254)
			(type default)
		)
		(layer "In3.Cu")
	)
	(gr_line
		(start 395.414246 -5.797804)
		(end 395.617446 -5.797804)
		(stroke
			(width 0.2032)
			(type default)
		)
		(layer "In3.Cu")
	)
	(gr_line
		(start 395.414246 -5.797804)
		(end 396.303246 -5.797804)
		(stroke
			(width 0.254)
			(type default)
		)
		(layer "In3.Cu")
	)
	(gr_line
		(start 395.414246 -5.697728)
		(end 395.617446 -5.697728)
		(stroke
			(width 0.2032)
			(type default)
		)
		(layer "In3.Cu")
	)
	(gr_line
		(start 395.414246 -5.697728)
		(end 396.303246 -5.697728)
		(stroke
			(width 0.254)
			(type default)
		)
		(layer "In3.Cu")
	)
	(gr_line
		(start 395.414246 -4.08686)
		(end 395.414246 -1.59766)
		(stroke
			(width 0.2032)
			(type default)
		)
		(layer "In3.Cu")
	)
	(gr_line
		(start 395.414246 -4.08686)
		(end 395.414246 -1.59766)
		(stroke
			(width 0.254)
			(type default)
		)
		(layer "In3.Cu")
	)
	(gr_line
		(start 395.414246 -3.986784)
		(end 395.414246 -1.497584)
		(stroke
			(width 0.2032)
			(type default)
		)
		(layer "In3.Cu")
	)
	(gr_line
		(start 395.414246 -3.986784)
		(end 395.414246 -1.497584)
		(stroke
			(width 0.254)
			(type default)
		)
		(layer "In3.Cu")
	)
	(gr_line
		(start 395.414246 -1.59766)
		(end 395.617446 -1.59766)
		(stroke
			(width 0.2032)
			(type default)
		)
		(layer "In3.Cu")
	)
	(gr_line
		(start 395.414246 -1.59766)
		(end 396.303246 -1.59766)
		(stroke
			(width 0.254)
			(type default)
		)
		(layer "In3.Cu")
	)
	(gr_line
		(start 395.414246 -1.497584)
		(end 395.617446 -1.497584)
		(stroke
			(width 0.2032)
			(type default)
		)
		(layer "In3.Cu")
	)
	(gr_line
		(start 395.414246 -1.497584)
		(end 396.303246 -1.497584)
		(stroke
			(width 0.254)
			(type default)
		)
		(layer "In3.Cu")
	)
	(gr_line
		(start 395.439646 -12.461748)
		(end 395.439646 -10.023348)
		(stroke
			(width 0.254)
			(type default)
		)
		(layer "In3.Cu")
	)
	(gr_line
		(start 395.439646 -12.361672)
		(end 395.439646 -9.923272)
		(stroke
			(width 0.254)
			(type default)
		)
		(layer "In3.Cu")
	)
	(gr_line
		(start 395.439646 -10.023348)
		(end 396.277846 -10.023348)
		(stroke
			(width 0.254)
			(type default)
		)
		(layer "In3.Cu")
	)
	(gr_line
		(start 395.439646 -9.923272)
		(end 396.277846 -9.923272)
		(stroke
			(width 0.254)
			(type default)
		)
		(layer "In3.Cu")
	)
	(gr_line
		(start 395.439646 -8.261604)
		(end 395.439646 -5.823204)
		(stroke
			(width 0.254)
			(type default)
		)
		(layer "In3.Cu")
	)
	(gr_line
		(start 395.439646 -8.161528)
		(end 395.439646 -5.723128)
		(stroke
			(width 0.254)
			(type default)
		)
		(layer "In3.Cu")
	)
	(gr_line
		(start 395.439646 -5.823204)
		(end 396.277846 -5.823204)
		(stroke
			(width 0.254)
			(type default)
		)
		(layer "In3.Cu")
	)
	(gr_line
		(start 395.439646 -5.723128)
		(end 396.277846 -5.723128)
		(stroke
			(width 0.254)
			(type default)
		)
		(layer "In3.Cu")
	)
	(gr_line
		(start 395.439646 -4.06146)
		(end 395.439646 -1.62306)
		(stroke
			(width 0.254)
			(type default)
		)
		(layer "In3.Cu")
	)
	(gr_line
		(start 395.439646 -3.961384)
		(end 395.439646 -1.522984)
		(stroke
			(width 0.254)
			(type default)
		)
		(layer "In3.Cu")
	)
	(gr_line
		(start 395.439646 -1.62306)
		(end 396.277846 -1.62306)
		(stroke
			(width 0.254)
			(type default)
		)
		(layer "In3.Cu")
	)
	(gr_line
		(start 395.439646 -1.522984)
		(end 396.277846 -1.522984)
		(stroke
			(width 0.254)
			(type default)
		)
		(layer "In3.Cu")
	)
	(gr_line
		(start 395.465046 -12.436348)
		(end 395.465046 -10.048748)
		(stroke
			(width 0.254)
			(type default)
		)
		(layer "In3.Cu")
	)
	(gr_line
		(start 395.465046 -12.336272)
		(end 395.465046 -9.948672)
		(stroke
			(width 0.254)
			(type default)
		)
		(layer "In3.Cu")
	)
	(gr_line
		(start 395.465046 -10.048748)
		(end 396.252446 -10.048748)
		(stroke
			(width 0.254)
			(type default)
		)
		(layer "In3.Cu")
	)
	(gr_line
		(start 395.465046 -9.948672)
		(end 396.252446 -9.948672)
		(stroke
			(width 0.254)
			(type default)
		)
		(layer "In3.Cu")
	)
	(gr_line
		(start 395.465046 -8.236204)
		(end 395.465046 -5.848604)
		(stroke
			(width 0.254)
			(type default)
		)
		(layer "In3.Cu")
	)
	(gr_line
		(start 395.465046 -8.136128)
		(end 395.465046 -5.748528)
		(stroke
			(width 0.254)
			(type default)
		)
		(layer "In3.Cu")
	)
	(gr_line
		(start 395.465046 -5.848604)
		(end 396.252446 -5.848604)
		(stroke
			(width 0.254)
			(type default)
		)
		(layer "In3.Cu")
	)
	(gr_line
		(start 395.465046 -5.748528)
		(end 396.252446 -5.748528)
		(stroke
			(width 0.254)
			(type default)
		)
		(layer "In3.Cu")
	)
	(gr_line
		(start 395.465046 -4.03606)
		(end 395.465046 -1.64846)
		(stroke
			(width 0.254)
			(type default)
		)
		(layer "In3.Cu")
	)
	(gr_line
		(start 395.465046 -3.935984)
		(end 395.465046 -1.548384)
		(stroke
			(width 0.254)
			(type default)
		)
		(layer "In3.Cu")
	)
	(gr_line
		(start 395.465046 -1.64846)
		(end 396.252446 -1.64846)
		(stroke
			(width 0.254)
			(type default)
		)
		(layer "In3.Cu")
	)
	(gr_line
		(start 395.465046 -1.548384)
		(end 396.252446 -1.548384)
		(stroke
			(width 0.254)
			(type default)
		)
		(layer "In3.Cu")
	)
	(gr_line
		(start 395.490446 -12.360148)
		(end 396.125446 -12.360148)
		(stroke
			(width 0.508)
			(type default)
		)
		(layer "In3.Cu")
	)
	(gr_line
		(start 395.490446 -12.260072)
		(end 396.125446 -12.260072)
		(stroke
			(width 0.508)
			(type default)
		)
		(layer "In3.Cu")
	)
	(gr_line
		(start 395.490446 -10.175748)
		(end 396.125446 -10.175748)
		(stroke
			(width 0.508)
			(type default)
		)
		(layer "In3.Cu")
	)
	(gr_line
		(start 395.490446 -10.124948)
		(end 396.125446 -10.124948)
		(stroke
			(width 0.508)
			(type default)
		)
		(layer "In3.Cu")
	)
	(gr_line
		(start 395.490446 -10.075672)
		(end 396.125446 -10.075672)
		(stroke
			(width 0.508)
			(type default)
		)
		(layer "In3.Cu")
	)
	(gr_line
		(start 395.490446 -10.024872)
		(end 396.125446 -10.024872)
		(stroke
			(width 0.508)
			(type default)
		)
		(layer "In3.Cu")
	)
	(gr_line
		(start 395.490446 -8.160004)
		(end 396.125446 -8.160004)
		(stroke
			(width 0.508)
			(type default)
		)
		(layer "In3.Cu")
	)
	(gr_line
		(start 395.490446 -8.059928)
		(end 396.125446 -8.059928)
		(stroke
			(width 0.508)
			(type default)
		)
		(layer "In3.Cu")
	)
	(gr_line
		(start 395.490446 -5.975604)
		(end 396.125446 -5.975604)
		(stroke
			(width 0.508)
			(type default)
		)
		(layer "In3.Cu")
	)
	(gr_line
		(start 395.490446 -5.924804)
		(end 396.125446 -5.924804)
		(stroke
			(width 0.508)
			(type default)
		)
		(layer "In3.Cu")
	)
	(gr_line
		(start 395.490446 -5.875528)
		(end 396.125446 -5.875528)
		(stroke
			(width 0.508)
			(type default)
		)
		(layer "In3.Cu")
	)
	(gr_line
		(start 395.490446 -5.824728)
		(end 396.125446 -5.824728)
		(stroke
			(width 0.508)
			(type default)
		)
		(layer "In3.Cu")
	)
	(gr_line
		(start 395.490446 -3.95986)
		(end 396.125446 -3.95986)
		(stroke
			(width 0.508)
			(type default)
		)
		(layer "In3.Cu")
	)
	(gr_line
		(start 395.490446 -3.859784)
		(end 396.125446 -3.859784)
		(stroke
			(width 0.508)
			(type default)
		)
		(layer "In3.Cu")
	)
	(gr_line
		(start 395.490446 -1.77546)
		(end 396.125446 -1.77546)
		(stroke
			(width 0.508)
			(type default)
		)
		(layer "In3.Cu")
	)
	(gr_line
		(start 395.490446 -1.72466)
		(end 396.125446 -1.72466)
		(stroke
			(width 0.508)
			(type default)
		)
		(layer "In3.Cu")
	)
	(gr_line
		(start 395.490446 -1.675384)
		(end 396.125446 -1.675384)
		(stroke
			(width 0.508)
			(type default)
		)
		(layer "In3.Cu")
	)
	(gr_line
		(start 395.490446 -1.624584)
		(end 396.125446 -1.624584)
		(stroke
			(width 0.508)
			(type default)
		)
		(layer "In3.Cu")
	)
	(gr_line
		(start 395.515846 -10.429748)
		(end 396.150846 -10.429748)
		(stroke
			(width 0.508)
			(type default)
		)
		(layer "In3.Cu")
	)
	(gr_line
		(start 395.515846 -10.329672)
		(end 396.150846 -10.329672)
		(stroke
			(width 0.508)
			(type default)
		)
		(layer "In3.Cu")
	)
	(gr_line
		(start 395.515846 -6.229604)
		(end 396.150846 -6.229604)
		(stroke
			(width 0.508)
			(type default)
		)
		(layer "In3.Cu")
	)
	(gr_line
		(start 395.515846 -6.129528)
		(end 396.150846 -6.129528)
		(stroke
			(width 0.508)
			(type default)
		)
		(layer "In3.Cu")
	)
	(gr_line
		(start 395.515846 -2.02946)
		(end 396.150846 -2.02946)
		(stroke
			(width 0.508)
			(type default)
		)
		(layer "In3.Cu")
	)
	(gr_line
		(start 395.515846 -1.929384)
		(end 396.150846 -1.929384)
		(stroke
			(width 0.508)
			(type default)
		)
		(layer "In3.Cu")
	)
	(gr_line
		(start 395.541246 -12.385548)
		(end 395.541246 -10.124948)
		(stroke
			(width 0.254)
			(type default)
		)
		(layer "In3.Cu")
	)
	(gr_line
		(start 395.541246 -12.285472)
		(end 395.541246 -10.024872)
		(stroke
			(width 0.254)
			(type default)
		)
		(layer "In3.Cu")
	)
	(gr_line
		(start 395.541246 -12.233148)
		(end 396.176246 -12.233148)
		(stroke
			(width 0.508)
			(type default)
		)
		(layer "In3.Cu")
	)
	(gr_line
		(start 395.541246 -12.133072)
		(end 396.176246 -12.133072)
		(stroke
			(width 0.508)
			(type default)
		)
		(layer "In3.Cu")
	)
	(gr_line
		(start 395.541246 -10.124948)
		(end 396.176246 -10.124948)
		(stroke
			(width 0.254)
			(type default)
		)
		(layer "In3.Cu")
	)
	(gr_line
		(start 395.541246 -10.024872)
		(end 396.176246 -10.024872)
		(stroke
			(width 0.254)
			(type default)
		)
		(layer "In3.Cu")
	)
	(gr_line
		(start 395.541246 -8.185404)
		(end 395.541246 -5.924804)
		(stroke
			(width 0.254)
			(type default)
		)
		(layer "In3.Cu")
	)
	(gr_line
		(start 395.541246 -8.085328)
		(end 395.541246 -5.824728)
		(stroke
			(width 0.254)
			(type default)
		)
		(layer "In3.Cu")
	)
	(gr_line
		(start 395.541246 -8.033004)
		(end 396.176246 -8.033004)
		(stroke
			(width 0.508)
			(type default)
		)
		(layer "In3.Cu")
	)
	(gr_line
		(start 395.541246 -7.932928)
		(end 396.176246 -7.932928)
		(stroke
			(width 0.508)
			(type default)
		)
		(layer "In3.Cu")
	)
	(gr_line
		(start 395.541246 -5.924804)
		(end 396.176246 -5.924804)
		(stroke
			(width 0.254)
			(type default)
		)
		(layer "In3.Cu")
	)
	(gr_line
		(start 395.541246 -5.824728)
		(end 396.176246 -5.824728)
		(stroke
			(width 0.254)
			(type default)
		)
		(layer "In3.Cu")
	)
	(gr_line
		(start 395.541246 -3.98526)
		(end 395.541246 -1.72466)
		(stroke
			(width 0.254)
			(type default)
		)
		(layer "In3.Cu")
	)
	(gr_line
		(start 395.541246 -3.885184)
		(end 395.541246 -1.624584)
		(stroke
			(width 0.254)
			(type default)
		)
		(layer "In3.Cu")
	)
	(gr_line
		(start 395.541246 -3.83286)
		(end 396.176246 -3.83286)
		(stroke
			(width 0.508)
			(type default)
		)
		(layer "In3.Cu")
	)
	(gr_line
		(start 395.541246 -3.732784)
		(end 396.176246 -3.732784)
		(stroke
			(width 0.508)
			(type default)
		)
		(layer "In3.Cu")
	)
	(gr_line
		(start 395.541246 -1.72466)
		(end 396.176246 -1.72466)
		(stroke
			(width 0.254)
			(type default)
		)
		(layer "In3.Cu")
	)
	(gr_line
		(start 395.541246 -1.624584)
		(end 396.176246 -1.624584)
		(stroke
			(width 0.254)
			(type default)
		)
		(layer "In3.Cu")
	)
	(gr_line
		(start 395.566646 -12.080748)
		(end 396.201646 -12.080748)
		(stroke
			(width 0.508)
			(type default)
		)
		(layer "In3.Cu")
	)
	(gr_line
		(start 395.566646 -11.980672)
		(end 396.201646 -11.980672)
		(stroke
			(width 0.508)
			(type default)
		)
		(layer "In3.Cu")
	)
	(gr_line
		(start 395.566646 -7.880604)
		(end 396.201646 -7.880604)
		(stroke
			(width 0.508)
			(type default)
		)
		(layer "In3.Cu")
	)
	(gr_line
		(start 395.566646 -7.780528)
		(end 396.201646 -7.780528)
		(stroke
			(width 0.508)
			(type default)
		)
		(layer "In3.Cu")
	)
	(gr_line
		(start 395.566646 -3.68046)
		(end 396.201646 -3.68046)
		(stroke
			(width 0.508)
			(type default)
		)
		(layer "In3.Cu")
	)
	(gr_line
		(start 395.566646 -3.580384)
		(end 396.201646 -3.580384)
		(stroke
			(width 0.508)
			(type default)
		)
		(layer "In3.Cu")
	)
	(gr_line
		(start 395.592046 -12.360148)
		(end 396.227046 -12.360148)
		(stroke
			(width 0.508)
			(type default)
		)
		(layer "In3.Cu")
	)
	(gr_line
		(start 395.592046 -12.260072)
		(end 396.227046 -12.260072)
		(stroke
			(width 0.508)
			(type default)
		)
		(layer "In3.Cu")
	)
	(gr_line
		(start 395.592046 -9.947148)
		(end 396.430246 -9.947148)
		(stroke
			(width 0.2032)
			(type default)
		)
		(layer "In3.Cu")
	)
	(gr_line
		(start 395.592046 -9.847072)
		(end 396.430246 -9.847072)
		(stroke
			(width 0.2032)
			(type default)
		)
		(layer "In3.Cu")
	)
	(gr_line
		(start 395.592046 -8.160004)
		(end 396.227046 -8.160004)
		(stroke
			(width 0.508)
			(type default)
		)
		(layer "In3.Cu")
	)
	(gr_line
		(start 395.592046 -8.059928)
		(end 396.227046 -8.059928)
		(stroke
			(width 0.508)
			(type default)
		)
		(layer "In3.Cu")
	)
	(gr_line
		(start 395.592046 -5.747004)
		(end 396.430246 -5.747004)
		(stroke
			(width 0.2032)
			(type default)
		)
		(layer "In3.Cu")
	)
	(gr_line
		(start 395.592046 -5.646928)
		(end 396.430246 -5.646928)
		(stroke
			(width 0.2032)
			(type default)
		)
		(layer "In3.Cu")
	)
	(gr_line
		(start 395.592046 -3.95986)
		(end 396.227046 -3.95986)
		(stroke
			(width 0.508)
			(type default)
		)
		(layer "In3.Cu")
	)
	(gr_line
		(start 395.592046 -3.859784)
		(end 396.227046 -3.859784)
		(stroke
			(width 0.508)
			(type default)
		)
		(layer "In3.Cu")
	)
	(gr_line
		(start 395.592046 -1.54686)
		(end 396.430246 -1.54686)
		(stroke
			(width 0.2032)
			(type default)
		)
		(layer "In3.Cu")
	)
	(gr_line
		(start 395.592046 -1.446784)
		(end 396.430246 -1.446784)
		(stroke
			(width 0.2032)
			(type default)
		)
		(layer "In3.Cu")
	)
	(gr_line
		(start 395.617446 -12.360148)
		(end 395.617446 -10.175748)
		(stroke
			(width 0.254)
			(type default)
		)
		(layer "In3.Cu")
	)
	(gr_line
		(start 395.617446 -12.260072)
		(end 395.617446 -10.075672)
		(stroke
			(width 0.254)
			(type default)
		)
		(layer "In3.Cu")
	)
	(gr_line
		(start 395.617446 -10.175748)
		(end 396.100046 -10.175748)
		(stroke
			(width 0.254)
			(type default)
		)
		(layer "In3.Cu")
	)
	(gr_line
		(start 395.617446 -10.075672)
		(end 396.100046 -10.075672)
		(stroke
			(width 0.254)
			(type default)
		)
		(layer "In3.Cu")
	)
	(gr_line
		(start 395.617446 -9.997948)
		(end 396.354046 -9.997948)
		(stroke
			(width 0.254)
			(type default)
		)
		(layer "In3.Cu")
	)
	(gr_line
		(start 395.617446 -9.897872)
		(end 396.354046 -9.897872)
		(stroke
			(width 0.254)
			(type default)
		)
		(layer "In3.Cu")
	)
	(gr_line
		(start 395.617446 -8.160004)
		(end 395.617446 -5.975604)
		(stroke
			(width 0.254)
			(type default)
		)
		(layer "In3.Cu")
	)
	(gr_line
		(start 395.617446 -8.059928)
		(end 395.617446 -5.875528)
		(stroke
			(width 0.254)
			(type default)
		)
		(layer "In3.Cu")
	)
	(gr_line
		(start 395.617446 -5.975604)
		(end 396.100046 -5.975604)
		(stroke
			(width 0.254)
			(type default)
		)
		(layer "In3.Cu")
	)
	(gr_line
		(start 395.617446 -5.875528)
		(end 396.100046 -5.875528)
		(stroke
			(width 0.254)
			(type default)
		)
		(layer "In3.Cu")
	)
	(gr_line
		(start 395.617446 -5.797804)
		(end 396.354046 -5.797804)
		(stroke
			(width 0.254)
			(type default)
		)
		(layer "In3.Cu")
	)
	(gr_line
		(start 395.617446 -5.697728)
		(end 396.354046 -5.697728)
		(stroke
			(width 0.254)
			(type default)
		)
		(layer "In3.Cu")
	)
	(gr_line
		(start 395.617446 -3.95986)
		(end 395.617446 -1.77546)
		(stroke
			(width 0.254)
			(type default)
		)
		(layer "In3.Cu")
	)
	(gr_line
		(start 395.617446 -3.859784)
		(end 395.617446 -1.675384)
		(stroke
			(width 0.254)
			(type default)
		)
		(layer "In3.Cu")
	)
	(gr_line
		(start 395.617446 -1.77546)
		(end 396.100046 -1.77546)
		(stroke
			(width 0.254)
			(type default)
		)
		(layer "In3.Cu")
	)
	(gr_line
		(start 395.617446 -1.675384)
		(end 396.100046 -1.675384)
		(stroke
			(width 0.254)
			(type default)
		)
		(layer "In3.Cu")
	)
	(gr_line
		(start 395.617446 -1.59766)
		(end 396.354046 -1.59766)
		(stroke
			(width 0.254)
			(type default)
		)
		(layer "In3.Cu")
	)
	(gr_line
		(start 395.617446 -1.497584)
		(end 396.354046 -1.497584)
		(stroke
			(width 0.254)
			(type default)
		)
		(layer "In3.Cu")
	)
	(gr_line
		(start 395.635988 -10.110978)
		(end 396.270988 -10.110978)
		(stroke
			(width 0.508)
			(type default)
		)
		(layer "In3.Cu")
	)
	(gr_line
		(start 395.635988 -10.010902)
		(end 396.270988 -10.010902)
		(stroke
			(width 0.508)
			(type default)
		)
		(layer "In3.Cu")
	)
	(gr_line
		(start 395.635988 -5.910834)
		(end 396.270988 -5.910834)
		(stroke
			(width 0.508)
			(type default)
		)
		(layer "In3.Cu")
	)
	(gr_line
		(start 395.635988 -5.810758)
		(end 396.270988 -5.810758)
		(stroke
			(width 0.508)
			(type default)
		)
		(layer "In3.Cu")
	)
	(gr_line
		(start 395.635988 -1.71069)
		(end 396.270988 -1.71069)
		(stroke
			(width 0.508)
			(type default)
		)
		(layer "In3.Cu")
	)
	(gr_line
		(start 395.635988 -1.610614)
		(end 396.270988 -1.610614)
		(stroke
			(width 0.508)
			(type default)
		)
		(layer "In3.Cu")
	)
	(gr_line
		(start 395.642846 -12.360148)
		(end 396.277846 -12.360148)
		(stroke
			(width 0.508)
			(type default)
		)
		(layer "In3.Cu")
	)
	(gr_line
		(start 395.642846 -12.260072)
		(end 396.277846 -12.260072)
		(stroke
			(width 0.508)
			(type default)
		)
		(layer "In3.Cu")
	)
	(gr_line
		(start 395.642846 -12.233148)
		(end 395.642846 -10.251948)
		(stroke
			(width 0.762)
			(type default)
		)
		(layer "In3.Cu")
	)
	(gr_line
		(start 395.642846 -12.133072)
		(end 395.642846 -10.151872)
		(stroke
			(width 0.762)
			(type default)
		)
		(layer "In3.Cu")
	)
	(gr_line
		(start 395.642846 -10.251948)
		(end 396.277846 -10.251948)
		(stroke
			(width 0.508)
			(type default)
		)
		(layer "In3.Cu")
	)
	(gr_line
		(start 395.642846 -10.151872)
		(end 396.277846 -10.151872)
		(stroke
			(width 0.508)
			(type default)
		)
		(layer "In3.Cu")
	)
	(gr_line
		(start 395.642846 -8.160004)
		(end 396.277846 -8.160004)
		(stroke
			(width 0.508)
			(type default)
		)
		(layer "In3.Cu")
	)
	(gr_line
		(start 395.642846 -8.059928)
		(end 396.277846 -8.059928)
		(stroke
			(width 0.508)
			(type default)
		)
		(layer "In3.Cu")
	)
	(gr_line
		(start 395.642846 -8.033004)
		(end 395.642846 -6.051804)
		(stroke
			(width 0.762)
			(type default)
		)
		(layer "In3.Cu")
	)
	(gr_line
		(start 395.642846 -7.932928)
		(end 395.642846 -5.951728)
		(stroke
			(width 0.762)
			(type default)
		)
		(layer "In3.Cu")
	)
	(gr_line
		(start 395.642846 -6.051804)
		(end 396.277846 -6.051804)
		(stroke
			(width 0.508)
			(type default)
		)
		(layer "In3.Cu")
	)
	(gr_line
		(start 395.642846 -5.951728)
		(end 396.277846 -5.951728)
		(stroke
			(width 0.508)
			(type default)
		)
		(layer "In3.Cu")
	)
	(gr_line
		(start 395.642846 -3.95986)
		(end 396.277846 -3.95986)
		(stroke
			(width 0.508)
			(type default)
		)
		(layer "In3.Cu")
	)
	(gr_line
		(start 395.642846 -3.859784)
		(end 396.277846 -3.859784)
		(stroke
			(width 0.508)
			(type default)
		)
		(layer "In3.Cu")
	)
	(gr_line
		(start 395.642846 -3.83286)
		(end 395.642846 -1.85166)
		(stroke
			(width 0.762)
			(type default)
		)
		(layer "In3.Cu")
	)
	(gr_line
		(start 395.642846 -3.732784)
		(end 395.642846 -1.751584)
		(stroke
			(width 0.762)
			(type default)
		)
		(layer "In3.Cu")
	)
	(gr_line
		(start 395.642846 -1.85166)
		(end 396.277846 -1.85166)
		(stroke
			(width 0.508)
			(type default)
		)
		(layer "In3.Cu")
	)
	(gr_line
		(start 395.642846 -1.751584)
		(end 396.277846 -1.751584)
		(stroke
			(width 0.508)
			(type default)
		)
		(layer "In3.Cu")
	)
	(gr_line
		(start 395.693646 -12.283948)
		(end 395.693646 -10.251948)
		(stroke
			(width 0.254)
			(type default)
		)
		(layer "In3.Cu")
	)
	(gr_line
		(start 395.693646 -12.183872)
		(end 395.693646 -10.151872)
		(stroke
			(width 0.254)
			(type default)
		)
		(layer "In3.Cu")
	)
	(gr_line
		(start 395.693646 -10.251948)
		(end 396.023846 -10.251948)
		(stroke
			(width 0.254)
			(type default)
		)
		(layer "In3.Cu")
	)
	(gr_line
		(start 395.693646 -10.151872)
		(end 396.023846 -10.151872)
		(stroke
			(width 0.254)
			(type default)
		)
		(layer "In3.Cu")
	)
	(gr_line
		(start 395.693646 -8.083804)
		(end 395.693646 -6.051804)
		(stroke
			(width 0.254)
			(type default)
		)
		(layer "In3.Cu")
	)
	(gr_line
		(start 395.693646 -7.983728)
		(end 395.693646 -5.951728)
		(stroke
			(width 0.254)
			(type default)
		)
		(layer "In3.Cu")
	)
	(gr_line
		(start 395.693646 -6.051804)
		(end 396.023846 -6.051804)
		(stroke
			(width 0.254)
			(type default)
		)
		(layer "In3.Cu")
	)
	(gr_line
		(start 395.693646 -5.951728)
		(end 396.023846 -5.951728)
		(stroke
			(width 0.254)
			(type default)
		)
		(layer "In3.Cu")
	)
	(gr_line
		(start 395.693646 -3.88366)
		(end 395.693646 -1.85166)
		(stroke
			(width 0.254)
			(type default)
		)
		(layer "In3.Cu")
	)
	(gr_line
		(start 395.693646 -3.783584)
		(end 395.693646 -1.751584)
		(stroke
			(width 0.254)
			(type default)
		)
		(layer "In3.Cu")
	)
	(gr_line
		(start 395.693646 -1.85166)
		(end 396.023846 -1.85166)
		(stroke
			(width 0.254)
			(type default)
		)
		(layer "In3.Cu")
	)
	(gr_line
		(start 395.693646 -1.751584)
		(end 396.023846 -1.751584)
		(stroke
			(width 0.254)
			(type default)
		)
		(layer "In3.Cu")
	)
	(gr_line
		(start 395.795246 -12.207748)
		(end 395.795246 -10.404348)
		(stroke
			(width 0.254)
			(type default)
		)
		(layer "In3.Cu")
	)
	(gr_line
		(start 395.795246 -12.207748)
		(end 395.795246 -10.226548)
		(stroke
			(width 0.762)
			(type default)
		)
		(layer "In3.Cu")
	)
	(gr_line
		(start 395.795246 -12.107672)
		(end 395.795246 -10.304272)
		(stroke
			(width 0.254)
			(type default)
		)
		(layer "In3.Cu")
	)
	(gr_line
		(start 395.795246 -12.107672)
		(end 395.795246 -10.126472)
		(stroke
			(width 0.762)
			(type default)
		)
		(layer "In3.Cu")
	)
	(gr_line
		(start 395.795246 -10.404348)
		(end 395.896846 -10.404348)
		(stroke
			(width 0.254)
			(type default)
		)
		(layer "In3.Cu")
	)
	(gr_line
		(start 395.795246 -10.304272)
		(end 395.896846 -10.304272)
		(stroke
			(width 0.254)
			(type default)
		)
		(layer "In3.Cu")
	)
	(gr_line
		(start 395.795246 -8.007604)
		(end 395.795246 -6.204204)
		(stroke
			(width 0.254)
			(type default)
		)
		(layer "In3.Cu")
	)
	(gr_line
		(start 395.795246 -8.007604)
		(end 395.795246 -6.026404)
		(stroke
			(width 0.762)
			(type default)
		)
		(layer "In3.Cu")
	)
	(gr_line
		(start 395.795246 -7.907528)
		(end 395.795246 -6.104128)
		(stroke
			(width 0.254)
			(type default)
		)
		(layer "In3.Cu")
	)
	(gr_line
		(start 395.795246 -7.907528)
		(end 395.795246 -5.926328)
		(stroke
			(width 0.762)
			(type default)
		)
		(layer "In3.Cu")
	)
	(gr_line
		(start 395.795246 -6.204204)
		(end 395.896846 -6.204204)
		(stroke
			(width 0.254)
			(type default)
		)
		(layer "In3.Cu")
	)
	(gr_line
		(start 395.795246 -6.104128)
		(end 395.896846 -6.104128)
		(stroke
			(width 0.254)
			(type default)
		)
		(layer "In3.Cu")
	)
	(gr_line
		(start 395.795246 -3.80746)
		(end 395.795246 -2.00406)
		(stroke
			(width 0.254)
			(type default)
		)
		(layer "In3.Cu")
	)
	(gr_line
		(start 395.795246 -3.80746)
		(end 395.795246 -1.82626)
		(stroke
			(width 0.762)
			(type default)
		)
		(layer "In3.Cu")
	)
	(gr_line
		(start 395.795246 -3.707384)
		(end 395.795246 -1.903984)
		(stroke
			(width 0.254)
			(type default)
		)
		(layer "In3.Cu")
	)
	(gr_line
		(start 395.795246 -3.707384)
		(end 395.795246 -1.726184)
		(stroke
			(width 0.762)
			(type default)
		)
		(layer "In3.Cu")
	)
	(gr_line
		(start 395.795246 -2.00406)
		(end 395.896846 -2.00406)
		(stroke
			(width 0.254)
			(type default)
		)
		(layer "In3.Cu")
	)
	(gr_line
		(start 395.795246 -1.903984)
		(end 395.896846 -1.903984)
		(stroke
			(width 0.254)
			(type default)
		)
		(layer "In3.Cu")
	)
	(gr_line
		(start 395.896846 -12.309348)
		(end 395.846046 -12.309348)
		(stroke
			(width 0.254)
			(type default)
		)
		(layer "In3.Cu")
	)
	(gr_line
		(start 395.896846 -12.209272)
		(end 395.846046 -12.209272)
		(stroke
			(width 0.254)
			(type default)
		)
		(layer "In3.Cu")
	)
	(gr_line
		(start 395.896846 -10.404348)
		(end 395.896846 -12.309348)
		(stroke
			(width 0.254)
			(type default)
		)
		(layer "In3.Cu")
	)
	(gr_line
		(start 395.896846 -10.304272)
		(end 395.896846 -12.209272)
		(stroke
			(width 0.254)
			(type default)
		)
		(layer "In3.Cu")
	)
	(gr_line
		(start 395.896846 -8.109204)
		(end 395.846046 -8.109204)
		(stroke
			(width 0.254)
			(type default)
		)
		(layer "In3.Cu")
	)
	(gr_line
		(start 395.896846 -8.009128)
		(end 395.846046 -8.009128)
		(stroke
			(width 0.254)
			(type default)
		)
		(layer "In3.Cu")
	)
	(gr_line
		(start 395.896846 -6.204204)
		(end 395.896846 -8.109204)
		(stroke
			(width 0.254)
			(type default)
		)
		(layer "In3.Cu")
	)
	(gr_line
		(start 395.896846 -6.104128)
		(end 395.896846 -8.009128)
		(stroke
			(width 0.254)
			(type default)
		)
		(layer "In3.Cu")
	)
	(gr_line
		(start 395.896846 -3.90906)
		(end 395.846046 -3.90906)
		(stroke
			(width 0.254)
			(type default)
		)
		(layer "In3.Cu")
	)
	(gr_line
		(start 395.896846 -3.808984)
		(end 395.846046 -3.808984)
		(stroke
			(width 0.254)
			(type default)
		)
		(layer "In3.Cu")
	)
	(gr_line
		(start 395.896846 -2.00406)
		(end 395.896846 -3.90906)
		(stroke
			(width 0.254)
			(type default)
		)
		(layer "In3.Cu")
	)
	(gr_line
		(start 395.896846 -1.903984)
		(end 395.896846 -3.808984)
		(stroke
			(width 0.254)
			(type default)
		)
		(layer "In3.Cu")
	)
	(gr_line
		(start 395.947646 -12.233148)
		(end 395.947646 -10.251948)
		(stroke
			(width 0.762)
			(type default)
		)
		(layer "In3.Cu")
	)
	(gr_line
		(start 395.947646 -12.133072)
		(end 395.947646 -10.151872)
		(stroke
			(width 0.762)
			(type default)
		)
		(layer "In3.Cu")
	)
	(gr_line
		(start 395.947646 -8.033004)
		(end 395.947646 -6.051804)
		(stroke
			(width 0.762)
			(type default)
		)
		(layer "In3.Cu")
	)
	(gr_line
		(start 395.947646 -7.932928)
		(end 395.947646 -5.951728)
		(stroke
			(width 0.762)
			(type default)
		)
		(layer "In3.Cu")
	)
	(gr_line
		(start 395.947646 -3.83286)
		(end 395.947646 -1.85166)
		(stroke
			(width 0.762)
			(type default)
		)
		(layer "In3.Cu")
	)
	(gr_line
		(start 395.947646 -3.732784)
		(end 395.947646 -1.751584)
		(stroke
			(width 0.762)
			(type default)
		)
		(layer "In3.Cu")
	)
	(gr_line
		(start 396.023846 -12.207748)
		(end 395.795246 -12.207748)
		(stroke
			(width 0.254)
			(type default)
		)
		(layer "In3.Cu")
	)
	(gr_line
		(start 396.023846 -12.107672)
		(end 395.795246 -12.107672)
		(stroke
			(width 0.254)
			(type default)
		)
		(layer "In3.Cu")
	)
	(gr_line
		(start 396.023846 -10.251948)
		(end 396.023846 -12.207748)
		(stroke
			(width 0.254)
			(type default)
		)
		(layer "In3.Cu")
	)
	(gr_line
		(start 396.023846 -10.151872)
		(end 396.023846 -12.107672)
		(stroke
			(width 0.254)
			(type default)
		)
		(layer "In3.Cu")
	)
	(gr_line
		(start 396.023846 -8.007604)
		(end 395.795246 -8.007604)
		(stroke
			(width 0.254)
			(type default)
		)
		(layer "In3.Cu")
	)
	(gr_line
		(start 396.023846 -7.907528)
		(end 395.795246 -7.907528)
		(stroke
			(width 0.254)
			(type default)
		)
		(layer "In3.Cu")
	)
	(gr_line
		(start 396.023846 -6.051804)
		(end 396.023846 -8.007604)
		(stroke
			(width 0.254)
			(type default)
		)
		(layer "In3.Cu")
	)
	(gr_line
		(start 396.023846 -5.951728)
		(end 396.023846 -7.907528)
		(stroke
			(width 0.254)
			(type default)
		)
		(layer "In3.Cu")
	)
	(gr_line
		(start 396.023846 -3.80746)
		(end 395.795246 -3.80746)
		(stroke
			(width 0.254)
			(type default)
		)
		(layer "In3.Cu")
	)
	(gr_line
		(start 396.023846 -3.707384)
		(end 395.795246 -3.707384)
		(stroke
			(width 0.254)
			(type default)
		)
		(layer "In3.Cu")
	)
	(gr_line
		(start 396.023846 -1.85166)
		(end 396.023846 -3.80746)
		(stroke
			(width 0.254)
			(type default)
		)
		(layer "In3.Cu")
	)
	(gr_line
		(start 396.023846 -1.751584)
		(end 396.023846 -3.707384)
		(stroke
			(width 0.254)
			(type default)
		)
		(layer "In3.Cu")
	)
	(gr_line
		(start 396.074646 -12.563348)
		(end 396.074646 -12.512548)
		(stroke
			(width 0.1016)
			(type default)
		)
		(layer "In3.Cu")
	)
	(gr_line
		(start 396.074646 -12.563348)
		(end 396.481046 -12.563348)
		(stroke
			(width 0.1016)
			(type default)
		)
		(layer "In3.Cu")
	)
	(gr_line
		(start 396.074646 -12.512548)
		(end 395.312646 -12.512548)
		(stroke
			(width 0.1016)
			(type default)
		)
		(layer "In3.Cu")
	)
	(gr_line
		(start 396.074646 -12.463272)
		(end 396.074646 -12.412472)
		(stroke
			(width 0.1016)
			(type default)
		)
		(layer "In3.Cu")
	)
	(gr_line
		(start 396.074646 -12.463272)
		(end 396.481046 -12.463272)
		(stroke
			(width 0.1016)
			(type default)
		)
		(layer "In3.Cu")
	)
	(gr_line
		(start 396.074646 -12.412472)
		(end 395.312646 -12.412472)
		(stroke
			(width 0.1016)
			(type default)
		)
		(layer "In3.Cu")
	)
	(gr_line
		(start 396.074646 -12.233148)
		(end 396.074646 -10.251948)
		(stroke
			(width 0.762)
			(type default)
		)
		(layer "In3.Cu")
	)
	(gr_line
		(start 396.074646 -12.133072)
		(end 396.074646 -10.151872)
		(stroke
			(width 0.762)
			(type default)
		)
		(layer "In3.Cu")
	)
	(gr_line
		(start 396.074646 -8.363204)
		(end 396.074646 -8.312404)
		(stroke
			(width 0.1016)
			(type default)
		)
		(layer "In3.Cu")
	)
	(gr_line
		(start 396.074646 -8.363204)
		(end 396.481046 -8.363204)
		(stroke
			(width 0.1016)
			(type default)
		)
		(layer "In3.Cu")
	)
	(gr_line
		(start 396.074646 -8.312404)
		(end 395.312646 -8.312404)
		(stroke
			(width 0.1016)
			(type default)
		)
		(layer "In3.Cu")
	)
	(gr_line
		(start 396.074646 -8.263128)
		(end 396.074646 -8.212328)
		(stroke
			(width 0.1016)
			(type default)
		)
		(layer "In3.Cu")
	)
	(gr_line
		(start 396.074646 -8.263128)
		(end 396.481046 -8.263128)
		(stroke
			(width 0.1016)
			(type default)
		)
		(layer "In3.Cu")
	)
	(gr_line
		(start 396.074646 -8.212328)
		(end 395.312646 -8.212328)
		(stroke
			(width 0.1016)
			(type default)
		)
		(layer "In3.Cu")
	)
	(gr_line
		(start 396.074646 -8.033004)
		(end 396.074646 -6.051804)
		(stroke
			(width 0.762)
			(type default)
		)
		(layer "In3.Cu")
	)
	(gr_line
		(start 396.074646 -7.932928)
		(end 396.074646 -5.951728)
		(stroke
			(width 0.762)
			(type default)
		)
		(layer "In3.Cu")
	)
	(gr_line
		(start 396.074646 -4.16306)
		(end 396.074646 -4.11226)
		(stroke
			(width 0.1016)
			(type default)
		)
		(layer "In3.Cu")
	)
	(gr_line
		(start 396.074646 -4.16306)
		(end 396.481046 -4.16306)
		(stroke
			(width 0.1016)
			(type default)
		)
		(layer "In3.Cu")
	)
	(gr_line
		(start 396.074646 -4.11226)
		(end 395.312646 -4.11226)
		(stroke
			(width 0.1016)
			(type default)
		)
		(layer "In3.Cu")
	)
	(gr_line
		(start 396.074646 -4.062984)
		(end 396.074646 -4.012184)
		(stroke
			(width 0.1016)
			(type default)
		)
		(layer "In3.Cu")
	)
	(gr_line
		(start 396.074646 -4.062984)
		(end 396.481046 -4.062984)
		(stroke
			(width 0.1016)
			(type default)
		)
		(layer "In3.Cu")
	)
	(gr_line
		(start 396.074646 -4.012184)
		(end 395.312646 -4.012184)
		(stroke
			(width 0.1016)
			(type default)
		)
		(layer "In3.Cu")
	)
	(gr_line
		(start 396.074646 -3.83286)
		(end 396.074646 -1.85166)
		(stroke
			(width 0.762)
			(type default)
		)
		(layer "In3.Cu")
	)
	(gr_line
		(start 396.074646 -3.732784)
		(end 396.074646 -1.751584)
		(stroke
			(width 0.762)
			(type default)
		)
		(layer "In3.Cu")
	)
	(gr_line
		(start 396.100046 -12.283948)
		(end 395.693646 -12.283948)
		(stroke
			(width 0.254)
			(type default)
		)
		(layer "In3.Cu")
	)
	(gr_line
		(start 396.100046 -12.183872)
		(end 395.693646 -12.183872)
		(stroke
			(width 0.254)
			(type default)
		)
		(layer "In3.Cu")
	)
	(gr_line
		(start 396.100046 -10.175748)
		(end 396.100046 -12.283948)
		(stroke
			(width 0.254)
			(type default)
		)
		(layer "In3.Cu")
	)
	(gr_line
		(start 396.100046 -10.075672)
		(end 396.100046 -12.183872)
		(stroke
			(width 0.254)
			(type default)
		)
		(layer "In3.Cu")
	)
	(gr_line
		(start 396.100046 -8.083804)
		(end 395.693646 -8.083804)
		(stroke
			(width 0.254)
			(type default)
		)
		(layer "In3.Cu")
	)
	(gr_line
		(start 396.100046 -7.983728)
		(end 395.693646 -7.983728)
		(stroke
			(width 0.254)
			(type default)
		)
		(layer "In3.Cu")
	)
	(gr_line
		(start 396.100046 -5.975604)
		(end 396.100046 -8.083804)
		(stroke
			(width 0.254)
			(type default)
		)
		(layer "In3.Cu")
	)
	(gr_line
		(start 396.100046 -5.875528)
		(end 396.100046 -7.983728)
		(stroke
			(width 0.254)
			(type default)
		)
		(layer "In3.Cu")
	)
	(gr_line
		(start 396.100046 -3.88366)
		(end 395.693646 -3.88366)
		(stroke
			(width 0.254)
			(type default)
		)
		(layer "In3.Cu")
	)
	(gr_line
		(start 396.100046 -3.783584)
		(end 395.693646 -3.783584)
		(stroke
			(width 0.254)
			(type default)
		)
		(layer "In3.Cu")
	)
	(gr_line
		(start 396.100046 -1.77546)
		(end 396.100046 -3.88366)
		(stroke
			(width 0.254)
			(type default)
		)
		(layer "In3.Cu")
	)
	(gr_line
		(start 396.100046 -1.675384)
		(end 396.100046 -3.783584)
		(stroke
			(width 0.254)
			(type default)
		)
		(layer "In3.Cu")
	)
	(gr_line
		(start 396.150846 -12.233148)
		(end 396.150846 -10.251948)
		(stroke
			(width 0.762)
			(type default)
		)
		(layer "In3.Cu")
	)
	(gr_line
		(start 396.150846 -12.133072)
		(end 396.150846 -10.151872)
		(stroke
			(width 0.762)
			(type default)
		)
		(layer "In3.Cu")
	)
	(gr_line
		(start 396.150846 -8.033004)
		(end 396.150846 -6.051804)
		(stroke
			(width 0.762)
			(type default)
		)
		(layer "In3.Cu")
	)
	(gr_line
		(start 396.150846 -7.932928)
		(end 396.150846 -5.951728)
		(stroke
			(width 0.762)
			(type default)
		)
		(layer "In3.Cu")
	)
	(gr_line
		(start 396.150846 -3.83286)
		(end 396.150846 -1.85166)
		(stroke
			(width 0.762)
			(type default)
		)
		(layer "In3.Cu")
	)
	(gr_line
		(start 396.150846 -3.732784)
		(end 396.150846 -1.751584)
		(stroke
			(width 0.762)
			(type default)
		)
		(layer "In3.Cu")
	)
	(gr_line
		(start 396.176246 -12.360148)
		(end 395.617446 -12.360148)
		(stroke
			(width 0.254)
			(type default)
		)
		(layer "In3.Cu")
	)
	(gr_line
		(start 396.176246 -12.260072)
		(end 395.617446 -12.260072)
		(stroke
			(width 0.254)
			(type default)
		)
		(layer "In3.Cu")
	)
	(gr_line
		(start 396.176246 -10.124948)
		(end 396.176246 -12.360148)
		(stroke
			(width 0.254)
			(type default)
		)
		(layer "In3.Cu")
	)
	(gr_line
		(start 396.176246 -10.024872)
		(end 396.176246 -12.260072)
		(stroke
			(width 0.254)
			(type default)
		)
		(layer "In3.Cu")
	)
	(gr_line
		(start 396.176246 -8.160004)
		(end 395.617446 -8.160004)
		(stroke
			(width 0.254)
			(type default)
		)
		(layer "In3.Cu")
	)
	(gr_line
		(start 396.176246 -8.059928)
		(end 395.617446 -8.059928)
		(stroke
			(width 0.254)
			(type default)
		)
		(layer "In3.Cu")
	)
	(gr_line
		(start 396.176246 -5.924804)
		(end 396.176246 -8.160004)
		(stroke
			(width 0.254)
			(type default)
		)
		(layer "In3.Cu")
	)
	(gr_line
		(start 396.176246 -5.824728)
		(end 396.176246 -8.059928)
		(stroke
			(width 0.254)
			(type default)
		)
		(layer "In3.Cu")
	)
	(gr_line
		(start 396.176246 -3.95986)
		(end 395.617446 -3.95986)
		(stroke
			(width 0.254)
			(type default)
		)
		(layer "In3.Cu")
	)
	(gr_line
		(start 396.176246 -3.859784)
		(end 395.617446 -3.859784)
		(stroke
			(width 0.254)
			(type default)
		)
		(layer "In3.Cu")
	)
	(gr_line
		(start 396.176246 -1.72466)
		(end 396.176246 -3.95986)
		(stroke
			(width 0.254)
			(type default)
		)
		(layer "In3.Cu")
	)
	(gr_line
		(start 396.176246 -1.624584)
		(end 396.176246 -3.859784)
		(stroke
			(width 0.254)
			(type default)
		)
		(layer "In3.Cu")
	)
	(gr_line
		(start 396.252446 -12.385548)
		(end 395.541246 -12.385548)
		(stroke
			(width 0.254)
			(type default)
		)
		(layer "In3.Cu")
	)
	(gr_line
		(start 396.252446 -12.285472)
		(end 395.541246 -12.285472)
		(stroke
			(width 0.254)
			(type default)
		)
		(layer "In3.Cu")
	)
	(gr_line
		(start 396.252446 -10.048748)
		(end 396.252446 -12.385548)
		(stroke
			(width 0.254)
			(type default)
		)
		(layer "In3.Cu")
	)
	(gr_line
		(start 396.252446 -9.948672)
		(end 396.252446 -12.285472)
		(stroke
			(width 0.254)
			(type default)
		)
		(layer "In3.Cu")
	)
	(gr_line
		(start 396.252446 -8.185404)
		(end 395.541246 -8.185404)
		(stroke
			(width 0.254)
			(type default)
		)
		(layer "In3.Cu")
	)
	(gr_line
		(start 396.252446 -8.085328)
		(end 395.541246 -8.085328)
		(stroke
			(width 0.254)
			(type default)
		)
		(layer "In3.Cu")
	)
	(gr_line
		(start 396.252446 -5.848604)
		(end 396.252446 -8.185404)
		(stroke
			(width 0.254)
			(type default)
		)
		(layer "In3.Cu")
	)
	(gr_line
		(start 396.252446 -5.748528)
		(end 396.252446 -8.085328)
		(stroke
			(width 0.254)
			(type default)
		)
		(layer "In3.Cu")
	)
	(gr_line
		(start 396.252446 -3.98526)
		(end 395.541246 -3.98526)
		(stroke
			(width 0.254)
			(type default)
		)
		(layer "In3.Cu")
	)
	(gr_line
		(start 396.252446 -3.885184)
		(end 395.541246 -3.885184)
		(stroke
			(width 0.254)
			(type default)
		)
		(layer "In3.Cu")
	)
	(gr_line
		(start 396.252446 -1.64846)
		(end 396.252446 -3.98526)
		(stroke
			(width 0.254)
			(type default)
		)
		(layer "In3.Cu")
	)
	(gr_line
		(start 396.252446 -1.548384)
		(end 396.252446 -3.885184)
		(stroke
			(width 0.254)
			(type default)
		)
		(layer "In3.Cu")
	)
	(gr_line
		(start 396.277846 -12.512548)
		(end 395.287246 -12.512548)
		(stroke
			(width 0.1016)
			(type default)
		)
		(layer "In3.Cu")
	)
	(gr_line
		(start 396.277846 -12.436348)
		(end 395.465046 -12.436348)
		(stroke
			(width 0.254)
			(type default)
		)
		(layer "In3.Cu")
	)
	(gr_line
		(start 396.277846 -12.412472)
		(end 395.287246 -12.412472)
		(stroke
			(width 0.1016)
			(type default)
		)
		(layer "In3.Cu")
	)
	(gr_line
		(start 396.277846 -12.336272)
		(end 395.465046 -12.336272)
		(stroke
			(width 0.254)
			(type default)
		)
		(layer "In3.Cu")
	)
	(gr_line
		(start 396.277846 -10.023348)
		(end 396.277846 -12.436348)
		(stroke
			(width 0.254)
			(type default)
		)
		(layer "In3.Cu")
	)
	(gr_line
		(start 396.277846 -9.923272)
		(end 396.277846 -12.336272)
		(stroke
			(width 0.254)
			(type default)
		)
		(layer "In3.Cu")
	)
	(gr_line
		(start 396.277846 -8.312404)
		(end 395.287246 -8.312404)
		(stroke
			(width 0.1016)
			(type default)
		)
		(layer "In3.Cu")
	)
	(gr_line
		(start 396.277846 -8.236204)
		(end 395.465046 -8.236204)
		(stroke
			(width 0.254)
			(type default)
		)
		(layer "In3.Cu")
	)
	(gr_line
		(start 396.277846 -8.212328)
		(end 395.287246 -8.212328)
		(stroke
			(width 0.1016)
			(type default)
		)
		(layer "In3.Cu")
	)
	(gr_line
		(start 396.277846 -8.136128)
		(end 395.465046 -8.136128)
		(stroke
			(width 0.254)
			(type default)
		)
		(layer "In3.Cu")
	)
	(gr_line
		(start 396.277846 -5.823204)
		(end 396.277846 -8.236204)
		(stroke
			(width 0.254)
			(type default)
		)
		(layer "In3.Cu")
	)
	(gr_line
		(start 396.277846 -5.723128)
		(end 396.277846 -8.136128)
		(stroke
			(width 0.254)
			(type default)
		)
		(layer "In3.Cu")
	)
	(gr_line
		(start 396.277846 -4.11226)
		(end 395.287246 -4.11226)
		(stroke
			(width 0.1016)
			(type default)
		)
		(layer "In3.Cu")
	)
	(gr_line
		(start 396.277846 -4.03606)
		(end 395.465046 -4.03606)
		(stroke
			(width 0.254)
			(type default)
		)
		(layer "In3.Cu")
	)
	(gr_line
		(start 396.277846 -4.012184)
		(end 395.287246 -4.012184)
		(stroke
			(width 0.1016)
			(type default)
		)
		(layer "In3.Cu")
	)
	(gr_line
		(start 396.277846 -3.935984)
		(end 395.465046 -3.935984)
		(stroke
			(width 0.254)
			(type default)
		)
		(layer "In3.Cu")
	)
	(gr_line
		(start 396.277846 -1.62306)
		(end 396.277846 -4.03606)
		(stroke
			(width 0.254)
			(type default)
		)
		(layer "In3.Cu")
	)
	(gr_line
		(start 396.277846 -1.522984)
		(end 396.277846 -3.935984)
		(stroke
			(width 0.254)
			(type default)
		)
		(layer "In3.Cu")
	)
	(gr_line
		(start 396.303246 -12.461748)
		(end 395.439646 -12.461748)
		(stroke
			(width 0.254)
			(type default)
		)
		(layer "In3.Cu")
	)
	(gr_line
		(start 396.303246 -12.361672)
		(end 395.439646 -12.361672)
		(stroke
			(width 0.254)
			(type default)
		)
		(layer "In3.Cu")
	)
	(gr_line
		(start 396.303246 -9.997948)
		(end 396.303246 -12.461748)
		(stroke
			(width 0.254)
			(type default)
		)
		(layer "In3.Cu")
	)
	(gr_line
		(start 396.303246 -9.897872)
		(end 396.303246 -12.361672)
		(stroke
			(width 0.254)
			(type default)
		)
		(layer "In3.Cu")
	)
	(gr_line
		(start 396.303246 -8.261604)
		(end 395.439646 -8.261604)
		(stroke
			(width 0.254)
			(type default)
		)
		(layer "In3.Cu")
	)
	(gr_line
		(start 396.303246 -8.161528)
		(end 395.439646 -8.161528)
		(stroke
			(width 0.254)
			(type default)
		)
		(layer "In3.Cu")
	)
	(gr_line
		(start 396.303246 -5.797804)
		(end 396.303246 -8.261604)
		(stroke
			(width 0.254)
			(type default)
		)
		(layer "In3.Cu")
	)
	(gr_line
		(start 396.303246 -5.697728)
		(end 396.303246 -8.161528)
		(stroke
			(width 0.254)
			(type default)
		)
		(layer "In3.Cu")
	)
	(gr_line
		(start 396.303246 -4.06146)
		(end 395.439646 -4.06146)
		(stroke
			(width 0.254)
			(type default)
		)
		(layer "In3.Cu")
	)
	(gr_line
		(start 396.303246 -3.961384)
		(end 395.439646 -3.961384)
		(stroke
			(width 0.254)
			(type default)
		)
		(layer "In3.Cu")
	)
	(gr_line
		(start 396.303246 -1.59766)
		(end 396.303246 -4.06146)
		(stroke
			(width 0.254)
			(type default)
		)
		(layer "In3.Cu")
	)
	(gr_line
		(start 396.303246 -1.497584)
		(end 396.303246 -3.961384)
		(stroke
			(width 0.254)
			(type default)
		)
		(layer "In3.Cu")
	)
	(gr_line
		(start 396.354046 -12.487148)
		(end 395.414246 -12.487148)
		(stroke
			(width 0.254)
			(type default)
		)
		(layer "In3.Cu")
	)
	(gr_line
		(start 396.354046 -12.387072)
		(end 395.414246 -12.387072)
		(stroke
			(width 0.254)
			(type default)
		)
		(layer "In3.Cu")
	)
	(gr_line
		(start 396.354046 -9.997948)
		(end 396.354046 -12.487148)
		(stroke
			(width 0.254)
			(type default)
		)
		(layer "In3.Cu")
	)
	(gr_line
		(start 396.354046 -9.897872)
		(end 396.354046 -12.387072)
		(stroke
			(width 0.254)
			(type default)
		)
		(layer "In3.Cu")
	)
	(gr_line
		(start 396.354046 -8.287004)
		(end 395.414246 -8.287004)
		(stroke
			(width 0.254)
			(type default)
		)
		(layer "In3.Cu")
	)
	(gr_line
		(start 396.354046 -8.186928)
		(end 395.414246 -8.186928)
		(stroke
			(width 0.254)
			(type default)
		)
		(layer "In3.Cu")
	)
	(gr_line
		(start 396.354046 -5.797804)
		(end 396.354046 -8.287004)
		(stroke
			(width 0.254)
			(type default)
		)
		(layer "In3.Cu")
	)
	(gr_line
		(start 396.354046 -5.697728)
		(end 396.354046 -8.186928)
		(stroke
			(width 0.254)
			(type default)
		)
		(layer "In3.Cu")
	)
	(gr_line
		(start 396.354046 -4.08686)
		(end 395.414246 -4.08686)
		(stroke
			(width 0.254)
			(type default)
		)
		(layer "In3.Cu")
	)
	(gr_line
		(start 396.354046 -3.986784)
		(end 395.414246 -3.986784)
		(stroke
			(width 0.254)
			(type default)
		)
		(layer "In3.Cu")
	)
	(gr_line
		(start 396.354046 -1.59766)
		(end 396.354046 -4.08686)
		(stroke
			(width 0.254)
			(type default)
		)
		(layer "In3.Cu")
	)
	(gr_line
		(start 396.354046 -1.497584)
		(end 396.354046 -3.986784)
		(stroke
			(width 0.254)
			(type default)
		)
		(layer "In3.Cu")
	)
	(gr_line
		(start 396.379446 -12.487148)
		(end 395.414246 -12.487148)
		(stroke
			(width 0.2032)
			(type default)
		)
		(layer "In3.Cu")
	)
	(gr_line
		(start 396.379446 -12.387072)
		(end 395.414246 -12.387072)
		(stroke
			(width 0.2032)
			(type default)
		)
		(layer "In3.Cu")
	)
	(gr_line
		(start 396.379446 -9.947148)
		(end 396.379446 -12.487148)
		(stroke
			(width 0.2032)
			(type default)
		)
		(layer "In3.Cu")
	)
	(gr_line
		(start 396.379446 -9.847072)
		(end 396.379446 -12.387072)
		(stroke
			(width 0.2032)
			(type default)
		)
		(layer "In3.Cu")
	)
	(gr_line
		(start 396.379446 -8.287004)
		(end 395.414246 -8.287004)
		(stroke
			(width 0.2032)
			(type default)
		)
		(layer "In3.Cu")
	)
	(gr_line
		(start 396.379446 -8.186928)
		(end 395.414246 -8.186928)
		(stroke
			(width 0.2032)
			(type default)
		)
		(layer "In3.Cu")
	)
	(gr_line
		(start 396.379446 -5.747004)
		(end 396.379446 -8.287004)
		(stroke
			(width 0.2032)
			(type default)
		)
		(layer "In3.Cu")
	)
	(gr_line
		(start 396.379446 -5.646928)
		(end 396.379446 -8.186928)
		(stroke
			(width 0.2032)
			(type default)
		)
		(layer "In3.Cu")
	)
	(gr_line
		(start 396.379446 -4.08686)
		(end 395.414246 -4.08686)
		(stroke
			(width 0.2032)
			(type default)
		)
		(layer "In3.Cu")
	)
	(gr_line
		(start 396.379446 -3.986784)
		(end 395.414246 -3.986784)
		(stroke
			(width 0.2032)
			(type default)
		)
		(layer "In3.Cu")
	)
	(gr_line
		(start 396.379446 -1.54686)
		(end 396.379446 -4.08686)
		(stroke
			(width 0.2032)
			(type default)
		)
		(layer "In3.Cu")
	)
	(gr_line
		(start 396.379446 -1.446784)
		(end 396.379446 -3.986784)
		(stroke
			(width 0.2032)
			(type default)
		)
		(layer "In3.Cu")
	)
	(gr_line
		(start 396.430246 -12.512548)
		(end 395.363446 -12.512548)
		(stroke
			(width 0.2032)
			(type default)
		)
		(layer "In3.Cu")
	)
	(gr_line
		(start 396.430246 -12.412472)
		(end 395.363446 -12.412472)
		(stroke
			(width 0.2032)
			(type default)
		)
		(layer "In3.Cu")
	)
	(gr_line
		(start 396.430246 -9.947148)
		(end 396.430246 -12.512548)
		(stroke
			(width 0.2032)
			(type default)
		)
		(layer "In3.Cu")
	)
	(gr_line
		(start 396.430246 -9.847072)
		(end 396.430246 -12.412472)
		(stroke
			(width 0.2032)
			(type default)
		)
		(layer "In3.Cu")
	)
	(gr_line
		(start 396.430246 -8.312404)
		(end 395.363446 -8.312404)
		(stroke
			(width 0.2032)
			(type default)
		)
		(layer "In3.Cu")
	)
	(gr_line
		(start 396.430246 -8.212328)
		(end 395.363446 -8.212328)
		(stroke
			(width 0.2032)
			(type default)
		)
		(layer "In3.Cu")
	)
	(gr_line
		(start 396.430246 -5.747004)
		(end 396.430246 -8.312404)
		(stroke
			(width 0.2032)
			(type default)
		)
		(layer "In3.Cu")
	)
	(gr_line
		(start 396.430246 -5.646928)
		(end 396.430246 -8.212328)
		(stroke
			(width 0.2032)
			(type default)
		)
		(layer "In3.Cu")
	)
	(gr_line
		(start 396.430246 -4.11226)
		(end 395.363446 -4.11226)
		(stroke
			(width 0.2032)
			(type default)
		)
		(layer "In3.Cu")
	)
	(gr_line
		(start 396.430246 -4.012184)
		(end 395.363446 -4.012184)
		(stroke
			(width 0.2032)
			(type default)
		)
		(layer "In3.Cu")
	)
	(gr_line
		(start 396.430246 -1.54686)
		(end 396.430246 -4.11226)
		(stroke
			(width 0.2032)
			(type default)
		)
		(layer "In3.Cu")
	)
	(gr_line
		(start 396.430246 -1.446784)
		(end 396.430246 -4.012184)
		(stroke
			(width 0.2032)
			(type default)
		)
		(layer "In3.Cu")
	)
	(gr_line
		(start 396.455646 -12.512548)
		(end 395.338046 -12.512548)
		(stroke
			(width 0.1016)
			(type default)
		)
		(layer "In3.Cu")
	)
	(gr_line
		(start 396.455646 -12.412472)
		(end 395.338046 -12.412472)
		(stroke
			(width 0.1016)
			(type default)
		)
		(layer "In3.Cu")
	)
	(gr_line
		(start 396.455646 -9.921748)
		(end 396.455646 -12.512548)
		(stroke
			(width 0.1016)
			(type default)
		)
		(layer "In3.Cu")
	)
	(gr_line
		(start 396.455646 -9.821672)
		(end 396.455646 -12.412472)
		(stroke
			(width 0.1016)
			(type default)
		)
		(layer "In3.Cu")
	)
	(gr_line
		(start 396.455646 -8.312404)
		(end 395.338046 -8.312404)
		(stroke
			(width 0.1016)
			(type default)
		)
		(layer "In3.Cu")
	)
	(gr_line
		(start 396.455646 -8.212328)
		(end 395.338046 -8.212328)
		(stroke
			(width 0.1016)
			(type default)
		)
		(layer "In3.Cu")
	)
	(gr_line
		(start 396.455646 -5.721604)
		(end 396.455646 -8.312404)
		(stroke
			(width 0.1016)
			(type default)
		)
		(layer "In3.Cu")
	)
	(gr_line
		(start 396.455646 -5.621528)
		(end 396.455646 -8.212328)
		(stroke
			(width 0.1016)
			(type default)
		)
		(layer "In3.Cu")
	)
	(gr_line
		(start 396.455646 -4.11226)
		(end 395.338046 -4.11226)
		(stroke
			(width 0.1016)
			(type default)
		)
		(layer "In3.Cu")
	)
	(gr_line
		(start 396.455646 -4.012184)
		(end 395.338046 -4.012184)
		(stroke
			(width 0.1016)
			(type default)
		)
		(layer "In3.Cu")
	)
	(gr_line
		(start 396.455646 -1.52146)
		(end 396.455646 -4.11226)
		(stroke
			(width 0.1016)
			(type default)
		)
		(layer "In3.Cu")
	)
	(gr_line
		(start 396.455646 -1.421384)
		(end 396.455646 -4.012184)
		(stroke
			(width 0.1016)
			(type default)
		)
		(layer "In3.Cu")
	)
	(gr_line
		(start 396.481046 -12.563348)
		(end 396.074646 -12.563348)
		(stroke
			(width 0.1016)
			(type default)
		)
		(layer "In3.Cu")
	)
	(gr_line
		(start 396.481046 -12.563348)
		(end 396.481046 -9.896348)
		(stroke
			(width 0.1016)
			(type default)
		)
		(layer "In3.Cu")
	)
	(gr_line
		(start 396.481046 -12.463272)
		(end 396.074646 -12.463272)
		(stroke
			(width 0.1016)
			(type default)
		)
		(layer "In3.Cu")
	)
	(gr_line
		(start 396.481046 -12.463272)
		(end 396.481046 -9.796272)
		(stroke
			(width 0.1016)
			(type default)
		)
		(layer "In3.Cu")
	)
	(gr_line
		(start 396.481046 -9.896348)
		(end 395.287246 -9.896348)
		(stroke
			(width 0.1016)
			(type default)
		)
		(layer "In3.Cu")
	)
	(gr_line
		(start 396.481046 -9.896348)
		(end 396.481046 -12.563348)
		(stroke
			(width 0.1016)
			(type default)
		)
		(layer "In3.Cu")
	)
	(gr_line
		(start 396.481046 -9.796272)
		(end 395.287246 -9.796272)
		(stroke
			(width 0.1016)
			(type default)
		)
		(layer "In3.Cu")
	)
	(gr_line
		(start 396.481046 -9.796272)
		(end 396.481046 -12.463272)
		(stroke
			(width 0.1016)
			(type default)
		)
		(layer "In3.Cu")
	)
	(gr_line
		(start 396.481046 -8.363204)
		(end 396.074646 -8.363204)
		(stroke
			(width 0.1016)
			(type default)
		)
		(layer "In3.Cu")
	)
	(gr_line
		(start 396.481046 -8.363204)
		(end 396.481046 -5.696204)
		(stroke
			(width 0.1016)
			(type default)
		)
		(layer "In3.Cu")
	)
	(gr_line
		(start 396.481046 -8.263128)
		(end 396.074646 -8.263128)
		(stroke
			(width 0.1016)
			(type default)
		)
		(layer "In3.Cu")
	)
	(gr_line
		(start 396.481046 -8.263128)
		(end 396.481046 -5.596128)
		(stroke
			(width 0.1016)
			(type default)
		)
		(layer "In3.Cu")
	)
	(gr_line
		(start 396.481046 -5.696204)
		(end 395.287246 -5.696204)
		(stroke
			(width 0.1016)
			(type default)
		)
		(layer "In3.Cu")
	)
	(gr_line
		(start 396.481046 -5.696204)
		(end 396.481046 -8.363204)
		(stroke
			(width 0.1016)
			(type default)
		)
		(layer "In3.Cu")
	)
	(gr_line
		(start 396.481046 -5.596128)
		(end 395.287246 -5.596128)
		(stroke
			(width 0.1016)
			(type default)
		)
		(layer "In3.Cu")
	)
	(gr_line
		(start 396.481046 -5.596128)
		(end 396.481046 -8.263128)
		(stroke
			(width 0.1016)
			(type default)
		)
		(layer "In3.Cu")
	)
	(gr_line
		(start 396.481046 -4.16306)
		(end 396.074646 -4.16306)
		(stroke
			(width 0.1016)
			(type default)
		)
		(layer "In3.Cu")
	)
	(gr_line
		(start 396.481046 -4.16306)
		(end 396.481046 -1.49606)
		(stroke
			(width 0.1016)
			(type default)
		)
		(layer "In3.Cu")
	)
	(gr_line
		(start 396.481046 -4.062984)
		(end 396.074646 -4.062984)
		(stroke
			(width 0.1016)
			(type default)
		)
		(layer "In3.Cu")
	)
	(gr_line
		(start 396.481046 -4.062984)
		(end 396.481046 -1.395984)
		(stroke
			(width 0.1016)
			(type default)
		)
		(layer "In3.Cu")
	)
	(gr_line
		(start 396.481046 -1.49606)
		(end 395.287246 -1.49606)
		(stroke
			(width 0.1016)
			(type default)
		)
		(layer "In3.Cu")
	)
	(gr_line
		(start 396.481046 -1.49606)
		(end 396.481046 -4.16306)
		(stroke
			(width 0.1016)
			(type default)
		)
		(layer "In3.Cu")
	)
	(gr_line
		(start 396.481046 -1.494028)
		(end 395.261846 -1.494028)
		(stroke
			(width 0.1016)
			(type default)
		)
		(layer "In3.Cu")
	)
	(gr_line
		(start 396.481046 -1.494028)
		(end 395.287246 -1.494028)
		(stroke
			(width 0.1016)
			(type default)
		)
		(layer "In3.Cu")
	)
	(gr_line
		(start 396.481046 -1.395984)
		(end 395.287246 -1.395984)
		(stroke
			(width 0.1016)
			(type default)
		)
		(layer "In3.Cu")
	)
	(gr_line
		(start 396.481046 -1.395984)
		(end 396.481046 -4.062984)
		(stroke
			(width 0.1016)
			(type default)
		)
		(layer "In3.Cu")
	)
	(gr_line
		(start 396.506446 -1.468628)
		(end 395.261846 -1.468628)
		(stroke
			(width 0.1016)
			(type default)
		)
		(layer "In3.Cu")
	)
	(gr_line
		(start 397.519906 -30.99562)
		(end 396.249906 -30.99562)
		(stroke
			(width 0.7874)
			(type default)
		)
		(layer "In3.Cu")
	)
	(gr_line
		(start 399.224246 -24.6634)
		(end 399.224246 -23.3934)
		(stroke
			(width 0.7874)
			(type default)
		)
		(layer "In3.Cu")
	)
	(gr_line
		(start 404.997412 -26.8224)
		(end 406.267412 -26.8224)
		(stroke
			(width 0.7874)
			(type default)
		)
		(layer "In3.Cu")
	)
	(gr_line
		(start 405.228552 -29.30906)
		(end 406.498552 -29.30906)
		(stroke
			(width 0.7874)
			(type default)
		)
		(layer "In3.Cu")
	)
	(gr_line
		(start 410.459682 -30.594808)
		(end 411.729682 -30.594808)
		(stroke
			(width 0.7874)
			(type default)
		)
		(layer "In3.Cu")
	)
	(gr_line
		(start 410.859986 -23.57882)
		(end 412.129986 -23.57882)
		(stroke
			(width 0.7874)
			(type default)
		)
		(layer "In3.Cu")
	)
	(gr_line
		(start 412.873952 -31.68142)
		(end 414.143952 -31.68142)
		(stroke
			(width 0.7874)
			(type default)
		)
		(layer "In3.Cu")
	)
	(gr_line
		(start 413.260032 -18.5166)
		(end 414.530032 -18.5166)
		(stroke
			(width 0.7874)
			(type default)
		)
		(layer "In3.Cu")
	)
	(gr_line
		(start 415.259774 -30.56382)
		(end 416.529774 -30.56382)
		(stroke
			(width 0.7874)
			(type default)
		)
		(layer "In3.Cu")
	)
	(gr_line
		(start 418.662866 -24.67102)
		(end 418.662866 -23.40102)
		(stroke
			(width 0.7874)
			(type default)
		)
		(layer "In3.Cu")
	)
	(gr_line
		(start 424.310048 -4.700016)
		(end 424.310048 -4.699762)
		(stroke
			(width 8.128)
			(type default)
		)
		(layer "In3.Cu")
	)
	(gr_arc
		(start 425.010072 -41.000172)
		(mid 425.156481 -41.353635)
		(end 425.509944 -41.500044)
		(stroke
			(width 2.032)
			(type default)
		)
		(layer "In3.Cu")
	)
	(gr_line
		(start 425.010072 -31.999936)
		(end 425.010072 -41.000172)
		(stroke
			(width 2.032)
			(type default)
		)
		(layer "In3.Cu")
	)
	(gr_line
		(start 425.509944 -41.500044)
		(end 427.110144 -41.500044)
		(stroke
			(width 2.032)
			(type default)
		)
		(layer "In3.Cu")
	)
	(gr_arc
		(start 425.509944 -31.500064)
		(mid 425.156481 -31.646473)
		(end 425.010072 -31.999936)
		(stroke
			(width 2.032)
			(type default)
		)
		(layer "In3.Cu")
	)
	(gr_line
		(start 425.61002 -50.390044)
		(end 381.990092 -50.390044)
		(stroke
			(width 2.032)
			(type default)
		)
		(layer "In3.Cu")
	)
	(gr_arc
		(start 425.61002 -50.390044)
		(mid 427.024235 -49.804255)
		(end 427.610016 -48.390048)
		(stroke
			(width 2.032)
			(type default)
		)
		(layer "In3.Cu")
	)
	(gr_line
		(start 426.82033 -1.905)
		(end 426.82033 -1.905254)
		(stroke
			(width 5.588)
			(type default)
		)
		(layer "In3.Cu")
	)
	(gr_line
		(start 427.10989 -31.500064)
		(end 425.509944 -31.500064)
		(stroke
			(width 2.032)
			(type default)
		)
		(layer "In3.Cu")
	)
	(gr_arc
		(start 427.10989 -31.500064)
		(mid 427.463552 -31.353586)
		(end 427.610016 -30.999938)
		(stroke
			(width 2.032)
			(type default)
		)
		(layer "In3.Cu")
	)
	(gr_arc
		(start 427.610016 -41.999916)
		(mid 427.463615 -41.646427)
		(end 427.110144 -41.500044)
		(stroke
			(width 2.032)
			(type default)
		)
		(layer "In3.Cu")
	)
	(gr_line
		(start 427.610016 -41.999916)
		(end 427.610016 -48.390048)
		(stroke
			(width 2.032)
			(type default)
		)
		(layer "In3.Cu")
	)
	(gr_line
		(start 427.610016 -10.999978)
		(end 427.610016 -30.999938)
		(stroke
			(width 2.032)
			(type default)
		)
		(layer "In3.Cu")
	)
	(gr_arc
		(start 428.109888 -10.500106)
		(mid 427.756425 -10.646515)
		(end 427.610016 -10.999978)
		(stroke
			(width 2.032)
			(type default)
		)
		(layer "In3.Cu")
	)
	(gr_line
		(start 428.309786 -10.500106)
		(end 428.109888 -10.500106)
		(stroke
			(width 2.032)
			(type default)
		)
		(layer "In3.Cu")
	)
	(gr_arc
		(start 428.309786 -10.500106)
		(mid 428.66343 -10.353626)
		(end 428.809912 -9.99998)
		(stroke
			(width 2.032)
			(type default)
		)
		(layer "In3.Cu")
	)
	(gr_arc
		(start 428.809912 -1.999996)
		(mid 428.224126 -0.585782)
		(end 426.809916 0)
		(stroke
			(width 2.032)
			(type default)
		)
		(layer "In3.Cu")
	)
	(gr_line
		(start 428.809912 -1.999996)
		(end 428.809912 -9.99998)
		(stroke
			(width 2.032)
			(type default)
		)
		(layer "In3.Cu")
	)
	(gr_line
		(start 0 -51.799998)
		(end 0 -1.999996)
		(stroke
			(width 2.032)
			(type default)
		)
		(layer "In4.Cu")
	)
	(gr_poly
		(pts
			(xy 77.43698 -51.303936) (xy 77.460144 -51.303425) (xy 77.505705 -51.29503) (xy 77.548988 -51.278514)
			(xy 77.58856 -51.254425) (xy 77.62311 -51.223561) (xy 77.651491 -51.186944) (xy 77.672764 -51.145789)
			(xy 77.686223 -51.10146) (xy 77.691422 -51.055425) (xy 77.68819 -51.00921) (xy 77.676632 -50.964347)
			(xy 77.657133 -50.922323) (xy 77.630339 -50.88453) (xy 77.597136 -50.852221) (xy 77.578204 -50.838862)
			(xy 77.504474 -50.788989) (xy 77.361001 -50.683592) (xy 77.22234 -50.571942) (xy 77.088762 -50.454256)
			(xy 76.960531 -50.330767) (xy 76.837898 -50.201716) (xy 76.721104 -50.067358) (xy 76.610378 -49.927957)
			(xy 76.505939 -49.783786) (xy 76.407991 -49.635128) (xy 76.316727 -49.482276) (xy 76.232326 -49.32553)
			(xy 76.154954 -49.165198) (xy 76.084762 -49.001595) (xy 76.02189 -48.835042) (xy 75.966459 -48.665866)
			(xy 75.91858 -48.4944) (xy 75.878347 -48.320982) (xy 75.845837 -48.14595) (xy 75.821116 -47.96965)
			(xy 75.804231 -47.792428) (xy 75.795216 -47.614631) (xy 75.794089 -47.43661) (xy 75.800852 -47.258713)
			(xy 75.815492 -47.081291) (xy 75.837979 -46.904692) (xy 75.86827 -46.729263) (xy 75.906305 -46.555349)
			(xy 75.952009 -46.383291) (xy 76.005293 -46.213427) (xy 76.066052 -46.046091) (xy 76.134166 -45.881612)
			(xy 76.209502 -45.720313) (xy 76.291912 -45.562511) (xy 76.381233 -45.408516) (xy 76.477291 -45.25863)
			(xy 76.579897 -45.113148) (xy 76.688848 -44.972356) (xy 76.803932 -44.83653) (xy 76.924921 -44.705938)
			(xy 76.987908 -44.64304) (xy 77.005688 -44.62526) (xy 77.044042 -44.534582) (xy 77.044042 -41.549574)
			(xy 77.044042 -41.450514) (xy 77.044042 -41.287192) (xy 77.051916 -41.279318) (xy 77.056488 -41.233852)
			(xy 77.056488 -41.233598) (xy 77.064096 -41.160097) (xy 77.086174 -41.013971) (xy 77.116023 -40.869232)
			(xy 77.153558 -40.726294) (xy 77.198672 -40.585564) (xy 77.251236 -40.447443) (xy 77.311101 -40.312327)
			(xy 77.378095 -40.1806) (xy 77.452027 -40.052638) (xy 77.532687 -39.928806) (xy 77.619843 -39.809458)
			(xy 77.713249 -39.694935) (xy 77.812636 -39.585562) (xy 77.917722 -39.481652) (xy 78.028207 -39.383502)
			(xy 78.143774 -39.291392) (xy 78.264096 -39.205584) (xy 78.388827 -39.126323) (xy 78.517613 -39.053836)
			(xy 78.650086 -38.988329) (xy 78.785868 -38.929989) (xy 78.924571 -38.878982) (xy 79.0658 -38.835455)
			(xy 79.209152 -38.799531) (xy 79.354217 -38.771313) (xy 79.500582 -38.750882) (xy 79.64783 -38.738295)
			(xy 79.795539 -38.733588) (xy 79.943289 -38.736776) (xy 80.090658 -38.747849) (xy 80.237226 -38.766775)
			(xy 80.382574 -38.7935) (xy 80.526287 -38.827948) (xy 80.667956 -38.870021) (xy 80.807177 -38.919599)
			(xy 80.943551 -38.97654) (xy 81.07669 -39.040682) (xy 81.206214 -39.111841) (xy 81.331754 -39.189816)
			(xy 81.452951 -39.274382) (xy 81.56946 -39.3653) (xy 81.680947 -39.462309) (xy 81.787096 -39.565133)
			(xy 81.887602 -39.673478) (xy 81.98218 -39.787036) (xy 82.070559 -39.905481) (xy 82.152488 -40.028477)
			(xy 82.227732 -40.155672) (xy 82.296076 -40.286704) (xy 82.357327 -40.421198) (xy 82.411308 -40.55877)
			(xy 82.457866 -40.699029) (xy 82.496869 -40.841574) (xy 82.528204 -40.985998) (xy 82.551783 -41.13189)
			(xy 82.567538 -41.278832) (xy 82.575424 -41.426406) (xy 82.575908 -41.500298) (xy 82.575908 -44.534582)
			(xy 82.614262 -44.62526) (xy 82.632042 -44.64304) (xy 82.695033 -44.705936) (xy 82.816032 -44.836524)
			(xy 82.897816 -44.933038) (xy 115.78564 -44.933038) (xy 115.78564 -44.805162) (xy 115.793669 -44.677538)
			(xy 115.809697 -44.55067) (xy 115.833658 -44.425058) (xy 115.86546 -44.3012) (xy 115.904976 -44.179582)
			(xy 115.95205 -44.060685) (xy 116.006497 -43.944979) (xy 116.068102 -43.83292) (xy 116.136622 -43.724951)
			(xy 116.211786 -43.621497) (xy 116.293297 -43.522966) (xy 116.380834 -43.429748) (xy 116.474052 -43.342211)
			(xy 116.572583 -43.2607) (xy 116.676037 -43.185536) (xy 116.784006 -43.117016) (xy 116.896065 -43.055411)
			(xy 117.011771 -43.000964) (xy 117.130668 -42.95389) (xy 117.252286 -42.914374) (xy 117.376144 -42.882572)
			(xy 117.501756 -42.858611) (xy 117.628624 -42.842583) (xy 117.756248 -42.834554) (xy 117.884124 -42.834554)
			(xy 118.011748 -42.842583) (xy 118.138616 -42.858611) (xy 118.264228 -42.882572) (xy 118.388086 -42.914374)
			(xy 118.509704 -42.95389) (xy 118.628601 -43.000964) (xy 118.744307 -43.055411) (xy 118.856366 -43.117016)
			(xy 118.964335 -43.185536) (xy 119.067789 -43.2607) (xy 119.16632 -43.342211) (xy 119.259538 -43.429748)
			(xy 119.347075 -43.522966) (xy 119.428586 -43.621497) (xy 119.50375 -43.724951) (xy 119.57227 -43.83292)
			(xy 119.633875 -43.944979) (xy 119.688322 -44.060685) (xy 119.735396 -44.179582) (xy 119.774912 -44.3012)
			(xy 119.806714 -44.425058) (xy 119.830675 -44.55067) (xy 119.846703 -44.677538) (xy 119.854732 -44.805162)
			(xy 119.855234 -44.8691) (xy 119.854732 -44.932982) (xy 127.217418 -44.932982) (xy 127.217418 -44.805218)
			(xy 127.22544 -44.677705) (xy 127.241453 -44.550948) (xy 127.265394 -44.425446) (xy 127.297168 -44.301696)
			(xy 127.336649 -44.180184) (xy 127.383682 -44.061392) (xy 127.438082 -43.945787) (xy 127.499633 -43.833826)
			(xy 127.568093 -43.725951) (xy 127.643191 -43.622587) (xy 127.724631 -43.524142) (xy 127.812092 -43.431006)
			(xy 127.905228 -43.343545) (xy 128.003673 -43.262105) (xy 128.107037 -43.187007) (xy 128.214912 -43.118547)
			(xy 128.326873 -43.056996) (xy 128.442478 -43.002596) (xy 128.56127 -42.955563) (xy 128.682782 -42.916082)
			(xy 128.806532 -42.884308) (xy 128.932034 -42.860367) (xy 129.058791 -42.844354) (xy 129.186304 -42.836332)
			(xy 129.314068 -42.836332) (xy 129.441581 -42.844354) (xy 129.568338 -42.860367) (xy 129.69384 -42.884308)
			(xy 129.81759 -42.916082) (xy 129.939102 -42.955563) (xy 130.057894 -43.002596) (xy 130.173499 -43.056996)
			(xy 130.28546 -43.118547) (xy 130.393335 -43.187007) (xy 130.496699 -43.262105) (xy 130.595144 -43.343545)
			(xy 130.68828 -43.431006) (xy 130.775741 -43.524142) (xy 130.857181 -43.622587) (xy 130.932279 -43.725951)
			(xy 131.000739 -43.833826) (xy 131.06229 -43.945787) (xy 131.11669 -44.061392) (xy 131.163723 -44.180184)
			(xy 131.203204 -44.301696) (xy 131.234978 -44.425446) (xy 131.258919 -44.550948) (xy 131.274932 -44.677705)
			(xy 131.282954 -44.805218) (xy 131.283456 -44.8691) (xy 131.282954 -44.932982) (xy 131.274932 -45.060495)
			(xy 131.258919 -45.187252) (xy 131.234978 -45.312754) (xy 131.203204 -45.436504) (xy 131.163723 -45.558016)
			(xy 131.11669 -45.676808) (xy 131.06229 -45.792413) (xy 131.000739 -45.904374) (xy 130.932279 -46.012249)
			(xy 130.857181 -46.115613) (xy 130.775741 -46.214058) (xy 130.68828 -46.307194) (xy 130.595144 -46.394655)
			(xy 130.496699 -46.476095) (xy 130.393335 -46.551193) (xy 130.28546 -46.619653) (xy 130.173499 -46.681204)
			(xy 130.057894 -46.735604) (xy 129.939102 -46.782637) (xy 129.81759 -46.822118) (xy 129.69384 -46.853892)
			(xy 129.568338 -46.877833) (xy 129.441581 -46.893846) (xy 129.314068 -46.901868) (xy 129.186304 -46.901868)
			(xy 129.058791 -46.893846) (xy 128.932034 -46.877833) (xy 128.806532 -46.853892) (xy 128.682782 -46.822118)
			(xy 128.56127 -46.782637) (xy 128.442478 -46.735604) (xy 128.326873 -46.681204) (xy 128.214912 -46.619653)
			(xy 128.107037 -46.551193) (xy 128.003673 -46.476095) (xy 127.905228 -46.394655) (xy 127.812092 -46.307194)
			(xy 127.724631 -46.214058) (xy 127.643191 -46.115613) (xy 127.568093 -46.012249) (xy 127.499633 -45.904374)
			(xy 127.438082 -45.792413) (xy 127.383682 -45.676808) (xy 127.336649 -45.558016) (xy 127.297168 -45.436504)
			(xy 127.265394 -45.312754) (xy 127.241453 -45.187252) (xy 127.22544 -45.060495) (xy 127.217418 -44.932982)
			(xy 119.854732 -44.932982) (xy 119.854732 -44.933038) (xy 119.846703 -45.060662) (xy 119.830675 -45.18753)
			(xy 119.806714 -45.313142) (xy 119.774912 -45.437) (xy 119.735396 -45.558618) (xy 119.688322 -45.677515)
			(xy 119.633875 -45.793221) (xy 119.57227 -45.90528) (xy 119.50375 -46.013249) (xy 119.428586 -46.116703)
			(xy 119.347075 -46.215234) (xy 119.259538 -46.308452) (xy 119.16632 -46.395989) (xy 119.067789 -46.4775)
			(xy 118.964335 -46.552664) (xy 118.856366 -46.621184) (xy 118.744307 -46.682789) (xy 118.628601 -46.737236)
			(xy 118.509704 -46.78431) (xy 118.388086 -46.823826) (xy 118.264228 -46.855628) (xy 118.138616 -46.879589)
			(xy 118.011748 -46.895617) (xy 117.884124 -46.903646) (xy 117.756248 -46.903646) (xy 117.628624 -46.895617)
			(xy 117.501756 -46.879589) (xy 117.376144 -46.855628) (xy 117.252286 -46.823826) (xy 117.130668 -46.78431)
			(xy 117.011771 -46.737236) (xy 116.896065 -46.682789) (xy 116.784006 -46.621184) (xy 116.676037 -46.552664)
			(xy 116.572583 -46.4775) (xy 116.474052 -46.395989) (xy 116.380834 -46.308452) (xy 116.293297 -46.215234)
			(xy 116.211786 -46.116703) (xy 116.136622 -46.013249) (xy 116.068102 -45.90528) (xy 116.006497 -45.793221)
			(xy 115.95205 -45.677515) (xy 115.904976 -45.558618) (xy 115.86546 -45.437) (xy 115.833658 -45.313142)
			(xy 115.809697 -45.18753) (xy 115.793669 -45.060662) (xy 115.78564 -44.933038) (xy 82.897816 -44.933038)
			(xy 82.931125 -44.972346) (xy 83.040086 -45.113136) (xy 83.1427 -45.258615) (xy 83.238766 -45.4085)
			(xy 83.328096 -45.562494) (xy 83.410514 -45.720296) (xy 83.485857 -45.881595) (xy 83.553978 -46.046075)
			(xy 83.614743 -46.213412) (xy 83.668032 -46.383277) (xy 83.713742 -46.555337) (xy 83.751781 -46.729254)
			(xy 83.782076 -46.904686) (xy 83.804566 -47.081288) (xy 83.819208 -47.258713) (xy 83.825972 -47.436612)
			(xy 83.824846 -47.614637) (xy 83.815832 -47.792437) (xy 83.798947 -47.969663) (xy 83.774225 -48.145966)
			(xy 83.741714 -48.321) (xy 83.701478 -48.494422) (xy 83.653596 -48.66589) (xy 83.598162 -48.835068)
			(xy 83.535285 -49.001623) (xy 83.465089 -49.165228) (xy 83.387711 -49.325561) (xy 83.303304 -49.482308)
			(xy 83.212034 -49.63516) (xy 83.114079 -49.783817) (xy 83.009633 -49.927987) (xy 82.8989 -50.067387)
			(xy 82.782098 -50.201742) (xy 82.659457 -50.33079) (xy 82.531218 -50.454275) (xy 82.397631 -50.571956)
			(xy 82.258961 -50.683601) (xy 82.11548 -50.788992) (xy 82.041746 -50.838862) (xy 82.022784 -50.85217)
			(xy 81.989599 -50.884484) (xy 81.962821 -50.922278) (xy 81.943336 -50.9643) (xy 81.93179 -51.009157)
			(xy 81.928566 -51.055365) (xy 81.933771 -51.101391) (xy 81.947232 -51.145711) (xy 81.968503 -51.186857)
			(xy 81.99688 -51.223467) (xy 82.031422 -51.254327) (xy 82.070985 -51.278415) (xy 82.114259 -51.294933)
			(xy 82.15981 -51.303334) (xy 82.18297 -51.303936) (xy 94.5388 -51.303936) (xy 94.55545 -51.303393)
			(xy 94.587616 -51.294776) (xy 94.616456 -51.278128) (xy 94.640006 -51.254585) (xy 94.656662 -51.225749)
			(xy 94.665288 -51.193586) (xy 94.6658 -51.176936) (xy 94.6658 -50.8) (xy 94.666298 -50.73666) (xy 94.674252 -50.610231)
			(xy 94.690129 -50.48455) (xy 94.713866 -50.360115) (xy 94.74537 -50.237415) (xy 94.784516 -50.116936)
			(xy 94.83115 -49.999153) (xy 94.885087 -49.88453) (xy 94.946116 -49.77352) (xy 95.013994 -49.666561)
			(xy 95.088454 -49.564075) (xy 95.169202 -49.466467) (xy 95.25592 -49.374122) (xy 95.348265 -49.287404)
			(xy 95.445874 -49.206655) (xy 95.548359 -49.132195) (xy 95.655318 -49.064317) (xy 95.766328 -49.003288)
			(xy 95.880951 -48.949351) (xy 95.998734 -48.902717) (xy 96.119214 -48.863571) (xy 96.241913 -48.832067)
			(xy 96.366349 -48.808329) (xy 96.492029 -48.792452) (xy 96.618458 -48.784498) (xy 96.681798 -48.784002)
			(xy 112.06988 -48.784002) (xy 112.13322 -48.784489) (xy 112.259651 -48.792442) (xy 112.385333 -48.808318)
			(xy 112.50977 -48.832055) (xy 112.632471 -48.863558) (xy 112.752952 -48.902703) (xy 112.870737 -48.949337)
			(xy 112.985362 -49.003274) (xy 113.096373 -49.064302) (xy 113.203334 -49.132181) (xy 113.305821 -49.206641)
			(xy 113.403431 -49.28739) (xy 113.495778 -49.374108) (xy 113.582497 -49.466454) (xy 113.663247 -49.564063)
			(xy 113.737708 -49.666549) (xy 113.805588 -49.773509) (xy 113.866617 -49.88452) (xy 113.920555 -49.999144)
			(xy 113.96719 -50.116929) (xy 114.006336 -50.237409) (xy 114.037841 -50.36011) (xy 114.061579 -50.484547)
			(xy 114.077456 -50.610229) (xy 114.08541 -50.73666) (xy 114.085878 -50.8) (xy 114.085878 -51.176936)
			(xy 114.086425 -51.193582) (xy 114.095049 -51.225739) (xy 114.111699 -51.254569) (xy 114.135242 -51.278109)
			(xy 114.164074 -51.294756) (xy 114.196232 -51.303376) (xy 114.212878 -51.303936) (xy 132.84708 -51.303936)
			(xy 132.863732 -51.303395) (xy 132.895902 -51.294781) (xy 132.924747 -51.278135) (xy 132.948301 -51.254592)
			(xy 132.96496 -51.225754) (xy 132.973588 -51.193588) (xy 132.97408 -51.176936) (xy 132.97408 -50.8)
			(xy 132.974578 -50.73666) (xy 132.982532 -50.61023) (xy 132.998409 -50.484549) (xy 133.022146 -50.360113)
			(xy 133.05365 -50.237413) (xy 133.092796 -50.116934) (xy 133.139429 -49.99915) (xy 133.193367 -49.884526)
			(xy 133.254395 -49.773516) (xy 133.322273 -49.666556) (xy 133.396733 -49.56407) (xy 133.477481 -49.466461)
			(xy 133.564199 -49.374115) (xy 133.656544 -49.287396) (xy 133.754152 -49.206646) (xy 133.856638 -49.132185)
			(xy 133.963597 -49.064306) (xy 134.074606 -49.003277) (xy 134.189229 -48.949338) (xy 134.307013 -48.902703)
			(xy 134.427492 -48.863556) (xy 134.550192 -48.832051) (xy 134.674628 -48.808312) (xy 134.800308 -48.792434)
			(xy 134.926738 -48.784478) (xy 134.990078 -48.784002) (xy 149.990048 -48.784002) (xy 150.053387 -48.784501)
			(xy 150.179814 -48.792458) (xy 150.305492 -48.808338) (xy 150.429925 -48.832077) (xy 150.552622 -48.863583)
			(xy 150.673099 -48.902731) (xy 150.79088 -48.949366) (xy 150.9055 -49.003305) (xy 151.016507 -49.064334)
			(xy 151.123463 -49.132212) (xy 151.225946 -49.206673) (xy 151.323552 -49.287422) (xy 151.415895 -49.374139)
			(xy 151.50261 -49.466484) (xy 151.583356 -49.564092) (xy 151.657815 -49.666576) (xy 151.725691 -49.773534)
			(xy 151.786717 -49.884543) (xy 151.840653 -49.999165) (xy 151.887285 -50.116946) (xy 151.92643 -50.237424)
			(xy 151.957933 -50.360122) (xy 151.98167 -50.484555) (xy 151.997546 -50.610234) (xy 152.005501 -50.736661)
			(xy 152.006046 -50.8) (xy 152.006046 -51.176936) (xy 152.006545 -51.193585) (xy 152.015173 -51.225747)
			(xy 152.031832 -51.25458) (xy 152.055385 -51.278119) (xy 152.084229 -51.294758) (xy 152.116396 -51.303366)
			(xy 152.133046 -51.303936) (xy 158.856172 -51.303936) (xy 158.873545 -51.303415) (xy 158.907007 -51.294061)
			(xy 158.936696 -51.276013) (xy 158.960405 -51.250615) (xy 158.976369 -51.219755) (xy 158.980378 -51.202844)
			(xy 158.99003 -51.156616) (xy 159.12465 -50.580036) (xy 159.334454 -50.272696) (xy 159.378142 -50.060606)
			(xy 159.562546 -49.93894) (xy 159.68726 -49.756568) (xy 159.899858 -49.716436) (xy 160.218882 -49.506124)
			(xy 160.89122 -49.374044) (xy 202.680316 -49.374044) (xy 202.772772 -49.312068) (xy 203.088748 -49.374044)
			(xy 203.41082 -49.374044) (xy 203.48956 -49.452784) (xy 203.761086 -49.506124) (xy 204.08011 -49.716436)
			(xy 204.292708 -49.756568) (xy 204.417422 -49.93894) (xy 204.601826 -50.060606) (xy 204.645514 -50.272696)
			(xy 204.855318 -50.580036) (xy 204.989938 -51.156616) (xy 204.99959 -51.202844) (xy 205.003719 -51.219706)
			(xy 205.01971 -51.250502) (xy 205.043401 -51.275856) (xy 205.073043 -51.293897) (xy 205.106447 -51.303292)
			(xy 205.123796 -51.303936) (xy 207.437482 -51.303936) (xy 207.460633 -51.303399) (xy 207.506161 -51.294958)
			(xy 207.549405 -51.278408) (xy 207.588935 -51.254296) (xy 207.623441 -51.22342) (xy 207.651781 -51.186803)
			(xy 207.673018 -51.145656) (xy 207.686447 -51.101343) (xy 207.691624 -51.05533) (xy 207.688379 -51.009141)
			(xy 207.676817 -50.964304) (xy 207.657323 -50.922304) (xy 207.630541 -50.884532) (xy 207.597358 -50.852239)
			(xy 207.578452 -50.838862) (xy 207.504712 -50.788993) (xy 207.36122 -50.683603) (xy 207.222539 -50.571958)
			(xy 207.088943 -50.454277) (xy 206.960692 -50.330791) (xy 206.838041 -50.201743) (xy 206.721228 -50.067386)
			(xy 206.610485 -49.927984) (xy 206.506028 -49.783811) (xy 206.408063 -49.635151) (xy 206.316783 -49.482296)
			(xy 206.232366 -49.325545) (xy 206.154979 -49.165207) (xy 206.084773 -49.001598) (xy 206.021888 -48.835038)
			(xy 205.966445 -48.665854) (xy 205.918554 -48.49438) (xy 205.87831 -48.320952) (xy 205.845791 -48.14591)
			(xy 205.821061 -47.9696) (xy 205.804168 -47.792367) (xy 205.795147 -47.614559) (xy 205.794015 -47.436526)
			(xy 205.800773 -47.258618) (xy 205.815409 -47.081185) (xy 205.837894 -46.904574) (xy 205.868184 -46.729133)
			(xy 205.906218 -46.555207) (xy 205.951924 -46.383137) (xy 206.00521 -46.213262) (xy 206.065971 -46.045915)
			(xy 206.13409 -45.881426) (xy 206.209431 -45.720116) (xy 206.291847 -45.562305) (xy 206.381175 -45.4083)
			(xy 206.477241 -45.258406) (xy 206.579855 -45.112916) (xy 206.688816 -44.972116) (xy 206.803909 -44.836284)
			(xy 206.924909 -44.705686) (xy 206.987902 -44.642786) (xy 207.005682 -44.625006) (xy 207.044036 -44.534328)
			(xy 207.044036 -41.54932) (xy 207.044036 -41.45026) (xy 207.044036 -41.286938) (xy 207.05191 -41.279064)
			(xy 207.056482 -41.233598) (xy 207.056482 -41.233344) (xy 207.064089 -41.159841) (xy 207.086165 -41.013711)
			(xy 207.116012 -40.868968) (xy 207.153546 -40.726025) (xy 207.198659 -40.58529) (xy 207.251222 -40.447166)
			(xy 207.311086 -40.312045) (xy 207.37808 -40.180313) (xy 207.452013 -40.052347) (xy 207.532673 -39.928511)
			(xy 207.619831 -39.809159) (xy 207.713237 -39.694631) (xy 207.812626 -39.585254) (xy 207.917714 -39.481341)
			(xy 208.0282 -39.383187) (xy 208.14377 -39.291073) (xy 208.264094 -39.205262) (xy 208.388828 -39.125998)
			(xy 208.517617 -39.053508) (xy 208.650093 -38.987998) (xy 208.785878 -38.929656) (xy 208.924585 -38.878648)
			(xy 209.065817 -38.835119) (xy 209.209172 -38.799193) (xy 209.354242 -38.770974) (xy 209.500611 -38.750541)
			(xy 209.647862 -38.737954) (xy 209.795575 -38.733247) (xy 209.943329 -38.736435) (xy 210.090702 -38.747508)
			(xy 210.237274 -38.766434) (xy 210.382625 -38.79316) (xy 210.526343 -38.827609) (xy 210.668015 -38.869684)
			(xy 210.807239 -38.919263) (xy 210.943617 -38.976206) (xy 211.076759 -39.04035) (xy 211.206287 -39.111512)
			(xy 211.331829 -39.189489) (xy 211.453029 -39.274059) (xy 211.56954 -39.36498) (xy 211.68103 -39.461992)
			(xy 211.78718 -39.564819) (xy 211.887689 -39.673168) (xy 211.982268 -39.78673) (xy 212.070648 -39.905179)
			(xy 212.152578 -40.028179) (xy 212.227822 -40.155378) (xy 212.296167 -40.286414) (xy 212.357418 -40.420912)
			(xy 212.411399 -40.558489) (xy 212.457956 -40.698752) (xy 212.496958 -40.841302) (xy 212.528292 -40.98573)
			(xy 212.551869 -41.131626) (xy 212.567622 -41.278572) (xy 212.575506 -41.42615) (xy 212.575902 -41.500044)
			(xy 212.575902 -44.534328) (xy 212.614256 -44.625006) (xy 212.632036 -44.642786) (xy 212.69503 -44.705686)
			(xy 212.816034 -44.836282) (xy 212.931132 -44.972112) (xy 213.040097 -45.112909) (xy 213.142715 -45.258398)
			(xy 213.238784 -45.408291) (xy 213.328116 -45.562295) (xy 213.410535 -45.720106) (xy 213.485879 -45.881415)
			(xy 213.554 -46.045905) (xy 213.614765 -46.213252) (xy 213.668053 -46.383128) (xy 213.71376 -46.555198)
			(xy 213.751797 -46.729125) (xy 213.782088 -46.904567) (xy 213.804574 -47.081178) (xy 213.819211 -47.258613)
			(xy 213.82597 -47.436522) (xy 213.824837 -47.614556) (xy 213.815816 -47.792365) (xy 213.798923 -47.969599)
			(xy 213.774192 -48.145911) (xy 213.741672 -48.320953) (xy 213.701426 -48.494382) (xy 213.653533 -48.665857)
			(xy 213.598089 -48.835041) (xy 213.5352 -49.001601) (xy 213.464992 -49.165211) (xy 213.387602 -49.325549)
			(xy 213.303182 -49.482299) (xy 213.211899 -49.635154) (xy 213.11393 -49.783813) (xy 213.00947 -49.927984)
			(xy 212.898723 -50.067384) (xy 212.781906 -50.201739) (xy 212.65925 -50.330785) (xy 212.530996 -50.454269)
			(xy 212.397395 -50.571947) (xy 212.25871 -50.683588) (xy 212.115213 -50.788974) (xy 212.041486 -50.838862)
			(xy 212.022522 -50.852168) (xy 211.989333 -50.884479) (xy 211.96255 -50.922272) (xy 211.943062 -50.964293)
			(xy 211.931514 -51.009151) (xy 211.928289 -51.05536) (xy 211.933493 -51.101387) (xy 211.946955 -51.145708)
			(xy 211.968228 -51.186855) (xy 211.996607 -51.223464) (xy 212.031152 -51.254322) (xy 212.070719 -51.278407)
			(xy 212.113996 -51.29492) (xy 212.15955 -51.303315) (xy 212.18271 -51.303936) (xy 298.437554 -51.303936)
			(xy 298.460707 -51.303401) (xy 298.506239 -51.294964) (xy 298.549488 -51.278416) (xy 298.589023 -51.254305)
			(xy 298.623533 -51.223428) (xy 298.651877 -51.186809) (xy 298.673116 -51.14566) (xy 298.686547 -51.101344)
			(xy 298.691724 -51.055327) (xy 298.688477 -51.009134) (xy 298.676914 -50.964294) (xy 298.657416 -50.922292)
			(xy 298.630629 -50.884519) (xy 298.597441 -50.852225) (xy 298.578524 -50.838862) (xy 298.504785 -50.788992)
			(xy 298.361293 -50.683603) (xy 298.222614 -50.571957) (xy 298.089018 -50.454276) (xy 297.960768 -50.330789)
			(xy 297.838117 -50.201741) (xy 297.721306 -50.067383) (xy 297.610563 -49.927981) (xy 297.506107 -49.783809)
			(xy 297.408143 -49.635149) (xy 297.316863 -49.482293) (xy 297.232447 -49.325543) (xy 297.155061 -49.165205)
			(xy 297.084856 -49.001596) (xy 297.02197 -48.835036) (xy 296.966528 -48.665852) (xy 296.918638 -48.494378)
			(xy 296.878394 -48.320951) (xy 296.845875 -48.14591) (xy 296.821145 -47.9696) (xy 296.804253 -47.792367)
			(xy 296.795232 -47.614559) (xy 296.794099 -47.436527) (xy 296.800857 -47.258619) (xy 296.815493 -47.081186)
			(xy 296.837978 -46.904576) (xy 296.868267 -46.729135) (xy 296.906302 -46.555209) (xy 296.952007 -46.38314)
			(xy 297.005292 -46.213265) (xy 297.066053 -46.045919) (xy 297.134171 -45.881429) (xy 297.209512 -45.72012)
			(xy 297.291927 -45.562308) (xy 297.381254 -45.408304) (xy 297.477319 -45.258409) (xy 297.579933 -45.11292)
			(xy 297.688893 -44.97212) (xy 297.803985 -44.836287) (xy 297.924985 -44.705689) (xy 297.987974 -44.642786)
			(xy 298.005754 -44.625006) (xy 298.044108 -44.534328) (xy 298.044108 -41.54932) (xy 298.044108 -41.45026)
			(xy 298.044108 -41.286938) (xy 298.051982 -41.279064) (xy 298.056554 -41.233598) (xy 298.056554 -41.233344)
			(xy 298.064161 -41.159843) (xy 298.086236 -41.013716) (xy 298.116083 -40.868977) (xy 298.153616 -40.726039)
			(xy 298.198728 -40.585308) (xy 298.251291 -40.447187) (xy 298.311154 -40.31207) (xy 298.378146 -40.180342)
			(xy 298.452077 -40.052379) (xy 298.532735 -39.928547) (xy 298.619891 -39.809198) (xy 298.713295 -39.694674)
			(xy 298.812682 -39.5853) (xy 298.917767 -39.48139) (xy 299.02825 -39.383239) (xy 299.143817 -39.291128)
			(xy 299.264138 -39.205319) (xy 299.388869 -39.126057) (xy 299.517655 -39.053569) (xy 299.650127 -38.988062)
			(xy 299.785909 -38.929721) (xy 299.924612 -38.878714) (xy 300.06584 -38.835187) (xy 300.209192 -38.799262)
			(xy 300.354257 -38.771044) (xy 300.500623 -38.750612) (xy 300.64787 -38.738025) (xy 300.795579 -38.733319)
			(xy 300.943329 -38.736507) (xy 301.090698 -38.747579) (xy 301.237266 -38.766505) (xy 301.382614 -38.793231)
			(xy 301.526327 -38.827679) (xy 301.667996 -38.869753) (xy 301.807216 -38.919331) (xy 301.94359 -38.976273)
			(xy 302.076729 -39.040415) (xy 302.206253 -39.111575) (xy 302.331792 -39.189551) (xy 302.452988 -39.274118)
			(xy 302.569496 -39.365036) (xy 302.680983 -39.462046) (xy 302.78713 -39.564871) (xy 302.887636 -39.673217)
			(xy 302.982213 -39.786775) (xy 303.070591 -39.905222) (xy 303.152518 -40.028218) (xy 303.22776 -40.155414)
			(xy 303.296103 -40.286446) (xy 303.357352 -40.420941) (xy 303.411332 -40.558514) (xy 303.457888 -40.698774)
			(xy 303.496889 -40.841319) (xy 303.528222 -40.985744) (xy 303.551798 -41.131635) (xy 303.567551 -41.278578)
			(xy 303.575435 -41.426152) (xy 303.575974 -41.500044) (xy 303.575974 -44.534328) (xy 303.614328 -44.625006)
			(xy 303.632108 -44.642786) (xy 303.695101 -44.705686) (xy 303.816103 -44.836283) (xy 303.898088 -44.933038)
			(xy 336.785706 -44.933038) (xy 336.785706 -44.805162) (xy 336.793735 -44.677538) (xy 336.809763 -44.55067)
			(xy 336.833724 -44.425058) (xy 336.865526 -44.3012) (xy 336.905042 -44.179582) (xy 336.952116 -44.060685)
			(xy 337.006563 -43.944979) (xy 337.068168 -43.83292) (xy 337.136688 -43.724951) (xy 337.211852 -43.621497)
			(xy 337.293363 -43.522966) (xy 337.3809 -43.429748) (xy 337.474118 -43.342211) (xy 337.572649 -43.2607)
			(xy 337.676103 -43.185536) (xy 337.784072 -43.117016) (xy 337.896131 -43.055411) (xy 338.011837 -43.000964)
			(xy 338.130734 -42.95389) (xy 338.252352 -42.914374) (xy 338.37621 -42.882572) (xy 338.501822 -42.858611)
			(xy 338.62869 -42.842583) (xy 338.756314 -42.834554) (xy 338.88419 -42.834554) (xy 339.011814 -42.842583)
			(xy 339.138682 -42.858611) (xy 339.264294 -42.882572) (xy 339.388152 -42.914374) (xy 339.50977 -42.95389)
			(xy 339.628667 -43.000964) (xy 339.744373 -43.055411) (xy 339.856432 -43.117016) (xy 339.964401 -43.185536)
			(xy 340.067855 -43.2607) (xy 340.166386 -43.342211) (xy 340.259604 -43.429748) (xy 340.347141 -43.522966)
			(xy 340.428652 -43.621497) (xy 340.503816 -43.724951) (xy 340.572336 -43.83292) (xy 340.633941 -43.944979)
			(xy 340.688388 -44.060685) (xy 340.735462 -44.179582) (xy 340.774978 -44.3012) (xy 340.80678 -44.425058)
			(xy 340.830741 -44.55067) (xy 340.846769 -44.677538) (xy 340.854798 -44.805162) (xy 340.8553 -44.8691)
			(xy 340.854798 -44.932982) (xy 348.217484 -44.932982) (xy 348.217484 -44.805218) (xy 348.225506 -44.677705)
			(xy 348.241519 -44.550948) (xy 348.26546 -44.425446) (xy 348.297234 -44.301696) (xy 348.336715 -44.180184)
			(xy 348.383748 -44.061392) (xy 348.438148 -43.945787) (xy 348.499699 -43.833826) (xy 348.568159 -43.725951)
			(xy 348.643257 -43.622587) (xy 348.724697 -43.524142) (xy 348.812158 -43.431006) (xy 348.905294 -43.343545)
			(xy 349.003739 -43.262105) (xy 349.107103 -43.187007) (xy 349.214978 -43.118547) (xy 349.326939 -43.056996)
			(xy 349.442544 -43.002596) (xy 349.561336 -42.955563) (xy 349.682848 -42.916082) (xy 349.806598 -42.884308)
			(xy 349.9321 -42.860367) (xy 350.058857 -42.844354) (xy 350.18637 -42.836332) (xy 350.314134 -42.836332)
			(xy 350.441647 -42.844354) (xy 350.568404 -42.860367) (xy 350.693906 -42.884308) (xy 350.817656 -42.916082)
			(xy 350.939168 -42.955563) (xy 351.05796 -43.002596) (xy 351.173565 -43.056996) (xy 351.285526 -43.118547)
			(xy 351.393401 -43.187007) (xy 351.496765 -43.262105) (xy 351.59521 -43.343545) (xy 351.688346 -43.431006)
			(xy 351.775807 -43.524142) (xy 351.857247 -43.622587) (xy 351.932345 -43.725951) (xy 352.000805 -43.833826)
			(xy 352.062356 -43.945787) (xy 352.116756 -44.061392) (xy 352.163789 -44.180184) (xy 352.20327 -44.301696)
			(xy 352.235044 -44.425446) (xy 352.258985 -44.550948) (xy 352.274998 -44.677705) (xy 352.28302 -44.805218)
			(xy 352.283522 -44.8691) (xy 352.28302 -44.932982) (xy 352.274998 -45.060495) (xy 352.258985 -45.187252)
			(xy 352.235044 -45.312754) (xy 352.20327 -45.436504) (xy 352.163789 -45.558016) (xy 352.116756 -45.676808)
			(xy 352.062356 -45.792413) (xy 352.000805 -45.904374) (xy 351.932345 -46.012249) (xy 351.857247 -46.115613)
			(xy 351.775807 -46.214058) (xy 351.688346 -46.307194) (xy 351.59521 -46.394655) (xy 351.496765 -46.476095)
			(xy 351.393401 -46.551193) (xy 351.285526 -46.619653) (xy 351.173565 -46.681204) (xy 351.05796 -46.735604)
			(xy 350.939168 -46.782637) (xy 350.817656 -46.822118) (xy 350.693906 -46.853892) (xy 350.568404 -46.877833)
			(xy 350.441647 -46.893846) (xy 350.314134 -46.901868) (xy 350.18637 -46.901868) (xy 350.058857 -46.893846)
			(xy 349.9321 -46.877833) (xy 349.806598 -46.853892) (xy 349.682848 -46.822118) (xy 349.561336 -46.782637)
			(xy 349.442544 -46.735604) (xy 349.326939 -46.681204) (xy 349.214978 -46.619653) (xy 349.107103 -46.551193)
			(xy 349.003739 -46.476095) (xy 348.905294 -46.394655) (xy 348.812158 -46.307194) (xy 348.724697 -46.214058)
			(xy 348.643257 -46.115613) (xy 348.568159 -46.012249) (xy 348.499699 -45.904374) (xy 348.438148 -45.792413)
			(xy 348.383748 -45.676808) (xy 348.336715 -45.558016) (xy 348.297234 -45.436504) (xy 348.26546 -45.312754)
			(xy 348.241519 -45.187252) (xy 348.225506 -45.060495) (xy 348.217484 -44.932982) (xy 340.854798 -44.932982)
			(xy 340.854798 -44.933038) (xy 340.846769 -45.060662) (xy 340.830741 -45.18753) (xy 340.80678 -45.313142)
			(xy 340.774978 -45.437) (xy 340.735462 -45.558618) (xy 340.688388 -45.677515) (xy 340.633941 -45.793221)
			(xy 340.572336 -45.90528) (xy 340.503816 -46.013249) (xy 340.428652 -46.116703) (xy 340.347141 -46.215234)
			(xy 340.259604 -46.308452) (xy 340.166386 -46.395989) (xy 340.067855 -46.4775) (xy 339.964401 -46.552664)
			(xy 339.856432 -46.621184) (xy 339.744373 -46.682789) (xy 339.628667 -46.737236) (xy 339.50977 -46.78431)
			(xy 339.388152 -46.823826) (xy 339.264294 -46.855628) (xy 339.138682 -46.879589) (xy 339.011814 -46.895617)
			(xy 338.88419 -46.903646) (xy 338.756314 -46.903646) (xy 338.62869 -46.895617) (xy 338.501822 -46.879589)
			(xy 338.37621 -46.855628) (xy 338.252352 -46.823826) (xy 338.130734 -46.78431) (xy 338.011837 -46.737236)
			(xy 337.896131 -46.682789) (xy 337.784072 -46.621184) (xy 337.676103 -46.552664) (xy 337.572649 -46.4775)
			(xy 337.474118 -46.395989) (xy 337.3809 -46.308452) (xy 337.293363 -46.215234) (xy 337.211852 -46.116703)
			(xy 337.136688 -46.013249) (xy 337.068168 -45.90528) (xy 337.006563 -45.793221) (xy 336.952116 -45.677515)
			(xy 336.905042 -45.558618) (xy 336.865526 -45.437) (xy 336.833724 -45.313142) (xy 336.809763 -45.18753)
			(xy 336.793735 -45.060662) (xy 336.785706 -44.933038) (xy 303.898088 -44.933038) (xy 303.931199 -44.972114)
			(xy 304.040162 -45.112913) (xy 304.142778 -45.258402) (xy 304.238846 -45.408296) (xy 304.328176 -45.5623)
			(xy 304.410594 -45.720111) (xy 304.485937 -45.88142) (xy 304.554057 -46.04591) (xy 304.61482 -46.213257)
			(xy 304.668107 -46.383132) (xy 304.713813 -46.555202) (xy 304.751849 -46.729129) (xy 304.78214 -46.90457)
			(xy 304.804625 -47.081181) (xy 304.819262 -47.258615) (xy 304.82602 -47.436524) (xy 304.824888 -47.614557)
			(xy 304.815866 -47.792366) (xy 304.798974 -47.969599) (xy 304.774243 -48.14591) (xy 304.741724 -48.320952)
			(xy 304.701478 -48.494381) (xy 304.653587 -48.665855) (xy 304.598143 -48.835039) (xy 304.535256 -49.001599)
			(xy 304.465049 -49.165209) (xy 304.38766 -49.325547) (xy 304.303242 -49.482297) (xy 304.211959 -49.635152)
			(xy 304.113992 -49.783812) (xy 304.009534 -49.927984) (xy 303.898788 -50.067384) (xy 303.781974 -50.20174)
			(xy 303.65932 -50.330787) (xy 303.531067 -50.454272) (xy 303.397468 -50.571951) (xy 303.258785 -50.683594)
			(xy 303.11529 -50.788981) (xy 303.041558 -50.838862) (xy 303.022596 -50.852169) (xy 302.989409 -50.884483)
			(xy 302.962629 -50.922276) (xy 302.943144 -50.964298) (xy 302.931597 -51.009156) (xy 302.928373 -51.055363)
			(xy 302.933578 -51.101389) (xy 302.947039 -51.14571) (xy 302.96831 -51.186857) (xy 302.996688 -51.223466)
			(xy 303.031231 -51.254325) (xy 303.070795 -51.278412) (xy 303.11407 -51.294929) (xy 303.159622 -51.303328)
			(xy 303.182782 -51.303936) (xy 315.926978 -51.303936) (xy 315.94363 -51.303396) (xy 315.975801 -51.294782)
			(xy 316.004646 -51.278136) (xy 316.028201 -51.254592) (xy 316.04486 -51.225754) (xy 316.053488 -51.193588)
			(xy 316.053978 -51.176936) (xy 316.053978 -50.8) (xy 316.054476 -50.73666) (xy 316.06243 -50.61023)
			(xy 316.078307 -50.484549) (xy 316.102044 -50.360113) (xy 316.133548 -50.237413) (xy 316.172694 -50.116933)
			(xy 316.219327 -49.999149) (xy 316.273265 -49.884526) (xy 316.334293 -49.773515) (xy 316.402171 -49.666555)
			(xy 316.476631 -49.564069) (xy 316.557379 -49.46646) (xy 316.644097 -49.374114) (xy 316.736442 -49.287395)
			(xy 316.83405 -49.206646) (xy 316.936536 -49.132184) (xy 317.043494 -49.064305) (xy 317.154504 -49.003276)
			(xy 317.269127 -48.949337) (xy 317.386911 -48.902702) (xy 317.50739 -48.863555) (xy 317.63009 -48.832049)
			(xy 317.754526 -48.808311) (xy 317.880206 -48.792432) (xy 318.006636 -48.784476) (xy 318.069976 -48.784002)
			(xy 333.069946 -48.784002) (xy 333.133285 -48.784501) (xy 333.259712 -48.792458) (xy 333.38539 -48.808337)
			(xy 333.509823 -48.832077) (xy 333.632521 -48.863583) (xy 333.752997 -48.90273) (xy 333.870778 -48.949365)
			(xy 333.985398 -49.003304) (xy 334.096406 -49.064333) (xy 334.203362 -49.132212) (xy 334.305845 -49.206672)
			(xy 334.403451 -49.287421) (xy 334.495794 -49.374139) (xy 334.58251 -49.466483) (xy 334.663256 -49.564091)
			(xy 334.737714 -49.666576) (xy 334.80559 -49.773534) (xy 334.866617 -49.884542) (xy 334.920553 -49.999164)
			(xy 334.967185 -50.116946) (xy 335.00633 -50.237424) (xy 335.037833 -50.360121) (xy 335.06157 -50.484555)
			(xy 335.077446 -50.610234) (xy 335.085401 -50.736661) (xy 335.085944 -50.8) (xy 335.085944 -51.176936)
			(xy 335.086443 -51.193586) (xy 335.095071 -51.225748) (xy 335.111729 -51.254581) (xy 335.135283 -51.278119)
			(xy 335.164127 -51.29476) (xy 335.196294 -51.303367) (xy 335.212944 -51.303936) (xy 353.846892 -51.303936)
			(xy 353.863543 -51.303394) (xy 353.89571 -51.294778) (xy 353.924553 -51.278131) (xy 353.948104 -51.254588)
			(xy 353.964761 -51.225751) (xy 353.973388 -51.193587) (xy 353.973892 -51.176936) (xy 353.973892 -50.8)
			(xy 353.97439 -50.73666) (xy 353.982344 -50.610231) (xy 353.998221 -50.48455) (xy 354.021958 -50.360114)
			(xy 354.053462 -50.237415) (xy 354.092608 -50.116935) (xy 354.139242 -49.999151) (xy 354.193179 -49.884528)
			(xy 354.254207 -49.773518) (xy 354.322085 -49.666559) (xy 354.396545 -49.564073) (xy 354.477294 -49.466464)
			(xy 354.564012 -49.374119) (xy 354.656357 -49.2874) (xy 354.753965 -49.206652) (xy 354.856451 -49.132191)
			(xy 354.96341 -49.064312) (xy 355.074419 -49.003284) (xy 355.189042 -48.949346) (xy 355.306826 -48.902711)
			(xy 355.427305 -48.863565) (xy 355.550005 -48.83206) (xy 355.67444 -48.808322) (xy 355.800121 -48.792445)
			(xy 355.92655 -48.78449) (xy 355.98989 -48.784002) (xy 370.98986 -48.784002) (xy 371.053201 -48.784488)
			(xy 371.179632 -48.79244) (xy 371.305315 -48.808315) (xy 371.429753 -48.832051) (xy 371.552456 -48.863553)
			(xy 371.672938 -48.902698) (xy 371.790724 -48.949331) (xy 371.905349 -49.003268) (xy 372.016362 -49.064296)
			(xy 372.123324 -49.132174) (xy 372.225812 -49.206634) (xy 372.323423 -49.287383) (xy 372.415771 -49.374101)
			(xy 372.502491 -49.466447) (xy 372.583242 -49.564056) (xy 372.657704 -49.666543) (xy 372.725584 -49.773503)
			(xy 372.786614 -49.884515) (xy 372.840553 -49.99914) (xy 372.887188 -50.116925) (xy 372.926335 -50.237406)
			(xy 372.95784 -50.360107) (xy 372.981578 -50.484545) (xy 372.997456 -50.610228) (xy 373.00541 -50.736659)
			(xy 373.005858 -50.8) (xy 373.005858 -51.176936) (xy 373.006405 -51.193583) (xy 373.015029 -51.225742)
			(xy 373.031678 -51.254575) (xy 373.055221 -51.278118) (xy 373.084053 -51.294769) (xy 373.116211 -51.303394)
			(xy 373.132858 -51.303936) (xy 379.856238 -51.303936) (xy 379.873605 -51.303407) (xy 379.907053 -51.294041)
			(xy 379.936727 -51.275988) (xy 379.960422 -51.250591) (xy 379.976376 -51.219737) (xy 379.980444 -51.202844)
			(xy 379.990096 -51.156616) (xy 380.124716 -50.580036) (xy 380.687326 -49.756568) (xy 380.899924 -49.716436)
			(xy 381.218948 -49.506124) (xy 381.891286 -49.374044) (xy 425.61002 -49.374044) (xy 425.655489 -49.373518)
			(xy 425.746038 -49.365126) (xy 425.835427 -49.348415) (xy 425.922893 -49.323528) (xy 426.00769 -49.290677)
			(xy 426.089094 -49.250143) (xy 426.166411 -49.202271) (xy 426.238981 -49.147469) (xy 426.306186 -49.086206)
			(xy 426.367451 -49.019003) (xy 426.422255 -48.946434) (xy 426.470129 -48.869119) (xy 426.510666 -48.787716)
			(xy 426.543519 -48.70292) (xy 426.568409 -48.615455) (xy 426.585122 -48.526066) (xy 426.593517 -48.435517)
			(xy 426.594016 -48.390048) (xy 426.594016 -44.114212) (xy 426.594098 -44.084986) (xy 426.595748 -44.026556)
			(xy 426.597318 -43.997372) (xy 426.597572 -43.993816) (xy 426.597572 -42.65549) (xy 426.48632 -42.544238)
			(xy 426.443394 -42.544238) (xy 426.4152 -42.516044) (xy 424.589194 -42.516044) (xy 423.994072 -41.920922)
			(xy 423.994072 -30.484064) (xy 426.4406 -30.484064) (xy 426.457253 -30.483569) (xy 426.489424 -30.474948)
			(xy 426.518266 -30.458292) (xy 426.541814 -30.434737) (xy 426.558461 -30.40589) (xy 426.567074 -30.373717)
			(xy 426.5676 -30.357064) (xy 426.5676 -10.3378) (xy 427.4058 -9.4996) (xy 427.666912 -9.4996) (xy 427.683559 -9.499055)
			(xy 427.715719 -9.490436) (xy 427.744552 -9.473786) (xy 427.768094 -9.450242) (xy 427.78474 -9.421408)
			(xy 427.793357 -9.389247) (xy 427.793912 -9.3726) (xy 427.793912 -7.493) (xy 427.793369 -7.476351)
			(xy 427.784751 -7.444188) (xy 427.768103 -7.41535) (xy 427.744559 -7.391804) (xy 427.715723 -7.375153)
			(xy 427.683561 -7.366533) (xy 427.666912 -7.366) (xy 427.47565 -7.366) (xy 427.425612 -7.38886) (xy 427.407578 -7.409434)
			(xy 427.346821 -7.478122) (xy 427.220036 -7.610646) (xy 427.087473 -7.73739) (xy 426.949395 -7.858102)
			(xy 426.806076 -7.972543) (xy 426.657801 -8.080485) (xy 426.504865 -8.181715) (xy 426.347571 -8.27603)
			(xy 426.186231 -8.363245) (xy 426.021166 -8.443185) (xy 425.852703 -8.515693) (xy 425.681177 -8.580623)
			(xy 425.50693 -8.637847) (xy 425.330305 -8.687252) (xy 425.151655 -8.728739) (xy 424.971335 -8.762226)
			(xy 424.789701 -8.787646) (xy 424.607115 -8.804949) (xy 424.42394 -8.814101) (xy 424.240539 -8.815084)
			(xy 424.057276 -8.807894) (xy 423.874515 -8.792548) (xy 423.783506 -8.781288) (xy 423.692878 -8.769085)
			(xy 423.512711 -8.737647) (xy 423.334119 -8.698235) (xy 423.157454 -8.650927) (xy 422.983065 -8.595818)
			(xy 422.811297 -8.533016) (xy 422.642489 -8.462644) (xy 422.476973 -8.384843) (xy 422.315078 -8.299765)
			(xy 422.157122 -8.207578) (xy 422.003417 -8.108465) (xy 421.854268 -8.002621) (xy 421.709968 -7.890256)
			(xy 421.570803 -7.771591) (xy 421.437046 -7.64686) (xy 421.308964 -7.51631) (xy 421.186808 -7.380198)
			(xy 421.070819 -7.238794) (xy 420.961227 -7.092377) (xy 420.858248 -6.941235) (xy 420.762085 -6.785668)
			(xy 420.672929 -6.625982) (xy 420.590955 -6.462493) (xy 420.516326 -6.295523) (xy 420.449187 -6.125403)
			(xy 420.389674 -5.952468) (xy 420.337901 -5.777059) (xy 420.293973 -5.599524) (xy 420.257976 -5.420213)
			(xy 420.22998 -5.239479) (xy 420.210041 -5.05768) (xy 420.198199 -4.875174) (xy 420.194476 -4.692323)
			(xy 420.198881 -4.509487) (xy 420.211404 -4.327027) (xy 420.232021 -4.145304) (xy 420.260691 -3.964676)
			(xy 420.297357 -3.7855) (xy 420.341947 -3.60813) (xy 420.394373 -3.432916) (xy 420.454532 -3.260204)
			(xy 420.522304 -3.090335) (xy 420.597556 -2.923645) (xy 420.680139 -2.760463) (xy 420.769891 -2.60111)
			(xy 420.866633 -2.445903) (xy 420.970175 -2.295146) (xy 421.080313 -2.149139) (xy 421.196828 -2.008169)
			(xy 421.319491 -1.872514) (xy 421.44806 -1.742443) (xy 421.58228 -1.618212) (xy 421.721887 -1.500066)
			(xy 421.793924 -1.443736) (xy 421.817292 -1.425702) (xy 421.8432 -1.37287) (xy 421.8432 -1.143) (xy 421.842657 -1.126352)
			(xy 421.834039 -1.094189) (xy 421.817391 -1.065354) (xy 421.793846 -1.041809) (xy 421.765011 -1.025161)
			(xy 421.732848 -1.016543) (xy 421.7162 -1.016) (xy 388.38505 -1.016) (xy 388.369624 -1.016428) (xy 388.339676 -1.023838)
			(xy 388.31239 -1.038234) (xy 388.289368 -1.058771) (xy 388.271963 -1.084244) (xy 388.266178 -1.09855)
			(xy 388.260597 -1.113105) (xy 388.247374 -1.141335) (xy 388.239762 -1.154938) (xy 388.222998 -1.184402)
			(xy 388.222998 -1.218184) (xy 388.223491 -1.23484) (xy 388.232109 -1.267018) (xy 388.248763 -1.295869)
			(xy 388.272316 -1.319426) (xy 388.301165 -1.336084) (xy 388.333342 -1.344707) (xy 388.349998 -1.345184)
			(xy 388.531862 -1.345184) (xy 395.236446 -1.345184) (xy 396.531846 -1.345184) (xy 396.531846 -4.21386)
			(xy 395.236446 -4.21386) (xy 395.236446 -1.345184) (xy 388.531862 -1.345184) (xy 388.531862 -2.699512)
			(xy 393.23645 -2.699512) (xy 394.53185 -2.699512) (xy 394.53185 -5.468112) (xy 393.23645 -5.468112)
			(xy 393.23645 -2.699512) (xy 388.531862 -2.699512) (xy 388.531862 -4.21386) (xy 387.236462 -4.21386)
			(xy 387.236462 -1.345184) (xy 387.467602 -1.345184) (xy 387.484256 -1.344689) (xy 387.516428 -1.336067)
			(xy 387.545273 -1.319412) (xy 387.568823 -1.295858) (xy 387.585474 -1.267012) (xy 387.594091 -1.234838)
			(xy 387.594602 -1.218184) (xy 387.594602 -1.184402) (xy 387.577838 -1.154938) (xy 387.570235 -1.14133)
			(xy 387.557007 -1.113103) (xy 387.551422 -1.09855) (xy 387.545609 -1.084262) (xy 387.528179 -1.058822)
			(xy 387.50516 -1.0383) (xy 387.477893 -1.023895) (xy 387.447968 -1.016444) (xy 387.43255 -1.016)
			(xy 120.966484 -1.016) (xy 120.899428 -1.065276) (xy 120.886982 -1.1049) (xy 120.877962 -1.131873)
			(xy 120.853056 -1.183002) (xy 120.820837 -1.229868) (xy 120.782017 -1.271431) (xy 120.737457 -1.306771)
			(xy 120.688145 -1.335104) (xy 120.662349 -1.345184) (xy 166.236396 -1.345184) (xy 167.531796 -1.345184)
			(xy 174.23638 -1.345184) (xy 175.53178 -1.345184) (xy 175.53178 -4.21386) (xy 174.23638 -4.21386)
			(xy 174.23638 -1.345184) (xy 167.531796 -1.345184) (xy 167.531796 -2.699512) (xy 172.236384 -2.699512)
			(xy 173.531784 -2.699512) (xy 173.531784 -5.468112) (xy 172.236384 -5.468112) (xy 172.236384 -2.699512)
			(xy 167.531796 -2.699512) (xy 167.531796 -4.21386) (xy 166.236396 -4.21386) (xy 166.236396 -1.345184)
			(xy 120.662349 -1.345184) (xy 120.635173 -1.355803) (xy 120.579715 -1.368409) (xy 120.523 -1.372642)
			(xy 120.466285 -1.368409) (xy 120.410827 -1.355803) (xy 120.357855 -1.335104) (xy 120.308543 -1.306771)
			(xy 120.263983 -1.271431) (xy 120.225163 -1.229868) (xy 120.192944 -1.183002) (xy 120.168038 -1.131873)
			(xy 120.159018 -1.1049) (xy 120.153734 -1.089679) (xy 120.136678 -1.062356) (xy 120.11332 -1.040178)
			(xy 120.08515 -1.02456) (xy 120.053965 -1.016499) (xy 120.03786 -1.016) (xy 7.1628 -1.016) (xy 7.146152 -1.016543)
			(xy 7.113989 -1.025161) (xy 7.085154 -1.041809) (xy 7.061609 -1.065354) (xy 7.044961 -1.094189) (xy 7.036343 -1.126352)
			(xy 7.0358 -1.143) (xy 7.0358 -1.385062) (xy 7.060946 -1.436878) (xy 7.083806 -1.455166) (xy 7.154537 -1.512123)
			(xy 7.291525 -1.631375) (xy 7.423162 -1.756509) (xy 7.549195 -1.887285) (xy 7.669383 -2.023453) (xy 7.783495 -2.164751)
			(xy 7.891313 -2.310909) (xy 7.992629 -2.461646) (xy 8.087251 -2.616673) (xy 8.13296 -2.699512) (xy 164.2364 -2.699512)
			(xy 165.5318 -2.699512) (xy 165.5318 -5.468112) (xy 164.2364 -5.468112) (xy 164.2364 -2.699512) (xy 8.13296 -2.699512)
			(xy 8.174996 -2.775694) (xy 8.255695 -2.938403) (xy 8.329196 -3.104489) (xy 8.395355 -3.273633) (xy 8.454048 -3.445511)
			(xy 8.50516 -3.619793) (xy 8.548595 -3.796145) (xy 8.584269 -3.97423) (xy 8.612113 -4.153706) (xy 8.632074 -4.334228)
			(xy 8.644115 -4.515451) (xy 8.648211 -4.697027) (xy 8.644355 -4.878609) (xy 8.632554 -5.059848) (xy 8.612832 -5.240396)
			(xy 8.585225 -5.419909) (xy 8.549787 -5.59804) (xy 8.506585 -5.77445) (xy 8.502586 -5.788152) (xy 101.226874 -5.788152)
			(xy 101.226874 -5.367528) (xy 101.524562 -5.06984) (xy 103.215186 -5.06984) (xy 103.512874 -5.367528)
			(xy 103.512874 -5.4356) (xy 132.4102 -5.4356) (xy 132.4102 -3.7592) (xy 132.7404 -3.429) (xy 133.1214 -3.429)
			(xy 133.4262 -3.7338) (xy 133.4262 -5.4356) (xy 133.1214 -5.7404) (xy 132.715 -5.7404) (xy 132.4102 -5.4356)
			(xy 103.512874 -5.4356) (xy 103.512874 -5.574538) (xy 127.80518 -5.574538) (xy 129.25298 -5.574538)
			(xy 129.25298 -5.9182) (xy 143.9418 -5.9182) (xy 143.9418 -5.5118) (xy 144.272 -5.1816) (xy 145.923 -5.1816)
			(xy 146.2278 -5.4864) (xy 146.2278 -5.545328) (xy 166.236396 -5.545328) (xy 167.531796 -5.545328)
			(xy 170.236388 -5.545328) (xy 171.531788 -5.545328) (xy 174.23638 -5.545328) (xy 175.53178 -5.545328)
			(xy 175.53178 -8.414004) (xy 174.23638 -8.414004) (xy 174.23638 -5.545328) (xy 171.531788 -5.545328)
			(xy 171.531788 -6.899656) (xy 172.236384 -6.899656) (xy 173.531784 -6.899656) (xy 173.531784 -9.668256)
			(xy 172.236384 -9.668256) (xy 172.236384 -6.899656) (xy 171.531788 -6.899656) (xy 171.531788 -8.414004)
			(xy 170.236388 -8.414004) (xy 170.236388 -5.545328) (xy 167.531796 -5.545328) (xy 167.531796 -6.899656)
			(xy 168.236392 -6.899656) (xy 169.531792 -6.899656) (xy 169.531792 -9.668256) (xy 168.236392 -9.668256)
			(xy 168.236392 -6.899656) (xy 167.531796 -6.899656) (xy 167.531796 -8.414004) (xy 166.236396 -8.414004)
			(xy 166.236396 -5.545328) (xy 146.2278 -5.545328) (xy 146.2278 -5.9436) (xy 145.9484 -6.223) (xy 144.2466 -6.223)
			(xy 143.9418 -5.9182) (xy 129.25298 -5.9182) (xy 129.25298 -6.899656) (xy 164.2364 -6.899656) (xy 165.5318 -6.899656)
			(xy 165.5318 -9.668256) (xy 164.2364 -9.668256) (xy 164.2364 -6.899656) (xy 129.25298 -6.899656)
			(xy 129.25298 -8.393938) (xy 127.80518 -8.393938) (xy 127.80518 -5.574538) (xy 103.512874 -5.574538)
			(xy 103.512874 -5.788152) (xy 103.215186 -6.08584) (xy 101.524562 -6.08584) (xy 101.226874 -5.788152)
			(xy 8.502586 -5.788152) (xy 8.455703 -5.9488) (xy 8.397238 -6.120755) (xy 8.331302 -6.289986) (xy 8.258021 -6.456169)
			(xy 8.177537 -6.618985) (xy 8.090002 -6.778121) (xy 7.995586 -6.933274) (xy 7.894469 -7.084145) (xy 7.786844 -7.230445)
			(xy 7.672919 -7.371894) (xy 7.560048 -7.500112) (xy 9.403341 -7.500112) (xy 9.407346 -7.412204) (xy 9.419329 -7.325024)
			(xy 9.439189 -7.239295) (xy 9.466764 -7.155727) (xy 9.501823 -7.075013) (xy 9.544076 -6.997821) (xy 9.593174 -6.924792)
			(xy 9.64871 -6.85653) (xy 9.710222 -6.7936) (xy 9.777203 -6.736526) (xy 9.849096 -6.685778) (xy 9.925305 -6.641778)
			(xy 10.0052 -6.604891) (xy 10.088119 -6.575422) (xy 10.173374 -6.553615) (xy 10.260258 -6.539651)
			(xy 10.348052 -6.533645) (xy 10.436029 -6.535649) (xy 10.523459 -6.545644) (xy 10.609618 -6.563548)
			(xy 10.693792 -6.589212) (xy 10.775283 -6.622425) (xy 10.853417 -6.662911) (xy 10.927545 -6.710333)
			(xy 10.997053 -6.7643) (xy 11.061367 -6.824365) (xy 11.106105 -6.87451) (xy 117.8052 -6.87451) (xy 119.253 -6.87451)
			(xy 119.253 -9.0678) (xy 139.3698 -9.0678) (xy 141.1986 -9.0678) (xy 144.169892 -9.0678) (xy 145.998692 -9.0678)
			(xy 145.998692 -9.745472) (xy 166.236396 -9.745472) (xy 167.531796 -9.745472) (xy 170.236388 -9.745472)
			(xy 171.531788 -9.745472) (xy 174.23638 -9.745472) (xy 175.53178 -9.745472) (xy 175.53178 -10.636885)
			(xy 195.033965 -10.636885) (xy 195.040797 -10.457527) (xy 195.055635 -10.278653) (xy 195.07845 -10.100621)
			(xy 195.109196 -9.923786) (xy 195.147811 -9.7485) (xy 195.194219 -9.575116) (xy 195.248327 -9.403977)
			(xy 195.310026 -9.235427) (xy 195.379194 -9.069801) (xy 195.455693 -8.907431) (xy 195.539369 -8.748641)
			(xy 195.630055 -8.593748) (xy 195.727571 -8.443061) (xy 195.831722 -8.296881) (xy 195.9423 -8.1555)
			(xy 196.059083 -8.0192) (xy 196.181839 -7.888254) (xy 196.245734 -7.825232) (xy 196.257486 -7.813044)
			(xy 196.274658 -7.783878) (xy 196.283558 -7.751223) (xy 196.284088 -7.7343) (xy 196.284088 -4.750308)
			(xy 196.284088 -4.649216) (xy 196.284088 -4.48691) (xy 196.291962 -4.479036) (xy 196.296534 -4.43357)
			(xy 196.304123 -4.360068) (xy 196.326196 -4.213943) (xy 196.356041 -4.069205) (xy 196.393572 -3.926267)
			(xy 196.438681 -3.785538) (xy 196.491241 -3.647417) (xy 196.551101 -3.512301) (xy 196.61809 -3.380573)
			(xy 196.692017 -3.25261) (xy 196.772672 -3.128777) (xy 196.859824 -3.009428) (xy 196.953225 -2.894903)
			(xy 197.052607 -2.785528) (xy 197.157688 -2.681616) (xy 197.268168 -2.583463) (xy 197.383731 -2.491349)
			(xy 197.504048 -2.405538) (xy 197.628775 -2.326273) (xy 197.757556 -2.253782) (xy 197.890025 -2.18827)
			(xy 198.025803 -2.129926) (xy 198.164503 -2.078914) (xy 198.305728 -2.035382) (xy 198.449077 -1.999452)
			(xy 198.594139 -1.971229) (xy 198.740502 -1.950791) (xy 198.887747 -1.938198) (xy 199.035455 -1.933485)
			(xy 199.183203 -1.936666) (xy 199.330571 -1.947731) (xy 199.477138 -1.96665) (xy 199.622485 -1.993368)
			(xy 199.766199 -2.027809) (xy 199.907868 -2.069875) (xy 200.047089 -2.119445) (xy 200.183465 -2.176379)
			(xy 200.316606 -2.240513) (xy 200.446132 -2.311665) (xy 200.571675 -2.389632) (xy 200.692875 -2.474191)
			(xy 200.809387 -2.565101) (xy 200.920879 -2.662103) (xy 201.027031 -2.76492) (xy 201.127543 -2.873258)
			(xy 201.222126 -2.986809) (xy 201.310511 -3.105248) (xy 201.392445 -3.228238) (xy 201.467696 -3.355427)
			(xy 201.536048 -3.486453) (xy 201.597305 -3.620942) (xy 201.651294 -3.75851) (xy 201.697861 -3.898764)
			(xy 201.736872 -4.041305) (xy 201.768216 -4.185725) (xy 201.791804 -4.331613) (xy 201.807568 -4.478553)
			(xy 201.815463 -4.626125) (xy 201.815954 -4.700016) (xy 201.815954 -7.7343) (xy 201.816506 -7.751221)
			(xy 201.825401 -7.783872) (xy 201.842565 -7.813038) (xy 201.854308 -7.825232) (xy 201.918203 -7.888254)
			(xy 202.040959 -8.0192) (xy 202.157742 -8.1555) (xy 202.26832 -8.296881) (xy 202.372471 -8.443061)
			(xy 202.469987 -8.593748) (xy 202.560673 -8.748641) (xy 202.644349 -8.907431) (xy 202.720848 -9.069801)
			(xy 202.790016 -9.235427) (xy 202.851715 -9.403977) (xy 202.905823 -9.575116) (xy 202.952231 -9.7485)
			(xy 202.990846 -9.923786) (xy 203.021592 -10.100621) (xy 203.044407 -10.278653) (xy 203.059245 -10.457527)
			(xy 203.066067 -10.636631) (xy 275.794027 -10.636631) (xy 275.800859 -10.457273) (xy 275.815697 -10.278399)
			(xy 275.838512 -10.100367) (xy 275.869258 -9.923532) (xy 275.907873 -9.748246) (xy 275.954281 -9.574862)
			(xy 276.008389 -9.403723) (xy 276.070088 -9.235173) (xy 276.139256 -9.069547) (xy 276.215755 -8.907177)
			(xy 276.299431 -8.748387) (xy 276.390117 -8.593494) (xy 276.487633 -8.442807) (xy 276.591784 -8.296627)
			(xy 276.702362 -8.155246) (xy 276.819145 -8.018946) (xy 276.941901 -7.888) (xy 277.005796 -7.824978)
			(xy 277.017567 -7.812806) (xy 277.034736 -7.783633) (xy 277.043626 -7.750971) (xy 277.04415 -7.734046)
			(xy 277.04415 -4.750054) (xy 277.04415 -4.648962) (xy 277.04415 -4.486656) (xy 277.052024 -4.478782)
			(xy 277.056596 -4.433316) (xy 277.064254 -4.359821) (xy 277.086325 -4.213696) (xy 277.116168 -4.068958)
			(xy 277.153696 -3.92602) (xy 277.198803 -3.78529) (xy 277.251361 -3.647169) (xy 277.311218 -3.512052)
			(xy 277.378206 -3.380324) (xy 277.452131 -3.25236) (xy 277.532784 -3.128527) (xy 277.619935 -3.009177)
			(xy 277.713334 -2.89465) (xy 277.812715 -2.785275) (xy 277.917794 -2.681362) (xy 278.028273 -2.583208)
			(xy 278.143835 -2.491094) (xy 278.264151 -2.405282) (xy 278.388877 -2.326016) (xy 278.517658 -2.253524)
			(xy 278.650126 -2.188012) (xy 278.785903 -2.129667) (xy 278.924602 -2.078655) (xy 279.065827 -2.035122)
			(xy 279.209175 -1.999192) (xy 279.354237 -1.970967) (xy 279.5006 -1.950529) (xy 279.647844 -1.937936)
			(xy 279.795552 -1.933223) (xy 279.9433 -1.936403) (xy 280.090667 -1.947469) (xy 280.237234 -1.966388)
			(xy 280.382581 -1.993106) (xy 280.526294 -2.027547) (xy 280.667963 -2.069613) (xy 280.807183 -2.119183)
			(xy 280.943558 -2.176117) (xy 281.076699 -2.240252) (xy 281.206225 -2.311404) (xy 281.331766 -2.389372)
			(xy 281.452966 -2.473931) (xy 281.569477 -2.564842) (xy 281.680968 -2.661845) (xy 281.719856 -2.699512)
			(xy 385.236466 -2.699512) (xy 386.531866 -2.699512) (xy 386.531866 -5.468112) (xy 385.236466 -5.468112)
			(xy 385.236466 -2.699512) (xy 281.719856 -2.699512) (xy 281.787119 -2.764662) (xy 281.88763 -2.873001)
			(xy 281.982212 -2.986552) (xy 282.070595 -3.104992) (xy 282.152528 -3.227982) (xy 282.227777 -3.355172)
			(xy 282.296127 -3.486198) (xy 282.357383 -3.620687) (xy 282.411371 -3.758256) (xy 282.457935 -3.89851)
			(xy 282.496944 -4.041051) (xy 282.528286 -4.185472) (xy 282.551872 -4.33136) (xy 282.567633 -4.478299)
			(xy 282.575527 -4.625871) (xy 282.576016 -4.699762) (xy 282.576016 -5.7912) (xy 322.2244 -5.7912)
			(xy 322.2244 -5.3848) (xy 322.5546 -5.0546) (xy 324.231 -5.0546) (xy 324.5104 -5.334) (xy 324.5104 -5.461)
			(xy 353.4156 -5.461) (xy 353.4156 -3.7592) (xy 353.7458 -3.429) (xy 354.1268 -3.429) (xy 354.4316 -3.7338)
			(xy 354.4316 -5.4356) (xy 354.1268 -5.7404) (xy 353.695 -5.7404) (xy 353.4156 -5.461) (xy 324.5104 -5.461)
			(xy 324.5104 -5.574538) (xy 348.805246 -5.574538) (xy 350.253046 -5.574538) (xy 350.253046 -5.9182)
			(xy 364.9472 -5.9182) (xy 364.9472 -5.5118) (xy 365.2774 -5.1816) (xy 366.903 -5.1816) (xy 367.2332 -5.5118)
			(xy 367.2332 -5.545328) (xy 387.236462 -5.545328) (xy 388.531862 -5.545328) (xy 391.236454 -5.545328)
			(xy 392.531854 -5.545328) (xy 395.236446 -5.545328) (xy 396.531846 -5.545328) (xy 396.531846 -8.414004)
			(xy 395.236446 -8.414004) (xy 395.236446 -5.545328) (xy 392.531854 -5.545328) (xy 392.531854 -6.899656)
			(xy 393.23645 -6.899656) (xy 394.53185 -6.899656) (xy 394.53185 -9.668256) (xy 393.23645 -9.668256)
			(xy 393.23645 -6.899656) (xy 392.531854 -6.899656) (xy 392.531854 -8.414004) (xy 391.236454 -8.414004)
			(xy 391.236454 -5.545328) (xy 388.531862 -5.545328) (xy 388.531862 -6.899656) (xy 389.236458 -6.899656)
			(xy 390.531858 -6.899656) (xy 390.531858 -9.668256) (xy 389.236458 -9.668256) (xy 389.236458 -6.899656)
			(xy 388.531862 -6.899656) (xy 388.531862 -8.414004) (xy 387.236462 -8.414004) (xy 387.236462 -5.545328)
			(xy 367.2332 -5.545328) (xy 367.2332 -5.9436) (xy 366.9538 -6.223) (xy 365.252 -6.223) (xy 364.9472 -5.9182)
			(xy 350.253046 -5.9182) (xy 350.253046 -6.899656) (xy 385.236466 -6.899656) (xy 386.531866 -6.899656)
			(xy 386.531866 -9.668256) (xy 385.236466 -9.668256) (xy 385.236466 -6.899656) (xy 350.253046 -6.899656)
			(xy 350.253046 -8.393938) (xy 348.805246 -8.393938) (xy 348.805246 -5.574538) (xy 324.5104 -5.574538)
			(xy 324.5104 -5.7912) (xy 324.2056 -6.096) (xy 322.5292 -6.096) (xy 322.2244 -5.7912) (xy 282.576016 -5.7912)
			(xy 282.576016 -6.87451) (xy 338.805266 -6.87451) (xy 340.253066 -6.87451) (xy 340.253066 -9.067546)
			(xy 360.369866 -9.067546) (xy 362.198666 -9.067546) (xy 365.169958 -9.067546) (xy 366.998758 -9.067546)
			(xy 366.998758 -9.745472) (xy 387.236462 -9.745472) (xy 388.531862 -9.745472) (xy 391.236454 -9.745472)
			(xy 392.531854 -9.745472) (xy 395.236446 -9.745472) (xy 396.531846 -9.745472) (xy 396.531846 -12.614148)
			(xy 395.236446 -12.614148) (xy 395.236446 -9.745472) (xy 392.531854 -9.745472) (xy 392.531854 -11.0998)
			(xy 393.23645 -11.0998) (xy 394.53185 -11.0998) (xy 394.53185 -13.8684) (xy 393.23645 -13.8684) (xy 393.23645 -11.0998)
			(xy 392.531854 -11.0998) (xy 392.531854 -12.614148) (xy 391.236454 -12.614148) (xy 391.236454 -9.745472)
			(xy 388.531862 -9.745472) (xy 388.531862 -11.0998) (xy 389.236458 -11.0998) (xy 390.531858 -11.0998)
			(xy 390.531858 -13.8684) (xy 389.236458 -13.8684) (xy 389.236458 -11.0998) (xy 388.531862 -11.0998)
			(xy 388.531862 -12.614148) (xy 387.236462 -12.614148) (xy 387.236462 -9.745472) (xy 366.998758 -9.745472)
			(xy 366.998758 -11.0998) (xy 385.236466 -11.0998) (xy 386.531866 -11.0998) (xy 386.531866 -13.8684)
			(xy 385.236466 -13.8684) (xy 385.236466 -11.0998) (xy 366.998758 -11.0998) (xy 366.998758 -11.505946)
			(xy 365.169958 -11.505946) (xy 365.169958 -9.067546) (xy 362.198666 -9.067546) (xy 362.198666 -11.505946)
			(xy 360.369866 -11.505946) (xy 360.369866 -9.067546) (xy 340.253066 -9.067546) (xy 340.253066 -9.69391)
			(xy 338.805266 -9.69391) (xy 338.805266 -6.87451) (xy 282.576016 -6.87451) (xy 282.576016 -7.734046)
			(xy 282.576552 -7.750968) (xy 282.585456 -7.783619) (xy 282.602625 -7.812784) (xy 282.61437 -7.824978)
			(xy 282.678265 -7.888) (xy 282.801021 -8.018946) (xy 282.917804 -8.155246) (xy 283.028382 -8.296627)
			(xy 283.132533 -8.442807) (xy 283.230049 -8.593494) (xy 283.320735 -8.748387) (xy 283.404411 -8.907177)
			(xy 283.48091 -9.069547) (xy 283.550078 -9.235173) (xy 283.611777 -9.403723) (xy 283.659262 -9.553914)
			(xy 308.833762 -9.553914) (xy 308.833762 -9.445286) (xy 308.841691 -9.336948) (xy 308.857508 -9.229477)
			(xy 308.881127 -9.123448) (xy 308.912423 -9.019426) (xy 308.951228 -8.917965) (xy 308.997336 -8.819608)
			(xy 309.0505 -8.724879) (xy 309.110438 -8.634284) (xy 309.176828 -8.548305) (xy 309.249318 -8.467402)
			(xy 309.327519 -8.392006) (xy 309.411016 -8.32252) (xy 309.499362 -8.259313) (xy 309.592086 -8.202725)
			(xy 309.688694 -8.153055) (xy 309.788669 -8.11057) (xy 309.891479 -8.075497) (xy 309.996575 -8.048021)
			(xy 310.103396 -8.02829) (xy 310.211372 -8.016409) (xy 310.319928 -8.012442) (xy 310.428484 -8.016409)
			(xy 310.53646 -8.02829) (xy 310.643281 -8.048021) (xy 310.748377 -8.075497) (xy 310.851187 -8.11057)
			(xy 310.951162 -8.153055) (xy 311.04777 -8.202725) (xy 311.140494 -8.259313) (xy 311.22884 -8.32252)
			(xy 311.312337 -8.392006) (xy 311.390538 -8.467402) (xy 311.463028 -8.548305) (xy 311.529418 -8.634284)
			(xy 311.589356 -8.724879) (xy 311.64252 -8.819608) (xy 311.688628 -8.917965) (xy 311.727433 -9.019426)
			(xy 311.741987 -9.0678) (xy 322.449698 -9.0678) (xy 324.278498 -9.0678) (xy 327.24979 -9.0678) (xy 329.07859 -9.0678)
			(xy 329.07859 -9.398) (xy 334.2386 -9.398) (xy 334.2386 -8.9916) (xy 334.5434 -8.6868) (xy 336.3976 -8.6868)
			(xy 336.7024 -8.9916) (xy 336.7024 -9.398) (xy 336.3976 -9.7028) (xy 334.5434 -9.7028) (xy 334.2386 -9.398)
			(xy 329.07859 -9.398) (xy 329.07859 -9.774428) (xy 348.805246 -9.774428) (xy 350.253046 -9.774428)
			(xy 350.253046 -12.593828) (xy 348.805246 -12.593828) (xy 348.805246 -9.774428) (xy 329.07859 -9.774428)
			(xy 329.07859 -11.0744) (xy 338.805266 -11.0744) (xy 340.253066 -11.0744) (xy 340.253066 -13.8938)
			(xy 338.805266 -13.8938) (xy 338.805266 -11.0744) (xy 329.07859 -11.0744) (xy 329.07859 -11.5062)
			(xy 327.24979 -11.5062) (xy 327.24979 -9.0678) (xy 324.278498 -9.0678) (xy 324.278498 -11.5062) (xy 322.449698 -11.5062)
			(xy 322.449698 -9.0678) (xy 311.741987 -9.0678) (xy 311.758729 -9.123448) (xy 311.782348 -9.229477)
			(xy 311.798165 -9.336948) (xy 311.806094 -9.445286) (xy 311.80659 -9.4996) (xy 311.806094 -9.553914)
			(xy 311.798165 -9.662252) (xy 311.782348 -9.769723) (xy 311.758729 -9.875752) (xy 311.727433 -9.979774)
			(xy 311.688628 -10.081235) (xy 311.64252 -10.179592) (xy 311.589356 -10.274321) (xy 311.529418 -10.364916)
			(xy 311.463028 -10.450895) (xy 311.390538 -10.531798) (xy 311.312337 -10.607194) (xy 311.22884 -10.67668)
			(xy 311.140494 -10.739887) (xy 311.04777 -10.796475) (xy 310.951162 -10.846145) (xy 310.851187 -10.88863)
			(xy 310.748377 -10.923703) (xy 310.643281 -10.951179) (xy 310.53646 -10.97091) (xy 310.428484 -10.982791)
			(xy 310.319928 -10.986758) (xy 310.211372 -10.982791) (xy 310.103396 -10.97091) (xy 309.996575 -10.951179)
			(xy 309.891479 -10.923703) (xy 309.788669 -10.88863) (xy 309.688694 -10.846145) (xy 309.592086 -10.796475)
			(xy 309.499362 -10.739887) (xy 309.411016 -10.67668) (xy 309.327519 -10.607194) (xy 309.249318 -10.531798)
			(xy 309.176828 -10.450895) (xy 309.110438 -10.364916) (xy 309.0505 -10.274321) (xy 308.997336 -10.179592)
			(xy 308.951228 -10.081235) (xy 308.912423 -9.979774) (xy 308.881127 -9.875752) (xy 308.857508 -9.769723)
			(xy 308.841691 -9.662252) (xy 308.833762 -9.553914) (xy 283.659262 -9.553914) (xy 283.665885 -9.574862)
			(xy 283.712293 -9.748246) (xy 283.750908 -9.923532) (xy 283.781654 -10.100367) (xy 283.804469 -10.278399)
			(xy 283.819307 -10.457273) (xy 283.826139 -10.636631) (xy 283.824952 -10.816115) (xy 283.815747 -10.995367)
			(xy 283.798542 -11.174029) (xy 283.773373 -11.351744) (xy 283.74029 -11.528157) (xy 283.699358 -11.702915)
			(xy 283.65066 -11.875671) (xy 283.594292 -12.046078) (xy 283.530368 -12.213797) (xy 283.459014 -12.378493)
			(xy 283.380373 -12.539836) (xy 283.294603 -12.697505) (xy 283.201875 -12.851185) (xy 283.102373 -13.000568)
			(xy 282.996297 -13.145357) (xy 282.883858 -13.285262) (xy 282.765281 -13.420005) (xy 282.640803 -13.549315)
			(xy 282.510672 -13.672935) (xy 282.375148 -13.790618) (xy 282.234501 -13.902129) (xy 282.089014 -14.007244)
			(xy 281.938975 -14.105755) (xy 281.784685 -14.197465) (xy 281.626452 -14.28219) (xy 281.464592 -14.359761)
			(xy 281.299428 -14.430023) (xy 281.274705 -14.439259) (xy 319.550021 -14.439259) (xy 319.550021 -14.340973)
			(xy 319.55793 -14.243006) (xy 319.573696 -14.145993) (xy 319.597217 -14.050564) (xy 319.628341 -13.957336)
			(xy 319.666866 -13.866915) (xy 319.712541 -13.779888) (xy 319.765072 -13.696817) (xy 319.824116 -13.618244)
			(xy 319.889291 -13.544676) (xy 319.960175 -13.476591) (xy 320.036308 -13.41443) (xy 320.117195 -13.358598)
			(xy 320.202313 -13.309455) (xy 320.29111 -13.267321) (xy 320.383008 -13.232468) (xy 320.477414 -13.205123)
			(xy 320.573713 -13.185464) (xy 320.671282 -13.173617) (xy 320.769488 -13.169659) (xy 320.867694 -13.173617)
			(xy 320.965263 -13.185464) (xy 321.061562 -13.205123) (xy 321.155968 -13.232468) (xy 321.247866 -13.267321)
			(xy 321.336663 -13.309455) (xy 321.421781 -13.358598) (xy 321.502668 -13.41443) (xy 321.578801 -13.476591)
			(xy 321.649685 -13.544676) (xy 321.71486 -13.618244) (xy 321.773904 -13.696817) (xy 321.826435 -13.779888)
			(xy 321.87211 -13.866915) (xy 321.910635 -13.957336) (xy 321.941759 -14.050564) (xy 321.944064 -14.059916)
			(xy 329.480926 -14.059916) (xy 329.481436 -14.017565) (xy 329.489498 -13.933249) (xy 329.505539 -13.85008)
			(xy 329.529411 -13.768812) (xy 329.5609 -13.690182) (xy 329.59972 -13.6149) (xy 329.645519 -13.543649)
			(xy 329.697884 -13.477073) (xy 329.756339 -13.415776) (xy 329.820356 -13.360313) (xy 329.889354 -13.311185)
			(xy 329.96271 -13.268838) (xy 330.039758 -13.233655) (xy 330.119802 -13.205954) (xy 330.202116 -13.185987)
			(xy 330.285956 -13.173933) (xy 330.370561 -13.169903) (xy 330.455166 -13.173933) (xy 330.539006 -13.185987)
			(xy 330.62132 -13.205954) (xy 330.701364 -13.233655) (xy 330.778412 -13.268838) (xy 330.851768 -13.311185)
			(xy 330.920766 -13.360313) (xy 330.984783 -13.415776) (xy 331.043238 -13.477073) (xy 331.095603 -13.543649)
			(xy 331.141402 -13.6149) (xy 331.180222 -13.690182) (xy 331.211711 -13.768812) (xy 331.235583 -13.85008)
			(xy 331.251624 -13.933249) (xy 331.259686 -14.017565) (xy 331.260196 -14.059916) (xy 331.260196 -14.439005)
			(xy 357.470189 -14.439005) (xy 357.470189 -14.340719) (xy 357.478098 -14.242752) (xy 357.493864 -14.145739)
			(xy 357.517385 -14.05031) (xy 357.548509 -13.957082) (xy 357.587034 -13.866661) (xy 357.632709 -13.779634)
			(xy 357.68524 -13.696563) (xy 357.744284 -13.61799) (xy 357.809459 -13.544422) (xy 357.880343 -13.476337)
			(xy 357.956476 -13.414176) (xy 358.037363 -13.358344) (xy 358.122481 -13.309201) (xy 358.211278 -13.267067)
			(xy 358.303176 -13.232214) (xy 358.397582 -13.204869) (xy 358.493881 -13.18521) (xy 358.59145 -13.173363)
			(xy 358.689656 -13.169405) (xy 358.787862 -13.173363) (xy 358.885431 -13.18521) (xy 358.98173 -13.204869)
			(xy 359.076136 -13.232214) (xy 359.168034 -13.267067) (xy 359.256831 -13.309201) (xy 359.341949 -13.358344)
			(xy 359.422836 -13.414176) (xy 359.498969 -13.476337) (xy 359.569853 -13.544422) (xy 359.635028 -13.61799)
			(xy 359.694072 -13.696563) (xy 359.746603 -13.779634) (xy 359.792278 -13.866661) (xy 359.830803 -13.957082)
			(xy 359.861927 -14.05031) (xy 359.885448 -14.145739) (xy 359.901214 -14.242752) (xy 359.909123 -14.340719)
			(xy 359.909618 -14.389862) (xy 359.909123 -14.439005) (xy 359.901214 -14.536972) (xy 359.885448 -14.633985)
			(xy 359.861927 -14.729414) (xy 359.856569 -14.745462) (xy 367.401348 -14.745462) (xy 367.401348 -14.059662)
			(xy 367.401852 -14.017314) (xy 367.409903 -13.933) (xy 367.425932 -13.849834) (xy 367.449793 -13.768567)
			(xy 367.481272 -13.689937) (xy 367.520083 -13.614656) (xy 367.565873 -13.543404) (xy 367.618229 -13.476828)
			(xy 367.676677 -13.41553) (xy 367.740687 -13.360065) (xy 367.809679 -13.310936) (xy 367.883029 -13.268587)
			(xy 367.960072 -13.233403) (xy 368.040111 -13.205701) (xy 368.12242 -13.185733) (xy 368.206255 -13.17368)
			(xy 368.290856 -13.16965) (xy 368.375457 -13.17368) (xy 368.459292 -13.185733) (xy 368.541601 -13.205701)
			(xy 368.62164 -13.233403) (xy 368.698683 -13.268587) (xy 368.772033 -13.310936) (xy 368.841025 -13.360065)
			(xy 368.905035 -13.41553) (xy 368.963483 -13.476828) (xy 369.015839 -13.543404) (xy 369.061629 -13.614656)
			(xy 369.10044 -13.689937) (xy 369.131919 -13.768567) (xy 369.15578 -13.849834) (xy 369.171809 -13.933)
			(xy 369.17986 -14.017314) (xy 369.180364 -14.059662) (xy 369.180364 -14.694662) (xy 369.179898 -14.73694)
			(xy 369.1721 -14.821134) (xy 369.156565 -14.90425) (xy 369.133428 -14.985578) (xy 369.102885 -15.064424)
			(xy 369.065196 -15.140115) (xy 369.020685 -15.212005) (xy 368.969729 -15.279482) (xy 368.912765 -15.341969)
			(xy 368.850277 -15.398933) (xy 368.7828 -15.449888) (xy 368.71091 -15.494399) (xy 368.635218 -15.532087)
			(xy 368.556372 -15.56263) (xy 368.475044 -15.585767) (xy 368.391928 -15.601301) (xy 368.307734 -15.609099)
			(xy 368.265456 -15.60957) (xy 368.223029 -15.609129) (xy 368.138583 -15.600808) (xy 368.05536 -15.584249)
			(xy 367.97416 -15.559613) (xy 367.895766 -15.527137) (xy 367.820933 -15.487133) (xy 367.750381 -15.439987)
			(xy 367.684791 -15.386153) (xy 367.624792 -15.326149) (xy 367.570964 -15.260553) (xy 367.523825 -15.189996)
			(xy 367.483828 -15.115159) (xy 367.451359 -15.036763) (xy 367.426731 -14.955561) (xy 367.41018 -14.872336)
			(xy 367.401867 -14.787889) (xy 367.401348 -14.745462) (xy 359.856569 -14.745462) (xy 359.830803 -14.822642)
			(xy 359.792278 -14.913063) (xy 359.746603 -15.000091) (xy 359.694072 -15.083161) (xy 359.635028 -15.161734)
			(xy 359.569853 -15.235302) (xy 359.498969 -15.303387) (xy 359.422836 -15.365548) (xy 359.341949 -15.42138)
			(xy 359.256831 -15.470523) (xy 359.168034 -15.512657) (xy 359.076136 -15.54751) (xy 358.98173 -15.574855)
			(xy 358.885431 -15.594514) (xy 358.787862 -15.606361) (xy 358.689656 -15.610319) (xy 358.59145 -15.606361)
			(xy 358.493881 -15.594514) (xy 358.397582 -15.574855) (xy 358.303176 -15.54751) (xy 358.211278 -15.512657)
			(xy 358.122481 -15.470523) (xy 358.037363 -15.42138) (xy 357.956476 -15.365548) (xy 357.880343 -15.303387)
			(xy 357.809459 -15.235302) (xy 357.744284 -15.161734) (xy 357.68524 -15.083161) (xy 357.632709 -15.000091)
			(xy 357.587034 -14.913063) (xy 357.548509 -14.822642) (xy 357.517385 -14.729414) (xy 357.493864 -14.633985)
			(xy 357.478098 -14.536972) (xy 357.470189 -14.439005) (xy 331.260196 -14.439005) (xy 331.260196 -14.694916)
			(xy 331.259735 -14.737193) (xy 331.251932 -14.821386) (xy 331.236394 -14.904499) (xy 331.213253 -14.985825)
			(xy 331.182708 -15.064668) (xy 331.145018 -15.140357) (xy 331.100505 -15.212245) (xy 331.049549 -15.279719)
			(xy 330.992584 -15.342204) (xy 330.930098 -15.399167) (xy 330.862622 -15.450121) (xy 330.790732 -15.494631)
			(xy 330.715042 -15.532319) (xy 330.636198 -15.562862) (xy 330.554872 -15.586) (xy 330.471758 -15.601536)
			(xy 330.387565 -15.609336) (xy 330.345288 -15.609824) (xy 330.302863 -15.609299) (xy 330.218422 -15.600981)
			(xy 330.135202 -15.584427) (xy 330.054006 -15.559796) (xy 329.975615 -15.527324) (xy 329.900784 -15.487326)
			(xy 329.830233 -15.440186) (xy 329.764643 -15.386357) (xy 329.704645 -15.32636) (xy 329.650817 -15.26077)
			(xy 329.603676 -15.19022) (xy 329.563677 -15.115389) (xy 329.531206 -15.036998) (xy 329.506574 -14.955802)
			(xy 329.490019 -14.872582) (xy 329.481701 -14.788141) (xy 329.48118 -14.745716) (xy 329.480926 -14.059916)
			(xy 321.944064 -14.059916) (xy 321.96528 -14.145993) (xy 321.981046 -14.243006) (xy 321.988955 -14.340973)
			(xy 321.98945 -14.390116) (xy 321.988955 -14.439259) (xy 321.981046 -14.537226) (xy 321.96528 -14.634239)
			(xy 321.941759 -14.729668) (xy 321.910635 -14.822896) (xy 321.87211 -14.913317) (xy 321.826435 -15.000345)
			(xy 321.773904 -15.083415) (xy 321.71486 -15.161988) (xy 321.649685 -15.235556) (xy 321.578801 -15.303641)
			(xy 321.502668 -15.365802) (xy 321.421781 -15.421634) (xy 321.336663 -15.470777) (xy 321.247866 -15.512911)
			(xy 321.155968 -15.547764) (xy 321.061562 -15.575109) (xy 320.965263 -15.594768) (xy 320.867694 -15.606615)
			(xy 320.769488 -15.610573) (xy 320.671282 -15.606615) (xy 320.573713 -15.594768) (xy 320.477414 -15.575109)
			(xy 320.383008 -15.547764) (xy 320.29111 -15.512911) (xy 320.202313 -15.470777) (xy 320.117195 -15.421634)
			(xy 320.036308 -15.365802) (xy 319.960175 -15.303641) (xy 319.889291 -15.235556) (xy 319.824116 -15.161988)
			(xy 319.765072 -15.083415) (xy 319.712541 -15.000345) (xy 319.666866 -14.913317) (xy 319.628341 -14.822896)
			(xy 319.597217 -14.729668) (xy 319.573696 -14.634239) (xy 319.55793 -14.537226) (xy 319.550021 -14.439259)
			(xy 281.274705 -14.439259) (xy 281.131289 -14.492837) (xy 280.960513 -14.548076) (xy 280.787439 -14.59563)
			(xy 280.612413 -14.635404) (xy 280.435785 -14.66732) (xy 280.257908 -14.691312) (xy 280.079136 -14.707334)
			(xy 279.899827 -14.715352) (xy 279.720339 -14.715352) (xy 279.54103 -14.707334) (xy 279.362258 -14.691312)
			(xy 279.184381 -14.66732) (xy 279.007753 -14.635404) (xy 278.832727 -14.59563) (xy 278.659653 -14.548076)
			(xy 278.488877 -14.492837) (xy 278.320738 -14.430023) (xy 278.155574 -14.359761) (xy 277.993714 -14.28219)
			(xy 277.835481 -14.197465) (xy 277.681191 -14.105755) (xy 277.531152 -14.007244) (xy 277.385665 -13.902129)
			(xy 277.245018 -13.790618) (xy 277.109494 -13.672935) (xy 276.979363 -13.549315) (xy 276.854885 -13.420005)
			(xy 276.736308 -13.285262) (xy 276.623869 -13.145357) (xy 276.517793 -13.000568) (xy 276.418291 -12.851185)
			(xy 276.325563 -12.697505) (xy 276.239793 -12.539836) (xy 276.161152 -12.378493) (xy 276.089798 -12.213797)
			(xy 276.025874 -12.046078) (xy 275.969506 -11.875671) (xy 275.920808 -11.702915) (xy 275.879876 -11.528157)
			(xy 275.846793 -11.351744) (xy 275.821624 -11.174029) (xy 275.804419 -10.995367) (xy 275.795214 -10.816115)
			(xy 275.794027 -10.636631) (xy 203.066067 -10.636631) (xy 203.066077 -10.636885) (xy 203.06489 -10.816369)
			(xy 203.055685 -10.995621) (xy 203.03848 -11.174283) (xy 203.013311 -11.351998) (xy 202.980228 -11.528411)
			(xy 202.939296 -11.703169) (xy 202.890598 -11.875925) (xy 202.83423 -12.046332) (xy 202.770306 -12.214051)
			(xy 202.698952 -12.378747) (xy 202.620311 -12.54009) (xy 202.534541 -12.697759) (xy 202.441813 -12.851439)
			(xy 202.342311 -13.000822) (xy 202.236235 -13.145611) (xy 202.123796 -13.285516) (xy 202.005219 -13.420259)
			(xy 201.880741 -13.549569) (xy 201.75061 -13.673189) (xy 201.615086 -13.790872) (xy 201.474439 -13.902383)
			(xy 201.328952 -14.007498) (xy 201.178913 -14.106009) (xy 201.024623 -14.197719) (xy 200.86639 -14.282444)
			(xy 200.70453 -14.360015) (xy 200.539366 -14.430277) (xy 200.371227 -14.493091) (xy 200.200451 -14.54833)
			(xy 200.027377 -14.595884) (xy 199.852351 -14.635658) (xy 199.675723 -14.667574) (xy 199.497846 -14.691566)
			(xy 199.319074 -14.707588) (xy 199.139765 -14.715606) (xy 198.960277 -14.715606) (xy 198.780968 -14.707588)
			(xy 198.602196 -14.691566) (xy 198.424319 -14.667574) (xy 198.247691 -14.635658) (xy 198.072665 -14.595884)
			(xy 197.899591 -14.54833) (xy 197.728815 -14.493091) (xy 197.560676 -14.430277) (xy 197.395512 -14.360015)
			(xy 197.233652 -14.282444) (xy 197.075419 -14.197719) (xy 196.921129 -14.106009) (xy 196.77109 -14.007498)
			(xy 196.625603 -13.902383) (xy 196.484956 -13.790872) (xy 196.349432 -13.673189) (xy 196.219301 -13.549569)
			(xy 196.094823 -13.420259) (xy 195.976246 -13.285516) (xy 195.863807 -13.145611) (xy 195.757731 -13.000822)
			(xy 195.658229 -12.851439) (xy 195.565501 -12.697759) (xy 195.479731 -12.54009) (xy 195.40109 -12.378747)
			(xy 195.329736 -12.214051) (xy 195.265812 -12.046332) (xy 195.209444 -11.875925) (xy 195.160746 -11.703169)
			(xy 195.119814 -11.528411) (xy 195.086731 -11.351998) (xy 195.061562 -11.174283) (xy 195.044357 -10.995621)
			(xy 195.035152 -10.816369) (xy 195.033965 -10.636885) (xy 175.53178 -10.636885) (xy 175.53178 -12.614148)
			(xy 174.23638 -12.614148) (xy 174.23638 -9.745472) (xy 171.531788 -9.745472) (xy 171.531788 -11.0998)
			(xy 172.236384 -11.0998) (xy 173.531784 -11.0998) (xy 173.531784 -13.8684) (xy 172.236384 -13.8684)
			(xy 172.236384 -11.0998) (xy 171.531788 -11.0998) (xy 171.531788 -12.614148) (xy 170.236388 -12.614148)
			(xy 170.236388 -9.745472) (xy 167.531796 -9.745472) (xy 167.531796 -11.0998) (xy 168.236392 -11.0998)
			(xy 169.531792 -11.0998) (xy 169.531792 -13.8684) (xy 168.236392 -13.8684) (xy 168.236392 -11.0998)
			(xy 167.531796 -11.0998) (xy 167.531796 -12.614148) (xy 166.236396 -12.614148) (xy 166.236396 -9.745472)
			(xy 145.998692 -9.745472) (xy 145.998692 -11.0998) (xy 164.2364 -11.0998) (xy 165.5318 -11.0998)
			(xy 165.5318 -13.8684) (xy 164.2364 -13.8684) (xy 164.2364 -11.0998) (xy 145.998692 -11.0998) (xy 145.998692 -11.5062)
			(xy 144.169892 -11.5062) (xy 144.169892 -9.0678) (xy 141.1986 -9.0678) (xy 141.1986 -11.5062) (xy 139.3698 -11.5062)
			(xy 139.3698 -9.0678) (xy 119.253 -9.0678) (xy 119.253 -9.69391) (xy 117.8052 -9.69391) (xy 117.8052 -6.87451)
			(xy 11.106105 -6.87451) (xy 11.119951 -6.890029) (xy 11.172322 -6.960748) (xy 11.218045 -7.035936)
			(xy 11.256742 -7.114971) (xy 11.288091 -7.197197) (xy 11.311833 -7.281933) (xy 11.327771 -7.368477)
			(xy 11.335773 -7.456112) (xy 11.336274 -7.500112) (xy 11.335773 -7.544112) (xy 11.327771 -7.631747)
			(xy 11.311833 -7.718291) (xy 11.288091 -7.803027) (xy 11.256742 -7.885253) (xy 11.218045 -7.964288)
			(xy 11.172322 -8.039476) (xy 11.119951 -8.110195) (xy 11.061367 -8.175859) (xy 10.997053 -8.235924)
			(xy 10.927545 -8.289891) (xy 10.853417 -8.337313) (xy 10.775283 -8.377799) (xy 10.693792 -8.411012)
			(xy 10.609618 -8.436676) (xy 10.523459 -8.45458) (xy 10.436029 -8.464575) (xy 10.348052 -8.466579)
			(xy 10.260258 -8.460573) (xy 10.173374 -8.446609) (xy 10.088119 -8.424802) (xy 10.0052 -8.395333)
			(xy 9.925305 -8.358446) (xy 9.849096 -8.314446) (xy 9.777203 -8.263698) (xy 9.710222 -8.206624) (xy 9.64871 -8.143694)
			(xy 9.593174 -8.075432) (xy 9.544076 -8.002403) (xy 9.501823 -7.925211) (xy 9.466764 -7.844497) (xy 9.439189 -7.760929)
			(xy 9.419329 -7.6752) (xy 9.407346 -7.58802) (xy 9.403341 -7.500112) (xy 7.560048 -7.500112) (xy 7.552911 -7.50822)
			(xy 7.427051 -7.639163) (xy 7.29558 -7.764471) (xy 7.15875 -7.883904) (xy 7.016823 -7.997233) (xy 6.870071 -8.104241)
			(xy 6.718776 -8.204723) (xy 6.563227 -8.298486) (xy 6.403724 -8.38535) (xy 6.240571 -8.465148) (xy 6.074081 -8.537729)
			(xy 5.904574 -8.602952) (xy 5.732374 -8.660693) (xy 5.557812 -8.710841) (xy 5.381222 -8.7533) (xy 5.202943 -8.787989)
			(xy 5.023316 -8.81484) (xy 4.842686 -8.833803) (xy 4.661399 -8.844841) (xy 4.479803 -8.847933) (xy 4.298245 -8.843073)
			(xy 4.117075 -8.83027) (xy 3.936638 -8.809549) (xy 3.757281 -8.78095) (xy 3.579348 -8.744527) (xy 3.40318 -8.700351)
			(xy 3.229114 -8.648505) (xy 3.057485 -8.58909) (xy 2.888621 -8.522219) (xy 2.722846 -8.448021) (xy 2.560478 -8.366637)
			(xy 2.401828 -8.278224) (xy 2.2472 -8.182951) (xy 2.09689 -8.081001) (xy 1.951187 -7.972569) (xy 1.810371 -7.857863)
			(xy 1.67471 -7.737104) (xy 1.544465 -7.610521) (xy 1.419886 -7.478359) (xy 1.36017 -7.409942) (xy 1.341882 -7.38886)
			(xy 1.292098 -7.366) (xy 1.143 -7.366) (xy 1.126352 -7.366543) (xy 1.094189 -7.375161) (xy 1.065354 -7.391809)
			(xy 1.041809 -7.415354) (xy 1.025161 -7.444189) (xy 1.016543 -7.476352) (xy 1.016 -7.493) (xy 1.016 -9.554177)
			(xy 87.833696 -9.554177) (xy 87.833696 -9.445531) (xy 87.841627 -9.337174) (xy 87.857446 -9.229685)
			(xy 87.881069 -9.123638) (xy 87.91237 -9.019598) (xy 87.951182 -8.91812) (xy 87.997297 -8.819746)
			(xy 88.050471 -8.725001) (xy 88.110419 -8.63439) (xy 88.176821 -8.548396) (xy 88.249323 -8.467479)
			(xy 88.327538 -8.392071) (xy 88.411049 -8.322572) (xy 88.49941 -8.259355) (xy 88.59215 -8.202757)
			(xy 88.688774 -8.153079) (xy 88.788766 -8.110587) (xy 88.891594 -8.075507) (xy 88.996708 -8.048027)
			(xy 89.103547 -8.028292) (xy 89.211542 -8.016409) (xy 89.320116 -8.012442) (xy 89.42869 -8.016409)
			(xy 89.536685 -8.028292) (xy 89.643524 -8.048027) (xy 89.748638 -8.075507) (xy 89.851466 -8.110587)
			(xy 89.951458 -8.153079) (xy 90.048082 -8.202757) (xy 90.140822 -8.259355) (xy 90.229183 -8.322572)
			(xy 90.312694 -8.392071) (xy 90.390909 -8.467479) (xy 90.463411 -8.548396) (xy 90.529813 -8.63439)
			(xy 90.589761 -8.725001) (xy 90.642935 -8.819746) (xy 90.68905 -8.91812) (xy 90.727862 -9.019598)
			(xy 90.742287 -9.067546) (xy 101.449632 -9.067546) (xy 103.278432 -9.067546) (xy 106.249724 -9.067546)
			(xy 108.078524 -9.067546) (xy 108.078524 -9.398) (xy 113.2586 -9.398) (xy 113.2586 -8.9662) (xy 113.5634 -8.6614)
			(xy 115.3668 -8.6614) (xy 115.697 -8.9916) (xy 115.697 -9.4234) (xy 115.4176 -9.7028) (xy 113.5634 -9.7028)
			(xy 113.2586 -9.398) (xy 108.078524 -9.398) (xy 108.078524 -9.774428) (xy 127.80518 -9.774428) (xy 129.25298 -9.774428)
			(xy 129.25298 -12.593828) (xy 127.80518 -12.593828) (xy 127.80518 -9.774428) (xy 108.078524 -9.774428)
			(xy 108.078524 -11.0744) (xy 117.8052 -11.0744) (xy 119.253 -11.0744) (xy 119.253 -13.8938) (xy 117.8052 -13.8938)
			(xy 117.8052 -11.0744) (xy 108.078524 -11.0744) (xy 108.078524 -11.505946) (xy 106.249724 -11.505946)
			(xy 106.249724 -9.067546) (xy 103.278432 -9.067546) (xy 103.278432 -11.505946) (xy 101.449632 -11.505946)
			(xy 101.449632 -9.067546) (xy 90.742287 -9.067546) (xy 90.759163 -9.123638) (xy 90.782786 -9.229685)
			(xy 90.798605 -9.337174) (xy 90.806536 -9.445531) (xy 90.807032 -9.499854) (xy 90.806536 -9.554177)
			(xy 90.798605 -9.662534) (xy 90.782786 -9.770023) (xy 90.759163 -9.87607) (xy 90.727862 -9.98011)
			(xy 90.68905 -10.081588) (xy 90.642935 -10.179962) (xy 90.589761 -10.274707) (xy 90.529813 -10.365318)
			(xy 90.463411 -10.451312) (xy 90.390909 -10.532229) (xy 90.312694 -10.607637) (xy 90.229183 -10.677136)
			(xy 90.140822 -10.740353) (xy 90.048082 -10.796951) (xy 89.951458 -10.846629) (xy 89.851466 -10.889121)
			(xy 89.748638 -10.924201) (xy 89.643524 -10.951681) (xy 89.536685 -10.971416) (xy 89.42869 -10.983299)
			(xy 89.320116 -10.987267) (xy 89.211542 -10.983299) (xy 89.103547 -10.971416) (xy 88.996708 -10.951681)
			(xy 88.891594 -10.924201) (xy 88.788766 -10.889121) (xy 88.688774 -10.846629) (xy 88.59215 -10.796951)
			(xy 88.49941 -10.740353) (xy 88.411049 -10.677136) (xy 88.327538 -10.607637) (xy 88.249323 -10.532229)
			(xy 88.176821 -10.451312) (xy 88.110419 -10.365318) (xy 88.050471 -10.274707) (xy 87.997297 -10.179962)
			(xy 87.951182 -10.081588) (xy 87.91237 -9.98011) (xy 87.881069 -9.87607) (xy 87.857446 -9.770023)
			(xy 87.841627 -9.662534) (xy 87.833696 -9.554177) (xy 1.016 -9.554177) (xy 1.016 -14.439005) (xy 98.549955 -14.439005)
			(xy 98.549955 -14.340719) (xy 98.557864 -14.242752) (xy 98.57363 -14.145739) (xy 98.597151 -14.05031)
			(xy 98.628275 -13.957082) (xy 98.6668 -13.866661) (xy 98.712475 -13.779634) (xy 98.765006 -13.696563)
			(xy 98.82405 -13.61799) (xy 98.889225 -13.544422) (xy 98.960109 -13.476337) (xy 99.036242 -13.414176)
			(xy 99.117129 -13.358344) (xy 99.202247 -13.309201) (xy 99.291044 -13.267067) (xy 99.382942 -13.232214)
			(xy 99.477348 -13.204869) (xy 99.573647 -13.18521) (xy 99.671216 -13.173363) (xy 99.769422 -13.169405)
			(xy 99.867628 -13.173363) (xy 99.965197 -13.18521) (xy 100.061496 -13.204869) (xy 100.155902 -13.232214)
			(xy 100.2478 -13.267067) (xy 100.336597 -13.309201) (xy 100.421715 -13.358344) (xy 100.502602 -13.414176)
			(xy 100.578735 -13.476337) (xy 100.649619 -13.544422) (xy 100.714794 -13.61799) (xy 100.773838 -13.696563)
			(xy 100.826369 -13.779634) (xy 100.872044 -13.866661) (xy 100.910569 -13.957082) (xy 100.941693 -14.05031)
			(xy 100.965214 -14.145739) (xy 100.98098 -14.242752) (xy 100.988889 -14.340719) (xy 100.989384 -14.389862)
			(xy 100.988889 -14.439005) (xy 100.98098 -14.536972) (xy 100.965214 -14.633985) (xy 100.941693 -14.729414)
			(xy 100.936335 -14.745462) (xy 108.48086 -14.745462) (xy 108.48086 -14.059662) (xy 108.481364 -14.017301)
			(xy 108.489417 -13.932964) (xy 108.505451 -13.849774) (xy 108.529319 -13.768484) (xy 108.560807 -13.689832)
			(xy 108.599629 -13.614529) (xy 108.645432 -13.543257) (xy 108.697803 -13.476661) (xy 108.756268 -13.415346)
			(xy 108.820296 -13.359865) (xy 108.889308 -13.310722) (xy 108.962678 -13.268362) (xy 109.039743 -13.233167)
			(xy 109.119805 -13.205458) (xy 109.202138 -13.185484) (xy 109.285997 -13.173427) (xy 109.370622 -13.169396)
			(xy 109.455247 -13.173427) (xy 109.539106 -13.185484) (xy 109.621439 -13.205458) (xy 109.701501 -13.233167)
			(xy 109.778566 -13.268362) (xy 109.851936 -13.310722) (xy 109.920948 -13.359865) (xy 109.984976 -13.415346)
			(xy 110.043441 -13.476661) (xy 110.095812 -13.543257) (xy 110.141615 -13.614529) (xy 110.180437 -13.689832)
			(xy 110.211925 -13.768484) (xy 110.235793 -13.849774) (xy 110.251827 -13.932964) (xy 110.25988 -14.017301)
			(xy 110.260384 -14.059662) (xy 110.260384 -14.439259) (xy 136.470123 -14.439259) (xy 136.470123 -14.340973)
			(xy 136.478032 -14.243006) (xy 136.493798 -14.145993) (xy 136.517319 -14.050564) (xy 136.548443 -13.957336)
			(xy 136.586968 -13.866915) (xy 136.632643 -13.779888) (xy 136.685174 -13.696817) (xy 136.744218 -13.618244)
			(xy 136.809393 -13.544676) (xy 136.880277 -13.476591) (xy 136.95641 -13.41443) (xy 137.037297 -13.358598)
			(xy 137.122415 -13.309455) (xy 137.211212 -13.267321) (xy 137.30311 -13.232468) (xy 137.397516 -13.205123)
			(xy 137.493815 -13.185464) (xy 137.591384 -13.173617) (xy 137.68959 -13.169659) (xy 137.787796 -13.173617)
			(xy 137.885365 -13.185464) (xy 137.981664 -13.205123) (xy 138.07607 -13.232468) (xy 138.167968 -13.267321)
			(xy 138.256765 -13.309455) (xy 138.341883 -13.358598) (xy 138.42277 -13.41443) (xy 138.498903 -13.476591)
			(xy 138.569787 -13.544676) (xy 138.634962 -13.618244) (xy 138.694006 -13.696817) (xy 138.746537 -13.779888)
			(xy 138.792212 -13.866915) (xy 138.830737 -13.957336) (xy 138.861861 -14.050564) (xy 138.885382 -14.145993)
			(xy 138.901148 -14.243006) (xy 138.909057 -14.340973) (xy 138.909552 -14.390116) (xy 138.909057 -14.439259)
			(xy 138.901148 -14.537226) (xy 138.885382 -14.634239) (xy 138.861861 -14.729668) (xy 138.856503 -14.745716)
			(xy 146.401028 -14.745716) (xy 146.401028 -14.059916) (xy 146.401532 -14.017555) (xy 146.409585 -13.933218)
			(xy 146.425619 -13.850028) (xy 146.449487 -13.768738) (xy 146.480975 -13.690086) (xy 146.519797 -13.614783)
			(xy 146.5656 -13.543511) (xy 146.617971 -13.476915) (xy 146.676436 -13.4156) (xy 146.740464 -13.360119)
			(xy 146.809476 -13.310976) (xy 146.882846 -13.268616) (xy 146.959911 -13.233421) (xy 147.039973 -13.205712)
			(xy 147.122306 -13.185738) (xy 147.206165 -13.173681) (xy 147.29079 -13.16965) (xy 147.375415 -13.173681)
			(xy 147.459274 -13.185738) (xy 147.541607 -13.205712) (xy 147.621669 -13.233421) (xy 147.698734 -13.268616)
			(xy 147.772104 -13.310976) (xy 147.841116 -13.360119) (xy 147.905144 -13.4156) (xy 147.963609 -13.476915)
			(xy 148.01598 -13.543511) (xy 148.061783 -13.614783) (xy 148.100605 -13.690086) (xy 148.132093 -13.768738)
			(xy 148.155961 -13.850028) (xy 148.171995 -13.933218) (xy 148.180048 -14.017555) (xy 148.180552 -14.059916)
			(xy 148.180552 -14.694916) (xy 148.18005 -14.737199) (xy 148.172244 -14.821405) (xy 148.156702 -14.904531)
			(xy 148.133555 -14.985868) (xy 148.103 -15.064722) (xy 148.0653 -15.14042) (xy 148.020774 -15.212316)
			(xy 147.969805 -15.279796) (xy 147.912825 -15.342285) (xy 147.850322 -15.399249) (xy 147.782829 -15.450202)
			(xy 147.710922 -15.49471) (xy 147.635215 -15.532392) (xy 147.556354 -15.562926) (xy 147.475011 -15.586054)
			(xy 147.391881 -15.601576) (xy 147.307673 -15.60936) (xy 147.26539 -15.609824) (xy 147.265136 -15.609824)
			(xy 147.222711 -15.60927) (xy 147.138269 -15.600956) (xy 147.055049 -15.584406) (xy 146.973852 -15.559779)
			(xy 146.895459 -15.527311) (xy 146.820627 -15.487315) (xy 146.750075 -15.440177) (xy 146.684483 -15.386351)
			(xy 146.624484 -15.326355) (xy 146.570654 -15.260767) (xy 146.523511 -15.190218) (xy 146.483512 -15.115388)
			(xy 146.451039 -15.036997) (xy 146.426406 -14.955802) (xy 146.409851 -14.872582) (xy 146.401533 -14.788141)
			(xy 146.401028 -14.745716) (xy 138.856503 -14.745716) (xy 138.830737 -14.822896) (xy 138.792212 -14.913317)
			(xy 138.746537 -15.000345) (xy 138.694006 -15.083415) (xy 138.634962 -15.161988) (xy 138.569787 -15.235556)
			(xy 138.498903 -15.303641) (xy 138.42277 -15.365802) (xy 138.341883 -15.421634) (xy 138.256765 -15.470777)
			(xy 138.167968 -15.512911) (xy 138.07607 -15.547764) (xy 137.981664 -15.575109) (xy 137.885365 -15.594768)
			(xy 137.787796 -15.606615) (xy 137.68959 -15.610573) (xy 137.591384 -15.606615) (xy 137.493815 -15.594768)
			(xy 137.397516 -15.575109) (xy 137.30311 -15.547764) (xy 137.211212 -15.512911) (xy 137.122415 -15.470777)
			(xy 137.037297 -15.421634) (xy 136.95641 -15.365802) (xy 136.880277 -15.303641) (xy 136.809393 -15.235556)
			(xy 136.744218 -15.161988) (xy 136.685174 -15.083415) (xy 136.632643 -15.000345) (xy 136.586968 -14.913317)
			(xy 136.548443 -14.822896) (xy 136.517319 -14.729668) (xy 136.493798 -14.634239) (xy 136.478032 -14.537226)
			(xy 136.470123 -14.439259) (xy 110.260384 -14.439259) (xy 110.260384 -14.694662) (xy 110.259852 -14.736949)
			(xy 110.252052 -14.821164) (xy 110.236515 -14.904299) (xy 110.213373 -14.985646) (xy 110.182824 -15.06451)
			(xy 110.145129 -15.14022) (xy 110.100608 -15.212128) (xy 110.049643 -15.279622) (xy 109.992668 -15.342125)
			(xy 109.930168 -15.399105) (xy 109.862678 -15.450074) (xy 109.790772 -15.494599) (xy 109.715065 -15.5323)
			(xy 109.636203 -15.562854) (xy 109.554857 -15.586001) (xy 109.471723 -15.601544) (xy 109.387509 -15.609349)
			(xy 109.345222 -15.609824) (xy 109.302783 -15.609337) (xy 109.218312 -15.601019) (xy 109.135064 -15.584462)
			(xy 109.05384 -15.559824) (xy 108.975422 -15.527343) (xy 108.900565 -15.487331) (xy 108.829991 -15.440175)
			(xy 108.764379 -15.386328) (xy 108.704361 -15.326309) (xy 108.650515 -15.260696) (xy 108.60336 -15.190121)
			(xy 108.563351 -15.115264) (xy 108.530871 -15.036845) (xy 108.506234 -14.95562) (xy 108.489678 -14.872372)
			(xy 108.481362 -14.787901) (xy 108.48086 -14.745462) (xy 100.936335 -14.745462) (xy 100.910569 -14.822642)
			(xy 100.872044 -14.913063) (xy 100.826369 -15.000091) (xy 100.773838 -15.083161) (xy 100.714794 -15.161734)
			(xy 100.649619 -15.235302) (xy 100.578735 -15.303387) (xy 100.502602 -15.365548) (xy 100.421715 -15.42138)
			(xy 100.336597 -15.470523) (xy 100.2478 -15.512657) (xy 100.155902 -15.54751) (xy 100.061496 -15.574855)
			(xy 99.965197 -15.594514) (xy 99.867628 -15.606361) (xy 99.769422 -15.610319) (xy 99.671216 -15.606361)
			(xy 99.573647 -15.594514) (xy 99.477348 -15.574855) (xy 99.382942 -15.54751) (xy 99.291044 -15.512657)
			(xy 99.202247 -15.470523) (xy 99.117129 -15.42138) (xy 99.036242 -15.365548) (xy 98.960109 -15.303387)
			(xy 98.889225 -15.235302) (xy 98.82405 -15.161734) (xy 98.765006 -15.083161) (xy 98.712475 -15.000091)
			(xy 98.6668 -14.913063) (xy 98.628275 -14.822642) (xy 98.597151 -14.729414) (xy 98.57363 -14.633985)
			(xy 98.557864 -14.536972) (xy 98.549955 -14.439005) (xy 1.016 -14.439005) (xy 1.016 -18.545219) (xy 20.872007 -18.545219)
			(xy 20.87205 -18.453908) (xy 20.880966 -18.363033) (xy 20.898671 -18.273454) (xy 20.911312 -18.22958)
			(xy 21.129752 -18.22958) (xy 21.146337 -18.229101) (xy 21.178386 -18.220556) (xy 21.207146 -18.204033)
			(xy 21.23067 -18.180649) (xy 21.23948 -18.166588) (xy 21.257783 -18.136238) (xy 21.299908 -18.079238)
			(xy 21.347887 -18.02707) (xy 21.401171 -17.980332) (xy 21.459147 -17.939561) (xy 21.489924 -17.921986)
			(xy 21.504471 -17.913263) (xy 21.528754 -17.889601) (xy 21.545969 -17.860391) (xy 21.554909 -17.827686)
			(xy 21.555456 -17.810734) (xy 21.555456 -17.596866) (xy 21.596941 -17.585678) (xy 21.681432 -17.570032)
			(xy 21.767 -17.562177) (xy 21.852928 -17.562177) (xy 21.938496 -17.570032) (xy 22.022987 -17.585678)
			(xy 22.064472 -17.596866) (xy 22.064472 -17.810734) (xy 22.064965 -17.827699) (xy 22.073856 -17.860443)
			(xy 22.091078 -17.889676) (xy 22.115409 -17.913323) (xy 22.130004 -17.921986) (xy 22.160779 -17.939567)
			(xy 22.21877 -17.98032) (xy 22.272063 -18.02705) (xy 22.320044 -18.079219) (xy 22.362161 -18.136227)
			(xy 22.380448 -18.166588) (xy 22.389279 -18.180628) (xy 22.412809 -18.203988) (xy 22.441563 -18.220498)
			(xy 22.473598 -18.229044) (xy 22.490176 -18.22958) (xy 22.708616 -18.22958) (xy 22.72124 -18.273545)
			(xy 22.738897 -18.363302) (xy 22.747728 -18.454351) (xy 22.74824 -18.50009) (xy 22.747731 -18.545211)
			(xy 22.739127 -18.635041) (xy 22.730464 -18.679668) (xy 167.07104 -18.679668) (xy 167.07104 -18.353532)
			(xy 167.301672 -18.1229) (xy 168.897808 -18.1229) (xy 169.12844 -18.353532) (xy 169.12844 -18.679668)
			(xy 191.866266 -18.679668) (xy 191.866266 -18.353532) (xy 192.096898 -18.1229) (xy 193.693034 -18.1229)
			(xy 193.923666 -18.353532) (xy 193.923666 -18.679668) (xy 388.070852 -18.679668) (xy 388.070852 -18.353532)
			(xy 388.301484 -18.1229) (xy 389.89762 -18.1229) (xy 390.128252 -18.353532) (xy 390.128252 -18.679668)
			(xy 412.866078 -18.679668) (xy 412.866078 -18.353532) (xy 413.09671 -18.1229) (xy 414.692846 -18.1229)
			(xy 414.923478 -18.353532) (xy 414.923478 -18.679668) (xy 414.692846 -18.9103) (xy 413.09671 -18.9103)
			(xy 412.866078 -18.679668) (xy 390.128252 -18.679668) (xy 389.89762 -18.9103) (xy 388.301484 -18.9103)
			(xy 388.070852 -18.679668) (xy 193.923666 -18.679668) (xy 193.693034 -18.9103) (xy 192.096898 -18.9103)
			(xy 191.866266 -18.679668) (xy 169.12844 -18.679668) (xy 168.897808 -18.9103) (xy 167.301672 -18.9103)
			(xy 167.07104 -18.679668) (xy 22.730464 -18.679668) (xy 22.721931 -18.723629) (xy 22.709632 -18.767044)
			(xy 22.492208 -18.767044) (xy 22.475563 -18.767623) (xy 22.443406 -18.776234) (xy 22.414572 -18.792872)
			(xy 22.391024 -18.816404) (xy 22.382226 -18.830544) (xy 22.363929 -18.861244) (xy 22.321713 -18.918915)
			(xy 22.273522 -18.971695) (xy 22.219918 -19.018968) (xy 22.161527 -19.060183) (xy 22.130512 -19.07794)
			(xy 22.115939 -19.086623) (xy 22.091663 -19.110301) (xy 22.074455 -19.139522) (xy 22.065523 -19.172237)
			(xy 22.06498 -19.189192) (xy 22.06498 -19.40306) (xy 22.023416 -19.414293) (xy 21.938758 -19.430004)
			(xy 21.853016 -19.437893) (xy 21.766912 -19.437893) (xy 21.68117 -19.430004) (xy 21.596512 -19.414293)
			(xy 21.554948 -19.40306) (xy 21.554948 -19.189192) (xy 21.554425 -19.172229) (xy 21.545543 -19.139488)
			(xy 21.528329 -19.110255) (xy 21.504007 -19.086606) (xy 21.489416 -19.07794) (xy 21.458589 -19.060303)
			(xy 21.40052 -19.019407) (xy 21.347167 -18.972525) (xy 21.299145 -18.920195) (xy 21.257007 -18.863021)
			(xy 21.238718 -18.832576) (xy 21.229921 -18.818513) (xy 21.206378 -18.795158) (xy 21.177615 -18.778654)
			(xy 21.145571 -18.770116) (xy 21.12899 -18.769584) (xy 20.911058 -18.769584) (xy 20.89846 -18.725697)
			(xy 20.880839 -18.636102) (xy 20.872007 -18.545219) (xy 1.016 -18.545219) (xy 1.016 -24.826468) (xy 165.8239 -24.826468)
			(xy 165.8239 -23.230332) (xy 166.054532 -22.9997) (xy 166.380668 -22.9997) (xy 166.6113 -23.230332)
			(xy 166.6113 -23.858728) (xy 170.456352 -23.858728) (xy 170.456352 -23.532592) (xy 170.686984 -23.30196)
			(xy 172.28312 -23.30196) (xy 172.513752 -23.532592) (xy 172.513752 -23.858728) (xy 172.28312 -24.08936)
			(xy 170.686984 -24.08936) (xy 170.456352 -23.858728) (xy 166.6113 -23.858728) (xy 166.6113 -24.826468)
			(xy 177.83048 -24.826468) (xy 177.83048 -23.230332) (xy 178.061112 -22.9997) (xy 178.387248 -22.9997)
			(xy 178.61788 -23.230332) (xy 178.61788 -23.741888) (xy 189.46622 -23.741888) (xy 189.46622 -23.415752)
			(xy 189.696852 -23.18512) (xy 191.292988 -23.18512) (xy 191.52362 -23.415752) (xy 191.52362 -23.741888)
			(xy 191.292988 -23.97252) (xy 189.696852 -23.97252) (xy 189.46622 -23.741888) (xy 178.61788 -23.741888)
			(xy 178.61788 -24.826468) (xy 178.61026 -24.834088) (xy 197.2691 -24.834088) (xy 197.2691 -23.237952)
			(xy 197.499732 -23.00732) (xy 197.825868 -23.00732) (xy 198.0565 -23.237952) (xy 198.0565 -24.826468)
			(xy 386.823712 -24.826468) (xy 386.823712 -23.230332) (xy 387.054344 -22.9997) (xy 387.38048 -22.9997)
			(xy 387.611112 -23.230332) (xy 387.611112 -23.858728) (xy 391.456164 -23.858728) (xy 391.456164 -23.532592)
			(xy 391.686796 -23.30196) (xy 393.282932 -23.30196) (xy 393.513564 -23.532592) (xy 393.513564 -23.858728)
			(xy 393.282932 -24.08936) (xy 391.686796 -24.08936) (xy 391.456164 -23.858728) (xy 387.611112 -23.858728)
			(xy 387.611112 -24.826468) (xy 398.830292 -24.826468) (xy 398.830292 -23.230332) (xy 399.060924 -22.9997)
			(xy 399.38706 -22.9997) (xy 399.617692 -23.230332) (xy 399.617692 -23.741888) (xy 410.466032 -23.741888)
			(xy 410.466032 -23.415752) (xy 410.696664 -23.18512) (xy 412.2928 -23.18512) (xy 412.523432 -23.415752)
			(xy 412.523432 -23.741888) (xy 412.2928 -23.97252) (xy 410.696664 -23.97252) (xy 410.466032 -23.741888)
			(xy 399.617692 -23.741888) (xy 399.617692 -24.826468) (xy 399.610072 -24.834088) (xy 418.268912 -24.834088)
			(xy 418.268912 -23.237952) (xy 418.499544 -23.00732) (xy 418.82568 -23.00732) (xy 419.056312 -23.237952)
			(xy 419.056312 -24.834088) (xy 418.82568 -25.06472) (xy 418.499544 -25.06472) (xy 418.268912 -24.834088)
			(xy 399.610072 -24.834088) (xy 399.38706 -25.0571) (xy 399.060924 -25.0571) (xy 398.830292 -24.826468)
			(xy 387.611112 -24.826468) (xy 387.38048 -25.0571) (xy 387.054344 -25.0571) (xy 386.823712 -24.826468)
			(xy 198.0565 -24.826468) (xy 198.0565 -24.834088) (xy 197.825868 -25.06472) (xy 197.499732 -25.06472)
			(xy 197.2691 -24.834088) (xy 178.61026 -24.834088) (xy 178.387248 -25.0571) (xy 178.061112 -25.0571)
			(xy 177.83048 -24.826468) (xy 166.6113 -24.826468) (xy 166.380668 -25.0571) (xy 166.054532 -25.0571)
			(xy 165.8239 -24.826468) (xy 1.016 -24.826468) (xy 1.016 -32.2072) (xy 1.016476 -32.229251) (xy 1.024096 -32.272689)
			(xy 1.0391 -32.31416) (xy 1.061036 -32.352419) (xy 1.089246 -32.386318) (xy 1.122884 -32.414839)
			(xy 1.16094 -32.437126) (xy 1.202271 -32.452511) (xy 1.245637 -32.46053) (xy 1.289737 -32.460945)
			(xy 1.333246 -32.453741) (xy 1.374859 -32.439136) (xy 1.413327 -32.417568) (xy 1.447495 -32.389685)
			(xy 1.462278 -32.373316) (xy 1.514188 -32.313818) (xy 1.622042 -32.198468) (xy 1.677924 -32.142684)
			(xy 1.695704 -32.124904) (xy 1.734058 -32.034226) (xy 1.734058 -29.049218) (xy 1.734058 -28.950158)
			(xy 1.734058 -28.786836) (xy 1.741932 -28.778962) (xy 1.746504 -28.733496) (xy 1.746504 -28.733242)
			(xy 1.754112 -28.659741) (xy 1.776189 -28.513615) (xy 1.806038 -28.368876) (xy 1.843573 -28.225938)
			(xy 1.888687 -28.085207) (xy 1.941251 -27.947087) (xy 2.001116 -27.81197) (xy 2.068109 -27.680243)
			(xy 2.142042 -27.552281) (xy 2.222701 -27.428449) (xy 2.309858 -27.309101) (xy 2.403263 -27.194577)
			(xy 2.502651 -27.085205) (xy 2.607737 -26.981295) (xy 2.718221 -26.883145) (xy 2.833789 -26.791034)
			(xy 2.95411 -26.705226) (xy 3.078842 -26.625965) (xy 3.207628 -26.553478) (xy 3.340101 -26.48797)
			(xy 3.475882 -26.42963) (xy 3.614586 -26.378624) (xy 3.755815 -26.335097) (xy 3.899166 -26.299173)
			(xy 4.044232 -26.270955) (xy 4.190597 -26.250523) (xy 4.337845 -26.237936) (xy 4.485554 -26.23323)
			(xy 4.633304 -26.236418) (xy 4.780674 -26.24749) (xy 4.927241 -26.266416) (xy 5.072589 -26.293141)
			(xy 5.216303 -26.32759) (xy 5.357972 -26.369663) (xy 5.497192 -26.419241) (xy 5.633566 -26.476182)
			(xy 5.766706 -26.540324) (xy 5.775589 -26.545204) (xy 20.872002 -26.545204) (xy 20.872046 -26.453892)
			(xy 20.880963 -26.363017) (xy 20.89867 -26.273438) (xy 20.911312 -26.229564) (xy 21.129752 -26.229564)
			(xy 21.146337 -26.229093) (xy 21.178388 -26.220547) (xy 21.207148 -26.204021) (xy 21.230671 -26.180634)
			(xy 21.23948 -26.166572) (xy 21.257779 -26.13622) (xy 21.299905 -26.07922) (xy 21.347885 -26.027052)
			(xy 21.40117 -25.980315) (xy 21.459146 -25.939544) (xy 21.489924 -25.92197) (xy 21.504479 -25.913258)
			(xy 21.528761 -25.889592) (xy 21.545974 -25.86038) (xy 21.554911 -25.827671) (xy 21.555456 -25.810718)
			(xy 21.555456 -25.59685) (xy 21.596941 -25.585662) (xy 21.681432 -25.570016) (xy 21.767 -25.562161)
			(xy 21.852928 -25.562161) (xy 21.938496 -25.570016) (xy 22.022987 -25.585662) (xy 22.064472 -25.59685)
			(xy 22.064472 -25.810718) (xy 22.064977 -25.827683) (xy 22.073864 -25.860425) (xy 22.091083 -25.889658)
			(xy 22.11541 -25.913306) (xy 22.130004 -25.92197) (xy 22.160776 -25.939556) (xy 22.218768 -25.980308)
			(xy 22.272061 -26.027037) (xy 22.320043 -26.079205) (xy 22.362161 -26.136212) (xy 22.380448 -26.166572)
			(xy 22.389252 -26.18063) (xy 22.412795 -26.203982) (xy 22.441556 -26.220486) (xy 22.473596 -26.229029)
			(xy 22.490176 -26.229564) (xy 22.708616 -26.229564) (xy 22.721236 -26.27353) (xy 22.738894 -26.363286)
			(xy 22.747728 -26.454335) (xy 22.74824 -26.500074) (xy 22.747727 -26.545195) (xy 22.739125 -26.635025)
			(xy 22.72193 -26.723613) (xy 22.709632 -26.767028) (xy 22.492208 -26.767028) (xy 22.475553 -26.767518)
			(xy 22.443378 -26.776138) (xy 22.414531 -26.792795) (xy 22.39098 -26.816351) (xy 22.382226 -26.830528)
			(xy 22.363925 -26.861225) (xy 22.32171 -26.918897) (xy 22.27352 -26.971677) (xy 22.257883 -26.985468)
			(xy 183.6039 -26.985468) (xy 183.6039 -26.659332) (xy 183.834532 -26.4287) (xy 185.430668 -26.4287)
			(xy 185.6613 -26.659332) (xy 185.6613 -26.985468) (xy 404.603712 -26.985468) (xy 404.603712 -26.659332)
			(xy 404.834344 -26.4287) (xy 406.43048 -26.4287) (xy 406.661112 -26.659332) (xy 406.661112 -26.985468)
			(xy 406.43048 -27.2161) (xy 404.834344 -27.2161) (xy 404.603712 -26.985468) (xy 185.6613 -26.985468)
			(xy 185.430668 -27.2161) (xy 183.834532 -27.2161) (xy 183.6039 -26.985468) (xy 22.257883 -26.985468)
			(xy 22.219917 -27.018951) (xy 22.161527 -27.060166) (xy 22.130512 -27.077924) (xy 22.115946 -27.086618)
			(xy 22.091669 -27.110292) (xy 22.07446 -27.13951) (xy 22.065525 -27.172222) (xy 22.06498 -27.189176)
			(xy 22.06498 -27.403044) (xy 22.023416 -27.414277) (xy 21.938758 -27.429988) (xy 21.853016 -27.437877)
			(xy 21.766912 -27.437877) (xy 21.68117 -27.429988) (xy 21.596512 -27.414277) (xy 21.554948 -27.403044)
			(xy 21.554948 -27.189176) (xy 21.554438 -27.172212) (xy 21.545551 -27.139471) (xy 21.528334 -27.110238)
			(xy 21.504009 -27.086589) (xy 21.489416 -27.077924) (xy 21.458587 -27.060291) (xy 21.400517 -27.019395)
			(xy 21.347165 -26.972511) (xy 21.299143 -26.92018) (xy 21.257006 -26.863005) (xy 21.238718 -26.83256)
			(xy 21.229926 -26.818493) (xy 21.206381 -26.79514) (xy 21.177616 -26.778637) (xy 21.145571 -26.770099)
			(xy 21.12899 -26.769568) (xy 20.911058 -26.769568) (xy 20.898452 -26.725683) (xy 20.880832 -26.636088)
			(xy 20.872002 -26.545204) (xy 5.775589 -26.545204) (xy 5.89623 -26.611483) (xy 6.02177 -26.689458)
			(xy 6.142967 -26.774025) (xy 6.259475 -26.864942) (xy 6.370963 -26.961951) (xy 6.477111 -27.064775)
			(xy 6.577618 -27.173121) (xy 6.672195 -27.286678) (xy 6.760575 -27.405124) (xy 6.842503 -27.52812)
			(xy 6.917747 -27.655315) (xy 6.986091 -27.786347) (xy 7.047341 -27.920841) (xy 7.101323 -28.058414)
			(xy 7.147881 -28.198673) (xy 7.186883 -28.341218) (xy 7.218218 -28.485642) (xy 7.241797 -28.631533)
			(xy 7.257552 -28.778476) (xy 7.265437 -28.92605) (xy 7.265924 -28.999942) (xy 7.265924 -29.472128)
			(xy 183.83504 -29.472128) (xy 183.83504 -29.145992) (xy 184.065672 -28.91536) (xy 185.661808 -28.91536)
			(xy 185.89244 -29.145992) (xy 185.89244 -29.472128) (xy 404.834852 -29.472128) (xy 404.834852 -29.145992)
			(xy 405.065484 -28.91536) (xy 406.66162 -28.91536) (xy 406.892252 -29.145992) (xy 406.892252 -29.472128)
			(xy 406.66162 -29.70276) (xy 405.065484 -29.70276) (xy 404.834852 -29.472128) (xy 185.89244 -29.472128)
			(xy 185.661808 -29.70276) (xy 184.065672 -29.70276) (xy 183.83504 -29.472128) (xy 7.265924 -29.472128)
			(xy 7.265924 -30.897068) (xy 167.656256 -30.897068) (xy 167.656256 -30.570932) (xy 167.886888 -30.3403)
			(xy 169.483024 -30.3403) (xy 169.713656 -30.570932) (xy 169.713656 -30.897068) (xy 169.483024 -31.1277)
			(xy 167.886888 -31.1277) (xy 167.656256 -30.897068) (xy 7.265924 -30.897068) (xy 7.265924 -31.158688)
			(xy 174.856394 -31.158688) (xy 174.856394 -30.832552) (xy 175.087026 -30.60192) (xy 176.683162 -30.60192)
			(xy 176.839118 -30.757876) (xy 189.06617 -30.757876) (xy 189.06617 -30.43174) (xy 189.296802 -30.201108)
			(xy 190.892938 -30.201108) (xy 191.12357 -30.43174) (xy 191.12357 -30.726888) (xy 193.866262 -30.726888)
			(xy 193.866262 -30.400752) (xy 194.096894 -30.17012) (xy 195.70192 -30.17012) (xy 195.923662 -30.391862)
			(xy 195.923662 -30.726888) (xy 195.753482 -30.897068) (xy 388.656068 -30.897068) (xy 388.656068 -30.570932)
			(xy 388.8867 -30.3403) (xy 390.482836 -30.3403) (xy 390.713468 -30.570932) (xy 390.713468 -30.897068)
			(xy 390.482836 -31.1277) (xy 388.8867 -31.1277) (xy 388.656068 -30.897068) (xy 195.753482 -30.897068)
			(xy 195.69303 -30.95752) (xy 194.096894 -30.95752) (xy 193.866262 -30.726888) (xy 191.12357 -30.726888)
			(xy 191.12357 -30.757876) (xy 190.892938 -30.988508) (xy 189.296802 -30.988508) (xy 189.06617 -30.757876)
			(xy 176.839118 -30.757876) (xy 176.913794 -30.832552) (xy 176.913794 -31.158688) (xy 395.856206 -31.158688)
			(xy 395.856206 -30.832552) (xy 396.086838 -30.60192) (xy 397.682974 -30.60192) (xy 397.83893 -30.757876)
			(xy 410.065982 -30.757876) (xy 410.065982 -30.43174) (xy 410.296614 -30.201108) (xy 411.89275 -30.201108)
			(xy 412.123382 -30.43174) (xy 412.123382 -30.726888) (xy 414.866074 -30.726888) (xy 414.866074 -30.400752)
			(xy 415.096706 -30.17012) (xy 416.692842 -30.17012) (xy 416.923474 -30.400752) (xy 416.923474 -30.726888)
			(xy 416.692842 -30.95752) (xy 415.096706 -30.95752) (xy 414.866074 -30.726888) (xy 412.123382 -30.726888)
			(xy 412.123382 -30.757876) (xy 411.89275 -30.988508) (xy 410.296614 -30.988508) (xy 410.065982 -30.757876)
			(xy 397.83893 -30.757876) (xy 397.913606 -30.832552) (xy 397.913606 -31.158688) (xy 397.682974 -31.38932)
			(xy 396.086838 -31.38932) (xy 395.856206 -31.158688) (xy 176.913794 -31.158688) (xy 176.683162 -31.38932)
			(xy 175.087026 -31.38932) (xy 174.856394 -31.158688) (xy 7.265924 -31.158688) (xy 7.265924 -32.034226)
			(xy 7.304278 -32.124904) (xy 7.322058 -32.142684) (xy 7.328671 -32.149288) (xy 170.056302 -32.149288)
			(xy 170.056302 -31.823152) (xy 170.286934 -31.59252) (xy 171.88307 -31.59252) (xy 172.113702 -31.823152)
			(xy 172.113702 -31.844488) (xy 191.48044 -31.844488) (xy 191.48044 -31.518352) (xy 191.591184 -31.407608)
			(xy 191.614806 -31.400496) (xy 191.634364 -31.384748) (xy 191.656208 -31.368238) (xy 191.682116 -31.350458)
			(xy 191.710818 -31.29534) (xy 191.710818 -31.287974) (xy 191.711072 -31.28772) (xy 193.307208 -31.28772)
			(xy 193.53784 -31.518352) (xy 193.53784 -31.844488) (xy 193.307208 -32.07512) (xy 191.711072 -32.07512)
			(xy 191.48044 -31.844488) (xy 172.113702 -31.844488) (xy 172.113702 -32.149288) (xy 391.056114 -32.149288)
			(xy 391.056114 -31.823152) (xy 391.286746 -31.59252) (xy 392.882882 -31.59252) (xy 393.113514 -31.823152)
			(xy 393.113514 -31.844488) (xy 412.480252 -31.844488) (xy 412.480252 -31.518352) (xy 412.590996 -31.407608)
			(xy 412.614618 -31.400496) (xy 412.634176 -31.384748) (xy 412.65602 -31.368238) (xy 412.681928 -31.350458)
			(xy 412.71063 -31.29534) (xy 412.71063 -31.287974) (xy 412.710884 -31.28772) (xy 414.30702 -31.28772)
			(xy 414.537652 -31.518352) (xy 414.537652 -31.844488) (xy 414.30702 -32.07512) (xy 412.710884 -32.07512)
			(xy 412.480252 -31.844488) (xy 393.113514 -31.844488) (xy 393.113514 -32.149288) (xy 392.882882 -32.37992)
			(xy 391.286746 -32.37992) (xy 391.056114 -32.149288) (xy 172.113702 -32.149288) (xy 171.88307 -32.37992)
			(xy 170.286934 -32.37992) (xy 170.056302 -32.149288) (xy 7.328671 -32.149288) (xy 7.385608 -32.206151)
			(xy 7.507639 -32.337964) (xy 7.623654 -32.475101) (xy 7.733421 -32.617289) (xy 7.83672 -32.764242)
			(xy 7.933346 -32.915667) (xy 8.023105 -33.071261) (xy 8.105817 -33.230712) (xy 8.181316 -33.393703)
			(xy 8.249453 -33.559906) (xy 8.277861 -33.639119) (xy 165.265595 -33.639119) (xy 165.265595 -33.540833)
			(xy 165.273504 -33.442866) (xy 165.28927 -33.345853) (xy 165.312791 -33.250424) (xy 165.343915 -33.157196)
			(xy 165.38244 -33.066775) (xy 165.428115 -32.979748) (xy 165.480646 -32.896677) (xy 165.53969 -32.818104)
			(xy 165.604865 -32.744536) (xy 165.675749 -32.676451) (xy 165.751882 -32.61429) (xy 165.832769 -32.558458)
			(xy 165.917887 -32.509315) (xy 166.006684 -32.467181) (xy 166.098582 -32.432328) (xy 166.192988 -32.404983)
			(xy 166.289287 -32.385324) (xy 166.386856 -32.373477) (xy 166.485062 -32.369519) (xy 166.583268 -32.373477)
			(xy 166.680837 -32.385324) (xy 166.777136 -32.404983) (xy 166.871542 -32.432328) (xy 166.96344 -32.467181)
			(xy 167.052237 -32.509315) (xy 167.137355 -32.558458) (xy 167.218242 -32.61429) (xy 167.294375 -32.676451)
			(xy 167.365259 -32.744536) (xy 167.430434 -32.818104) (xy 167.489478 -32.896677) (xy 167.542009 -32.979748)
			(xy 167.587684 -33.066775) (xy 167.593944 -33.081468) (xy 172.481748 -33.081468) (xy 172.481748 -32.755332)
			(xy 172.71238 -32.5247) (xy 174.308516 -32.5247) (xy 174.539148 -32.755332) (xy 174.539148 -33.081468)
			(xy 174.308516 -33.3121) (xy 172.71238 -33.3121) (xy 172.481748 -33.081468) (xy 167.593944 -33.081468)
			(xy 167.626209 -33.157196) (xy 167.657333 -33.250424) (xy 167.680854 -33.345853) (xy 167.69662 -33.442866)
			(xy 167.704529 -33.540833) (xy 167.705024 -33.589976) (xy 167.704529 -33.639119) (xy 167.704526 -33.63915)
			(xy 177.264809 -33.63915) (xy 177.264809 -33.540802) (xy 177.272723 -33.442774) (xy 177.288499 -33.345701)
			(xy 177.312035 -33.250211) (xy 177.343178 -33.156926) (xy 177.381727 -33.066448) (xy 177.427431 -32.979366)
			(xy 177.479994 -32.896244) (xy 177.539075 -32.817621) (xy 177.604292 -32.744008) (xy 177.67522 -32.67588)
			(xy 177.7514 -32.613681) (xy 177.832338 -32.557813) (xy 177.917509 -32.50864) (xy 178.006361 -32.466479)
			(xy 178.098317 -32.431605) (xy 178.192781 -32.404243) (xy 178.289141 -32.384571) (xy 178.386771 -32.372717)
			(xy 178.485038 -32.368757) (xy 178.583305 -32.372717) (xy 178.680935 -32.384571) (xy 178.777295 -32.404243)
			(xy 178.871759 -32.431605) (xy 178.963715 -32.466479) (xy 179.052567 -32.50864) (xy 179.137738 -32.557813)
			(xy 179.218676 -32.613681) (xy 179.294856 -32.67588) (xy 179.365784 -32.744008) (xy 179.431001 -32.817621)
			(xy 179.490082 -32.896244) (xy 179.542645 -32.979366) (xy 179.588349 -33.066448) (xy 179.626898 -33.156926)
			(xy 179.658041 -33.250211) (xy 179.681577 -33.345701) (xy 179.697353 -33.442774) (xy 179.705267 -33.540802)
			(xy 179.705762 -33.589976) (xy 179.705267 -33.639119) (xy 184.275463 -33.639119) (xy 184.275463 -33.540833)
			(xy 184.283372 -33.442866) (xy 184.299138 -33.345853) (xy 184.322659 -33.250424) (xy 184.353783 -33.157196)
			(xy 184.392308 -33.066775) (xy 184.437983 -32.979748) (xy 184.490514 -32.896677) (xy 184.549558 -32.818104)
			(xy 184.614733 -32.744536) (xy 184.685617 -32.676451) (xy 184.76175 -32.61429) (xy 184.842637 -32.558458)
			(xy 184.927755 -32.509315) (xy 185.016552 -32.467181) (xy 185.10845 -32.432328) (xy 185.202856 -32.404983)
			(xy 185.299155 -32.385324) (xy 185.396724 -32.373477) (xy 185.49493 -32.369519) (xy 185.593136 -32.373477)
			(xy 185.690705 -32.385324) (xy 185.787004 -32.404983) (xy 185.88141 -32.432328) (xy 185.973308 -32.467181)
			(xy 186.062105 -32.509315) (xy 186.147223 -32.558458) (xy 186.22811 -32.61429) (xy 186.304243 -32.676451)
			(xy 186.375127 -32.744536) (xy 186.440302 -32.818104) (xy 186.499346 -32.896677) (xy 186.551877 -32.979748)
			(xy 186.597552 -33.066775) (xy 186.636077 -33.157196) (xy 186.667201 -33.250424) (xy 186.690722 -33.345853)
			(xy 186.706488 -33.442866) (xy 186.714397 -33.540833) (xy 186.714892 -33.589976) (xy 186.714397 -33.639119)
			(xy 186.714394 -33.63915) (xy 196.274677 -33.63915) (xy 196.274677 -33.540802) (xy 196.282591 -33.442774)
			(xy 196.298367 -33.345701) (xy 196.321903 -33.250211) (xy 196.353046 -33.156926) (xy 196.391595 -33.066448)
			(xy 196.437299 -32.979366) (xy 196.489862 -32.896244) (xy 196.548943 -32.817621) (xy 196.61416 -32.744008)
			(xy 196.685088 -32.67588) (xy 196.761268 -32.613681) (xy 196.842206 -32.557813) (xy 196.927377 -32.50864)
			(xy 197.016229 -32.466479) (xy 197.108185 -32.431605) (xy 197.202649 -32.404243) (xy 197.299009 -32.384571)
			(xy 197.396639 -32.372717) (xy 197.494906 -32.368757) (xy 197.593173 -32.372717) (xy 197.690803 -32.384571)
			(xy 197.787163 -32.404243) (xy 197.881627 -32.431605) (xy 197.973583 -32.466479) (xy 198.062435 -32.50864)
			(xy 198.147606 -32.557813) (xy 198.228544 -32.613681) (xy 198.304724 -32.67588) (xy 198.375652 -32.744008)
			(xy 198.440869 -32.817621) (xy 198.49995 -32.896244) (xy 198.552513 -32.979366) (xy 198.598217 -33.066448)
			(xy 198.636766 -33.156926) (xy 198.667909 -33.250211) (xy 198.691445 -33.345701) (xy 198.707221 -33.442774)
			(xy 198.715135 -33.540802) (xy 198.71563 -33.589976) (xy 198.715135 -33.639119) (xy 386.265407 -33.639119)
			(xy 386.265407 -33.540833) (xy 386.273316 -33.442866) (xy 386.289082 -33.345853) (xy 386.312603 -33.250424)
			(xy 386.343727 -33.157196) (xy 386.382252 -33.066775) (xy 386.427927 -32.979748) (xy 386.480458 -32.896677)
			(xy 386.539502 -32.818104) (xy 386.604677 -32.744536) (xy 386.675561 -32.676451) (xy 386.751694 -32.61429)
			(xy 386.832581 -32.558458) (xy 386.917699 -32.509315) (xy 387.006496 -32.467181) (xy 387.098394 -32.432328)
			(xy 387.1928 -32.404983) (xy 387.289099 -32.385324) (xy 387.386668 -32.373477) (xy 387.484874 -32.369519)
			(xy 387.58308 -32.373477) (xy 387.680649 -32.385324) (xy 387.776948 -32.404983) (xy 387.871354 -32.432328)
			(xy 387.963252 -32.467181) (xy 388.052049 -32.509315) (xy 388.137167 -32.558458) (xy 388.218054 -32.61429)
			(xy 388.294187 -32.676451) (xy 388.365071 -32.744536) (xy 388.430246 -32.818104) (xy 388.48929 -32.896677)
			(xy 388.541821 -32.979748) (xy 388.587496 -33.066775) (xy 388.593756 -33.081468) (xy 393.48156 -33.081468)
			(xy 393.48156 -32.755332) (xy 393.712192 -32.5247) (xy 395.308328 -32.5247) (xy 395.53896 -32.755332)
			(xy 395.53896 -33.081468) (xy 395.308328 -33.3121) (xy 393.712192 -33.3121) (xy 393.48156 -33.081468)
			(xy 388.593756 -33.081468) (xy 388.626021 -33.157196) (xy 388.657145 -33.250424) (xy 388.680666 -33.345853)
			(xy 388.696432 -33.442866) (xy 388.704341 -33.540833) (xy 388.704836 -33.589976) (xy 388.704341 -33.639119)
			(xy 388.704338 -33.63915) (xy 398.264621 -33.63915) (xy 398.264621 -33.540802) (xy 398.272535 -33.442774)
			(xy 398.288311 -33.345701) (xy 398.311847 -33.250211) (xy 398.34299 -33.156926) (xy 398.381539 -33.066448)
			(xy 398.427243 -32.979366) (xy 398.479806 -32.896244) (xy 398.538887 -32.817621) (xy 398.604104 -32.744008)
			(xy 398.675032 -32.67588) (xy 398.751212 -32.613681) (xy 398.83215 -32.557813) (xy 398.917321 -32.50864)
			(xy 399.006173 -32.466479) (xy 399.098129 -32.431605) (xy 399.192593 -32.404243) (xy 399.288953 -32.384571)
			(xy 399.386583 -32.372717) (xy 399.48485 -32.368757) (xy 399.583117 -32.372717) (xy 399.680747 -32.384571)
			(xy 399.777107 -32.404243) (xy 399.871571 -32.431605) (xy 399.963527 -32.466479) (xy 400.052379 -32.50864)
			(xy 400.13755 -32.557813) (xy 400.218488 -32.613681) (xy 400.294668 -32.67588) (xy 400.365596 -32.744008)
			(xy 400.430813 -32.817621) (xy 400.489894 -32.896244) (xy 400.542457 -32.979366) (xy 400.588161 -33.066448)
			(xy 400.62671 -33.156926) (xy 400.657853 -33.250211) (xy 400.681389 -33.345701) (xy 400.697165 -33.442774)
			(xy 400.705079 -33.540802) (xy 400.705574 -33.589976) (xy 400.705079 -33.639119) (xy 405.275529 -33.639119)
			(xy 405.275529 -33.540833) (xy 405.283438 -33.442866) (xy 405.299204 -33.345853) (xy 405.322725 -33.250424)
			(xy 405.353849 -33.157196) (xy 405.392374 -33.066775) (xy 405.438049 -32.979748) (xy 405.49058 -32.896677)
			(xy 405.549624 -32.818104) (xy 405.614799 -32.744536) (xy 405.685683 -32.676451) (xy 405.761816 -32.61429)
			(xy 405.842703 -32.558458) (xy 405.927821 -32.509315) (xy 406.016618 -32.467181) (xy 406.108516 -32.432328)
			(xy 406.202922 -32.404983) (xy 406.299221 -32.385324) (xy 406.39679 -32.373477) (xy 406.494996 -32.369519)
			(xy 406.593202 -32.373477) (xy 406.690771 -32.385324) (xy 406.78707 -32.404983) (xy 406.881476 -32.432328)
			(xy 406.973374 -32.467181) (xy 407.062171 -32.509315) (xy 407.147289 -32.558458) (xy 407.228176 -32.61429)
			(xy 407.304309 -32.676451) (xy 407.375193 -32.744536) (xy 407.440368 -32.818104) (xy 407.499412 -32.896677)
			(xy 407.551943 -32.979748) (xy 407.597618 -33.066775) (xy 407.636143 -33.157196) (xy 407.667267 -33.250424)
			(xy 407.690788 -33.345853) (xy 407.706554 -33.442866) (xy 407.714463 -33.540833) (xy 407.714958 -33.589976)
			(xy 407.714463 -33.639119) (xy 407.71446 -33.63915) (xy 417.274743 -33.63915) (xy 417.274743 -33.540802)
			(xy 417.282657 -33.442774) (xy 417.298433 -33.345701) (xy 417.321969 -33.250211) (xy 417.353112 -33.156926)
			(xy 417.391661 -33.066448) (xy 417.437365 -32.979366) (xy 417.489928 -32.896244) (xy 417.549009 -32.817621)
			(xy 417.614226 -32.744008) (xy 417.685154 -32.67588) (xy 417.761334 -32.613681) (xy 417.842272 -32.557813)
			(xy 417.927443 -32.50864) (xy 418.016295 -32.466479) (xy 418.108251 -32.431605) (xy 418.202715 -32.404243)
			(xy 418.299075 -32.384571) (xy 418.396705 -32.372717) (xy 418.494972 -32.368757) (xy 418.593239 -32.372717)
			(xy 418.690869 -32.384571) (xy 418.787229 -32.404243) (xy 418.881693 -32.431605) (xy 418.973649 -32.466479)
			(xy 419.062501 -32.50864) (xy 419.147672 -32.557813) (xy 419.22861 -32.613681) (xy 419.30479 -32.67588)
			(xy 419.375718 -32.744008) (xy 419.440935 -32.817621) (xy 419.500016 -32.896244) (xy 419.552579 -32.979366)
			(xy 419.598283 -33.066448) (xy 419.636832 -33.156926) (xy 419.667975 -33.250211) (xy 419.691511 -33.345701)
			(xy 419.707287 -33.442774) (xy 419.715201 -33.540802) (xy 419.715696 -33.589976) (xy 419.715201 -33.63915)
			(xy 419.707287 -33.737178) (xy 419.691511 -33.834251) (xy 419.667975 -33.929741) (xy 419.636832 -34.023026)
			(xy 419.598283 -34.113504) (xy 419.552579 -34.200586) (xy 419.500016 -34.283708) (xy 419.440935 -34.362331)
			(xy 419.375718 -34.435944) (xy 419.30479 -34.504072) (xy 419.22861 -34.566271) (xy 419.147672 -34.622139)
			(xy 419.062501 -34.671312) (xy 418.973649 -34.713473) (xy 418.881693 -34.748347) (xy 418.787229 -34.775709)
			(xy 418.690869 -34.795381) (xy 418.593239 -34.807235) (xy 418.494972 -34.811196) (xy 418.396705 -34.807235)
			(xy 418.299075 -34.795381) (xy 418.202715 -34.775709) (xy 418.108251 -34.748347) (xy 418.016295 -34.713473)
			(xy 417.927443 -34.671312) (xy 417.842272 -34.622139) (xy 417.761334 -34.566271) (xy 417.685154 -34.504072)
			(xy 417.614226 -34.435944) (xy 417.549009 -34.362331) (xy 417.489928 -34.283708) (xy 417.437365 -34.200586)
			(xy 417.391661 -34.113504) (xy 417.353112 -34.023026) (xy 417.321969 -33.929741) (xy 417.298433 -33.834251)
			(xy 417.282657 -33.737178) (xy 417.274743 -33.63915) (xy 407.71446 -33.63915) (xy 407.706554 -33.737086)
			(xy 407.690788 -33.834099) (xy 407.667267 -33.929528) (xy 407.636143 -34.022756) (xy 407.597618 -34.113177)
			(xy 407.551943 -34.200205) (xy 407.499412 -34.283275) (xy 407.440368 -34.361848) (xy 407.375193 -34.435416)
			(xy 407.304309 -34.503501) (xy 407.228176 -34.565662) (xy 407.147289 -34.621494) (xy 407.062171 -34.670637)
			(xy 406.973374 -34.712771) (xy 406.881476 -34.747624) (xy 406.78707 -34.774969) (xy 406.690771 -34.794628)
			(xy 406.593202 -34.806475) (xy 406.494996 -34.810433) (xy 406.39679 -34.806475) (xy 406.299221 -34.794628)
			(xy 406.202922 -34.774969) (xy 406.108516 -34.747624) (xy 406.016618 -34.712771) (xy 405.927821 -34.670637)
			(xy 405.842703 -34.621494) (xy 405.761816 -34.565662) (xy 405.685683 -34.503501) (xy 405.614799 -34.435416)
			(xy 405.549624 -34.361848) (xy 405.49058 -34.283275) (xy 405.438049 -34.200205) (xy 405.392374 -34.113177)
			(xy 405.353849 -34.022756) (xy 405.322725 -33.929528) (xy 405.299204 -33.834099) (xy 405.283438 -33.737086)
			(xy 405.275529 -33.639119) (xy 400.705079 -33.639119) (xy 400.705079 -33.63915) (xy 400.697165 -33.737178)
			(xy 400.681389 -33.834251) (xy 400.657853 -33.929741) (xy 400.62671 -34.023026) (xy 400.588161 -34.113504)
			(xy 400.542457 -34.200586) (xy 400.489894 -34.283708) (xy 400.430813 -34.362331) (xy 400.365596 -34.435944)
			(xy 400.294668 -34.504072) (xy 400.218488 -34.566271) (xy 400.13755 -34.622139) (xy 400.052379 -34.671312)
			(xy 399.963527 -34.713473) (xy 399.871571 -34.748347) (xy 399.777107 -34.775709) (xy 399.680747 -34.795381)
			(xy 399.583117 -34.807235) (xy 399.48485 -34.811196) (xy 399.386583 -34.807235) (xy 399.288953 -34.795381)
			(xy 399.192593 -34.775709) (xy 399.098129 -34.748347) (xy 399.006173 -34.713473) (xy 398.917321 -34.671312)
			(xy 398.83215 -34.622139) (xy 398.751212 -34.566271) (xy 398.675032 -34.504072) (xy 398.604104 -34.435944)
			(xy 398.538887 -34.362331) (xy 398.479806 -34.283708) (xy 398.427243 -34.200586) (xy 398.381539 -34.113504)
			(xy 398.34299 -34.023026) (xy 398.311847 -33.929741) (xy 398.288311 -33.834251) (xy 398.272535 -33.737178)
			(xy 398.264621 -33.63915) (xy 388.704338 -33.63915) (xy 388.696432 -33.737086) (xy 388.680666 -33.834099)
			(xy 388.657145 -33.929528) (xy 388.626021 -34.022756) (xy 388.587496 -34.113177) (xy 388.541821 -34.200205)
			(xy 388.48929 -34.283275) (xy 388.430246 -34.361848) (xy 388.365071 -34.435416) (xy 388.294187 -34.503501)
			(xy 388.218054 -34.565662) (xy 388.137167 -34.621494) (xy 388.052049 -34.670637) (xy 387.963252 -34.712771)
			(xy 387.871354 -34.747624) (xy 387.776948 -34.774969) (xy 387.680649 -34.794628) (xy 387.58308 -34.806475)
			(xy 387.484874 -34.810433) (xy 387.386668 -34.806475) (xy 387.289099 -34.794628) (xy 387.1928 -34.774969)
			(xy 387.098394 -34.747624) (xy 387.006496 -34.712771) (xy 386.917699 -34.670637) (xy 386.832581 -34.621494)
			(xy 386.751694 -34.565662) (xy 386.675561 -34.503501) (xy 386.604677 -34.435416) (xy 386.539502 -34.361848)
			(xy 386.480458 -34.283275) (xy 386.427927 -34.200205) (xy 386.382252 -34.113177) (xy 386.343727 -34.022756)
			(xy 386.312603 -33.929528) (xy 386.289082 -33.834099) (xy 386.273316 -33.737086) (xy 386.265407 -33.639119)
			(xy 198.715135 -33.639119) (xy 198.715135 -33.63915) (xy 198.707221 -33.737178) (xy 198.691445 -33.834251)
			(xy 198.667909 -33.929741) (xy 198.636766 -34.023026) (xy 198.598217 -34.113504) (xy 198.552513 -34.200586)
			(xy 198.49995 -34.283708) (xy 198.440869 -34.362331) (xy 198.375652 -34.435944) (xy 198.304724 -34.504072)
			(xy 198.228544 -34.566271) (xy 198.147606 -34.622139) (xy 198.062435 -34.671312) (xy 197.973583 -34.713473)
			(xy 197.881627 -34.748347) (xy 197.787163 -34.775709) (xy 197.690803 -34.795381) (xy 197.593173 -34.807235)
			(xy 197.494906 -34.811196) (xy 197.396639 -34.807235) (xy 197.299009 -34.795381) (xy 197.202649 -34.775709)
			(xy 197.108185 -34.748347) (xy 197.016229 -34.713473) (xy 196.927377 -34.671312) (xy 196.842206 -34.622139)
			(xy 196.761268 -34.566271) (xy 196.685088 -34.504072) (xy 196.61416 -34.435944) (xy 196.548943 -34.362331)
			(xy 196.489862 -34.283708) (xy 196.437299 -34.200586) (xy 196.391595 -34.113504) (xy 196.353046 -34.023026)
			(xy 196.321903 -33.929741) (xy 196.298367 -33.834251) (xy 196.282591 -33.737178) (xy 196.274677 -33.63915)
			(xy 186.714394 -33.63915) (xy 186.706488 -33.737086) (xy 186.690722 -33.834099) (xy 186.667201 -33.929528)
			(xy 186.636077 -34.022756) (xy 186.597552 -34.113177) (xy 186.551877 -34.200205) (xy 186.499346 -34.283275)
			(xy 186.440302 -34.361848) (xy 186.375127 -34.435416) (xy 186.304243 -34.503501) (xy 186.22811 -34.565662)
			(xy 186.147223 -34.621494) (xy 186.062105 -34.670637) (xy 185.973308 -34.712771) (xy 185.88141 -34.747624)
			(xy 185.787004 -34.774969) (xy 185.690705 -34.794628) (xy 185.593136 -34.806475) (xy 185.49493 -34.810433)
			(xy 185.396724 -34.806475) (xy 185.299155 -34.794628) (xy 185.202856 -34.774969) (xy 185.10845 -34.747624)
			(xy 185.016552 -34.712771) (xy 184.927755 -34.670637) (xy 184.842637 -34.621494) (xy 184.76175 -34.565662)
			(xy 184.685617 -34.503501) (xy 184.614733 -34.435416) (xy 184.549558 -34.361848) (xy 184.490514 -34.283275)
			(xy 184.437983 -34.200205) (xy 184.392308 -34.113177) (xy 184.353783 -34.022756) (xy 184.322659 -33.929528)
			(xy 184.299138 -33.834099) (xy 184.283372 -33.737086) (xy 184.275463 -33.639119) (xy 179.705267 -33.639119)
			(xy 179.705267 -33.63915) (xy 179.697353 -33.737178) (xy 179.681577 -33.834251) (xy 179.658041 -33.929741)
			(xy 179.626898 -34.023026) (xy 179.588349 -34.113504) (xy 179.542645 -34.200586) (xy 179.490082 -34.283708)
			(xy 179.431001 -34.362331) (xy 179.365784 -34.435944) (xy 179.294856 -34.504072) (xy 179.218676 -34.566271)
			(xy 179.137738 -34.622139) (xy 179.052567 -34.671312) (xy 178.963715 -34.713473) (xy 178.871759 -34.748347)
			(xy 178.777295 -34.775709) (xy 178.680935 -34.795381) (xy 178.583305 -34.807235) (xy 178.485038 -34.811196)
			(xy 178.386771 -34.807235) (xy 178.289141 -34.795381) (xy 178.192781 -34.775709) (xy 178.098317 -34.748347)
			(xy 178.006361 -34.713473) (xy 177.917509 -34.671312) (xy 177.832338 -34.622139) (xy 177.7514 -34.566271)
			(xy 177.67522 -34.504072) (xy 177.604292 -34.435944) (xy 177.539075 -34.362331) (xy 177.479994 -34.283708)
			(xy 177.427431 -34.200586) (xy 177.381727 -34.113504) (xy 177.343178 -34.023026) (xy 177.312035 -33.929741)
			(xy 177.288499 -33.834251) (xy 177.272723 -33.737178) (xy 177.264809 -33.63915) (xy 167.704526 -33.63915)
			(xy 167.69662 -33.737086) (xy 167.680854 -33.834099) (xy 167.657333 -33.929528) (xy 167.626209 -34.022756)
			(xy 167.587684 -34.113177) (xy 167.542009 -34.200205) (xy 167.489478 -34.283275) (xy 167.430434 -34.361848)
			(xy 167.365259 -34.435416) (xy 167.294375 -34.503501) (xy 167.218242 -34.565662) (xy 167.137355 -34.621494)
			(xy 167.052237 -34.670637) (xy 166.96344 -34.712771) (xy 166.871542 -34.747624) (xy 166.777136 -34.774969)
			(xy 166.680837 -34.794628) (xy 166.583268 -34.806475) (xy 166.485062 -34.810433) (xy 166.386856 -34.806475)
			(xy 166.289287 -34.794628) (xy 166.192988 -34.774969) (xy 166.098582 -34.747624) (xy 166.006684 -34.712771)
			(xy 165.917887 -34.670637) (xy 165.832769 -34.621494) (xy 165.751882 -34.565662) (xy 165.675749 -34.503501)
			(xy 165.604865 -34.435416) (xy 165.53969 -34.361848) (xy 165.480646 -34.283275) (xy 165.428115 -34.200205)
			(xy 165.38244 -34.113177) (xy 165.343915 -34.022756) (xy 165.312791 -33.929528) (xy 165.28927 -33.834099)
			(xy 165.273504 -33.737086) (xy 165.265595 -33.639119) (xy 8.277861 -33.639119) (xy 8.31009 -33.728989)
			(xy 8.363106 -33.900614) (xy 8.408396 -34.074439) (xy 8.445868 -34.250114) (xy 8.475448 -34.42729)
			(xy 8.497076 -34.60561) (xy 8.51071 -34.78472) (xy 8.516322 -34.96426) (xy 8.5139 -35.143871) (xy 8.50345 -35.323194)
			(xy 8.484993 -35.501871) (xy 8.458565 -35.679543) (xy 8.424219 -35.855857) (xy 8.382024 -36.030458)
			(xy 8.332065 -36.202998) (xy 8.274441 -36.373132) (xy 8.209267 -36.540519) (xy 8.136675 -36.704825)
			(xy 8.056808 -36.865721) (xy 7.969828 -37.022884) (xy 7.875907 -37.176002) (xy 7.775234 -37.324767)
			(xy 7.66801 -37.468881) (xy 7.642576 -37.500052) (xy 9.403341 -37.500052) (xy 9.407346 -37.412144)
			(xy 9.419329 -37.324964) (xy 9.439189 -37.239235) (xy 9.466764 -37.155667) (xy 9.501823 -37.074953)
			(xy 9.544076 -36.997761) (xy 9.593174 -36.924732) (xy 9.64871 -36.85647) (xy 9.710222 -36.79354)
			(xy 9.777203 -36.736466) (xy 9.849096 -36.685718) (xy 9.925305 -36.641718) (xy 10.0052 -36.604831)
			(xy 10.088119 -36.575362) (xy 10.173374 -36.553555) (xy 10.260258 -36.539591) (xy 10.348052 -36.533585)
			(xy 10.436029 -36.535589) (xy 10.523459 -36.545584) (xy 10.609618 -36.563488) (xy 10.693792 -36.589152)
			(xy 10.775283 -36.622365) (xy 10.853417 -36.662851) (xy 10.927545 -36.710273) (xy 10.997053 -36.76424)
			(xy 11.061367 -36.824305) (xy 11.119951 -36.889969) (xy 11.172322 -36.960688) (xy 11.218045 -37.035876)
			(xy 11.256742 -37.114911) (xy 11.288091 -37.197137) (xy 11.311833 -37.281873) (xy 11.327771 -37.368417)
			(xy 11.335773 -37.456052) (xy 11.336274 -37.500052) (xy 11.335773 -37.544052) (xy 11.327771 -37.631687)
			(xy 11.311833 -37.718231) (xy 11.288091 -37.802967) (xy 11.256742 -37.885193) (xy 11.218045 -37.964228)
			(xy 11.172322 -38.039416) (xy 11.119951 -38.110135) (xy 11.061367 -38.175799) (xy 10.997053 -38.235864)
			(xy 10.927545 -38.289831) (xy 10.853417 -38.337253) (xy 10.775283 -38.377739) (xy 10.693792 -38.410952)
			(xy 10.609618 -38.436616) (xy 10.523459 -38.45452) (xy 10.436029 -38.464515) (xy 10.348052 -38.466519)
			(xy 10.260258 -38.460513) (xy 10.173374 -38.446549) (xy 10.088119 -38.424742) (xy 10.0052 -38.395273)
			(xy 9.925305 -38.358386) (xy 9.849096 -38.314386) (xy 9.777203 -38.263638) (xy 9.710222 -38.206564)
			(xy 9.64871 -38.143634) (xy 9.593174 -38.075372) (xy 9.544076 -38.002343) (xy 9.501823 -37.925151)
			(xy 9.466764 -37.844437) (xy 9.439189 -37.760869) (xy 9.419329 -37.67514) (xy 9.407346 -37.58796)
			(xy 9.403341 -37.500052) (xy 7.642576 -37.500052) (xy 7.554449 -37.608058) (xy 7.43478 -37.742018)
			(xy 7.30924 -37.870493) (xy 7.178081 -37.993226) (xy 7.041566 -38.109972) (xy 6.899968 -38.220498)
			(xy 6.753569 -38.324582) (xy 6.602663 -38.422016) (xy 6.447551 -38.512605) (xy 6.288544 -38.596168)
			(xy 6.12596 -38.672538) (xy 5.960123 -38.741562) (xy 5.791367 -38.803103) (xy 5.620027 -38.857036)
			(xy 5.446447 -38.903254) (xy 5.270975 -38.941665) (xy 5.09396 -38.972192) (xy 4.915758 -38.994773)
			(xy 4.736724 -39.009364) (xy 4.557216 -39.015936) (xy 4.377595 -39.014474) (xy 4.198218 -39.004983)
			(xy 4.019445 -38.987481) (xy 3.841634 -38.962004) (xy 3.665139 -38.928601) (xy 3.490315 -38.88734)
			(xy 3.31751 -38.838304) (xy 3.147071 -38.78159) (xy 2.979337 -38.717313) (xy 2.814646 -38.6456) (xy 2.653326 -38.566594)
			(xy 2.495699 -38.480455) (xy 2.342082 -38.387355) (xy 2.192781 -38.287478) (xy 2.048095 -38.181026)
			(xy 1.908313 -38.068212) (xy 1.773716 -37.94926) (xy 1.644571 -37.824409) (xy 1.521138 -37.693908)
			(xy 1.462024 -37.62629) (xy 1.447247 -37.609935) (xy 1.413088 -37.582086) (xy 1.374636 -37.560548)
			(xy 1.333044 -37.545968) (xy 1.28956 -37.538784) (xy 1.245489 -37.539211) (xy 1.202153 -37.547236)
			(xy 1.160851 -37.562619) (xy 1.122823 -37.584897) (xy 1.08921 -37.613403) (xy 1.06102 -37.647282)
			(xy 1.039098 -37.685516) (xy 1.024102 -37.72696) (xy 1.016483 -37.77037) (xy 1.016 -37.792406) (xy 1.016 -46.4058)
			(xy 1.016543 -46.422448) (xy 1.025161 -46.454611) (xy 1.041809 -46.483446) (xy 1.065354 -46.506991)
			(xy 1.094189 -46.523639) (xy 1.126352 -46.532257) (xy 1.143 -46.5328) (xy 9.307068 -46.5328) (xy 9.323726 -46.532309)
			(xy 9.355907 -46.523693) (xy 9.384761 -46.507041) (xy 9.408321 -46.483487) (xy 9.424981 -46.454637)
			(xy 9.433605 -46.422457) (xy 9.434068 -46.4058) (xy 9.434068 -42.650664) (xy 9.434569 -42.598323)
			(xy 9.442583 -42.493948) (xy 9.458562 -42.390492) (xy 9.482415 -42.288563) (xy 9.513999 -42.188759)
			(xy 9.553131 -42.091666) (xy 9.599581 -41.997853) (xy 9.653076 -41.907872) (xy 9.713302 -41.822249)
			(xy 9.779905 -41.741487) (xy 9.852495 -41.666062) (xy 9.930646 -41.596414) (xy 10.013899 -41.532952)
			(xy 10.101766 -41.476051) (xy 10.193731 -41.426042) (xy 10.289254 -41.383219) (xy 10.387775 -41.347835)
			(xy 10.488715 -41.320096) (xy 10.591483 -41.300165) (xy 10.695474 -41.28816) (xy 10.80008 -41.284151)
			(xy 10.904686 -41.28816) (xy 11.008677 -41.300165) (xy 11.111445 -41.320096) (xy 11.212385 -41.347835)
			(xy 11.310906 -41.383219) (xy 11.406429 -41.426042) (xy 11.498394 -41.476051) (xy 11.586261 -41.532952)
			(xy 11.669514 -41.596414) (xy 11.747665 -41.666062) (xy 11.820255 -41.741487) (xy 11.886858 -41.822249)
			(xy 11.947084 -41.907872) (xy 12.000579 -41.997853) (xy 12.047029 -42.091666) (xy 12.086161 -42.188759)
			(xy 12.117745 -42.288563) (xy 12.141598 -42.390492) (xy 12.157577 -42.493948) (xy 12.165591 -42.598323)
			(xy 12.166092 -42.650664) (xy 12.166092 -45.1104) (xy 12.166635 -45.127049) (xy 12.175253 -45.159212)
			(xy 12.191901 -45.188049) (xy 12.215445 -45.211594) (xy 12.244281 -45.228244) (xy 12.276443 -45.236864)
			(xy 12.293092 -45.2374) (xy 50.936906 -45.2374) (xy 50.953554 -45.236856) (xy 50.985715 -45.228237)
			(xy 51.014549 -45.211588) (xy 51.038092 -45.188044) (xy 51.05474 -45.159209) (xy 51.063357 -45.127048)
			(xy 51.063906 -45.1104) (xy 51.063906 -43.319954) (xy 51.064393 -43.256614) (xy 51.072347 -43.130184)
			(xy 51.088224 -43.004503) (xy 51.111962 -42.880067) (xy 51.143466 -42.757366) (xy 51.182612 -42.636887)
			(xy 51.229246 -42.519102) (xy 51.283183 -42.404479) (xy 51.344212 -42.293468) (xy 51.41209 -42.186509)
			(xy 51.486551 -42.084023) (xy 51.5673 -41.986414) (xy 51.654018 -41.894068) (xy 51.746364 -41.80735)
			(xy 51.843973 -41.726601) (xy 51.946459 -41.65214) (xy 52.053418 -41.584262) (xy 52.164429 -41.523233)
			(xy 52.279052 -41.469296) (xy 52.396837 -41.422662) (xy 52.517316 -41.383516) (xy 52.640017 -41.352012)
			(xy 52.764453 -41.328274) (xy 52.890134 -41.312397) (xy 53.016564 -41.304443) (xy 53.079904 -41.303956)
			(xy 55.0799 -41.303956) (xy 55.14324 -41.304454) (xy 55.269671 -41.312408) (xy 55.395352 -41.328285)
			(xy 55.519789 -41.352022) (xy 55.642489 -41.383526) (xy 55.76297 -41.422671) (xy 55.880754 -41.469305)
			(xy 55.995378 -41.523242) (xy 56.10639 -41.58427) (xy 56.21335 -41.652148) (xy 56.315837 -41.726608)
			(xy 56.413447 -41.807356) (xy 56.505794 -41.894074) (xy 56.592514 -41.986419) (xy 56.673264 -42.084026)
			(xy 56.747726 -42.186512) (xy 56.815607 -42.293471) (xy 56.876637 -42.404481) (xy 56.930577 -42.519104)
			(xy 56.977213 -42.636887) (xy 57.016362 -42.757367) (xy 57.047868 -42.880066) (xy 57.071608 -43.004503)
			(xy 57.087488 -43.130184) (xy 57.095445 -43.256614) (xy 57.095898 -43.319954) (xy 57.095898 -50.31994)
			(xy 57.096425 -50.365408) (xy 57.104819 -50.455954) (xy 57.121531 -50.54534) (xy 57.146419 -50.632803)
			(xy 57.179272 -50.717597) (xy 57.219807 -50.798997) (xy 57.26768 -50.876311) (xy 57.322482 -50.948877)
			(xy 57.383746 -51.016078) (xy 57.450949 -51.07734) (xy 57.523517 -51.132139) (xy 57.600832 -51.18001)
			(xy 57.682234 -51.220542) (xy 57.767029 -51.253391) (xy 57.854493 -51.278277) (xy 57.943879 -51.294986)
			(xy 58.034426 -51.303377) (xy 58.079894 -51.303936)
		)
		(stroke
			(width 0)
			(type solid)
		)
		(fill yes)
		(layer "In4.Cu")
		(net "P12V")
	)
	(gr_line
		(start 0.1778 -46.8376)
		(end 10.541 -46.8376)
		(stroke
			(width 0.508)
			(type default)
		)
		(layer "In4.Cu")
	)
	(gr_line
		(start 0.7366 -49.1744)
		(end 9.271 -49.1744)
		(stroke
			(width 2.54)
			(type default)
		)
		(layer "In4.Cu")
	)
	(gr_line
		(start 0.762 -51.3334)
		(end 9.2964 -51.3334)
		(stroke
			(width 2.54)
			(type default)
		)
		(layer "In4.Cu")
	)
	(gr_line
		(start 0.762 -50.3174)
		(end 9.2964 -50.3174)
		(stroke
			(width 2.54)
			(type default)
		)
		(layer "In4.Cu")
	)
	(gr_line
		(start 0.762 -49.911)
		(end 9.2964 -49.911)
		(stroke
			(width 2.54)
			(type default)
		)
		(layer "In4.Cu")
	)
	(gr_line
		(start 0.7874 -50.8508)
		(end 9.3218 -50.8508)
		(stroke
			(width 2.54)
			(type default)
		)
		(layer "In4.Cu")
	)
	(gr_line
		(start 0.7874 -50.3682)
		(end 9.3218 -50.3682)
		(stroke
			(width 2.54)
			(type default)
		)
		(layer "In4.Cu")
	)
	(gr_line
		(start 0.7874 -49.5046)
		(end 9.3218 -49.5046)
		(stroke
			(width 2.54)
			(type default)
		)
		(layer "In4.Cu")
	)
	(gr_line
		(start 0.7874 -48.6156)
		(end 9.3218 -48.6156)
		(stroke
			(width 2.54)
			(type default)
		)
		(layer "In4.Cu")
	)
	(gr_line
		(start 0.7874 -48.0822)
		(end 9.3218 -48.0822)
		(stroke
			(width 2.54)
			(type default)
		)
		(layer "In4.Cu")
	)
	(gr_line
		(start 0.8128 -48.3108)
		(end 9.3472 -48.3108)
		(stroke
			(width 2.54)
			(type default)
		)
		(layer "In4.Cu")
	)
	(gr_line
		(start 0.8128 -48.26)
		(end 9.3472 -48.26)
		(stroke
			(width 2.54)
			(type default)
		)
		(layer "In4.Cu")
	)
	(gr_line
		(start 0.8128 -47.9044)
		(end 9.3472 -47.9044)
		(stroke
			(width 2.54)
			(type default)
		)
		(layer "In4.Cu")
	)
	(gr_line
		(start 0.8382 -48.8442)
		(end 9.3726 -48.8442)
		(stroke
			(width 2.54)
			(type default)
		)
		(layer "In4.Cu")
	)
	(gr_line
		(start 0.8382 -48.5394)
		(end 9.3726 -48.5394)
		(stroke
			(width 2.54)
			(type default)
		)
		(layer "In4.Cu")
	)
	(gr_line
		(start 0.8382 -48.4378)
		(end 9.3726 -48.4378)
		(stroke
			(width 2.54)
			(type default)
		)
		(layer "In4.Cu")
	)
	(gr_line
		(start 0.8382 -48.0822)
		(end 9.3726 -48.0822)
		(stroke
			(width 2.54)
			(type default)
		)
		(layer "In4.Cu")
	)
	(gr_line
		(start 0.8636 -49.0982)
		(end 9.398 -49.0982)
		(stroke
			(width 2.54)
			(type default)
		)
		(layer "In4.Cu")
	)
	(gr_line
		(start 0.8636 -48.9204)
		(end 9.398 -48.9204)
		(stroke
			(width 2.54)
			(type default)
		)
		(layer "In4.Cu")
	)
	(gr_line
		(start 0.8636 -48.7172)
		(end 9.398 -48.7172)
		(stroke
			(width 2.54)
			(type default)
		)
		(layer "In4.Cu")
	)
	(gr_line
		(start 0.8636 -48.641)
		(end 9.398 -48.641)
		(stroke
			(width 2.54)
			(type default)
		)
		(layer "In4.Cu")
	)
	(gr_line
		(start 0.889 -51.5366)
		(end 9.4234 -51.5366)
		(stroke
			(width 2.54)
			(type default)
		)
		(layer "In4.Cu")
	)
	(gr_line
		(start 0.9144 -49.8856)
		(end 9.4488 -49.8856)
		(stroke
			(width 2.54)
			(type default)
		)
		(layer "In4.Cu")
	)
	(gr_line
		(start 0.9144 -49.2506)
		(end 9.4488 -49.2506)
		(stroke
			(width 2.54)
			(type default)
		)
		(layer "In4.Cu")
	)
	(gr_line
		(start 0.9398 -51.2572)
		(end 9.4742 -51.2572)
		(stroke
			(width 2.54)
			(type default)
		)
		(layer "In4.Cu")
	)
	(gr_line
		(start 0.9398 -49.7332)
		(end 9.4742 -49.7332)
		(stroke
			(width 2.54)
			(type default)
		)
		(layer "In4.Cu")
	)
	(gr_line
		(start 0.9398 -49.5808)
		(end 9.4742 -49.5808)
		(stroke
			(width 2.54)
			(type default)
		)
		(layer "In4.Cu")
	)
	(gr_line
		(start 0.9398 -49.3522)
		(end 9.4742 -49.3522)
		(stroke
			(width 2.54)
			(type default)
		)
		(layer "In4.Cu")
	)
	(gr_line
		(start 0.9652 -51.3588)
		(end 9.4996 -51.3588)
		(stroke
			(width 2.54)
			(type default)
		)
		(layer "In4.Cu")
	)
	(gr_line
		(start 0.9652 -50.4698)
		(end 9.4996 -50.4698)
		(stroke
			(width 2.54)
			(type default)
		)
		(layer "In4.Cu")
	)
	(gr_line
		(start 0.9652 -50.3682)
		(end 9.4996 -50.3682)
		(stroke
			(width 2.54)
			(type default)
		)
		(layer "In4.Cu")
	)
	(gr_line
		(start 0.9652 -50.1142)
		(end 9.4996 -50.1142)
		(stroke
			(width 2.54)
			(type default)
		)
		(layer "In4.Cu")
	)
	(gr_line
		(start 0.9906 -51.435)
		(end 5.8674 -51.435)
		(stroke
			(width 2.54)
			(type default)
		)
		(layer "In4.Cu")
	)
	(gr_line
		(start 0.9906 -51.1048)
		(end 9.525 -51.1048)
		(stroke
			(width 2.54)
			(type default)
		)
		(layer "In4.Cu")
	)
	(gr_line
		(start 0.9906 -50.8)
		(end 9.525 -50.8)
		(stroke
			(width 2.54)
			(type default)
		)
		(layer "In4.Cu")
	)
	(gr_line
		(start 0.9906 -50.6476)
		(end 9.525 -50.6476)
		(stroke
			(width 2.54)
			(type default)
		)
		(layer "In4.Cu")
	)
	(gr_line
		(start 1.016 -50.9524)
		(end 9.5504 -50.9524)
		(stroke
			(width 2.54)
			(type default)
		)
		(layer "In4.Cu")
	)
	(gr_line
		(start 1.0414 -51.1556)
		(end 9.5758 -51.1556)
		(stroke
			(width 2.54)
			(type default)
		)
		(layer "In4.Cu")
	)
	(gr_line
		(start 1.0414 -50.9016)
		(end 9.5758 -50.9016)
		(stroke
			(width 2.54)
			(type default)
		)
		(layer "In4.Cu")
	)
	(gr_line
		(start 1.0414 -50.0888)
		(end 9.5758 -50.0888)
		(stroke
			(width 2.54)
			(type default)
		)
		(layer "In4.Cu")
	)
	(gr_line
		(start 1.0668 -50.6984)
		(end 9.6012 -50.6984)
		(stroke
			(width 2.54)
			(type default)
		)
		(layer "In4.Cu")
	)
	(gr_line
		(start 1.0668 -50.4952)
		(end 9.6012 -50.4952)
		(stroke
			(width 2.54)
			(type default)
		)
		(layer "In4.Cu")
	)
	(gr_line
		(start 1.0668 -50.2412)
		(end 9.6012 -50.2412)
		(stroke
			(width 2.54)
			(type default)
		)
		(layer "In4.Cu")
	)
	(gr_line
		(start 1.1938 -50.3682)
		(end 9.7282 -50.3682)
		(stroke
			(width 2.54)
			(type default)
		)
		(layer "In4.Cu")
	)
	(gr_line
		(start 1.2192 -50.3428)
		(end 9.7536 -50.3428)
		(stroke
			(width 2.54)
			(type default)
		)
		(layer "In4.Cu")
	)
	(gr_line
		(start 1.2192 -49.8602)
		(end 9.7536 -49.8602)
		(stroke
			(width 2.54)
			(type default)
		)
		(layer "In4.Cu")
	)
	(gr_line
		(start 1.2446 -48.7934)
		(end 9.779 -48.7934)
		(stroke
			(width 2.54)
			(type default)
		)
		(layer "In4.Cu")
	)
	(gr_line
		(start 1.4732 -52.1462)
		(end 6.35 -52.1462)
		(stroke
			(width 2.54)
			(type default)
		)
		(layer "In4.Cu")
	)
	(gr_line
		(start 1.49987 -53.299868)
		(end 0 -51.799998)
		(stroke
			(width 2.032)
			(type default)
		)
		(layer "In4.Cu")
	)
	(gr_line
		(start 1.8542 -52.5272)
		(end 6.731 -52.5272)
		(stroke
			(width 2.54)
			(type default)
		)
		(layer "In4.Cu")
	)
	(gr_arc
		(start 1.999996 0)
		(mid 0.585785 -0.585785)
		(end 0 -1.999996)
		(stroke
			(width 2.032)
			(type default)
		)
		(layer "In4.Cu")
	)
	(gr_line
		(start 1.999996 0)
		(end 426.809916 0)
		(stroke
			(width 2.032)
			(type default)
		)
		(layer "In4.Cu")
	)
	(gr_line
		(start 2.2098 -2.0574)
		(end 2.2098 -2.057654)
		(stroke
			(width 5.588)
			(type default)
		)
		(layer "In4.Cu")
	)
	(gr_line
		(start 2.5654 -52.2478)
		(end 7.4422 -52.2478)
		(stroke
			(width 2.54)
			(type default)
		)
		(layer "In4.Cu")
	)
	(gr_arc
		(start 2.750058 -32.563308)
		(mid 4.372855 -37.997202)
		(end 6.45033 -32.720534)
		(stroke
			(width 2.032)
			(type default)
		)
		(layer "In4.Cu")
	)
	(gr_line
		(start 2.750058 -29.207714)
		(end 2.750058 -32.563308)
		(stroke
			(width 2.032)
			(type default)
		)
		(layer "In4.Cu")
	)
	(gr_line
		(start 2.760726 -29.197046)
		(end 2.750058 -29.207714)
		(stroke
			(width 2.032)
			(type default)
		)
		(layer "In4.Cu")
	)
	(gr_line
		(start 3.6576 -52.5018)
		(end 8.5344 -52.5018)
		(stroke
			(width 2.54)
			(type default)
		)
		(layer "In4.Cu")
	)
	(gr_line
		(start 4.2418 -49.5554)
		(end 12.7762 -49.5554)
		(stroke
			(width 2.54)
			(type default)
		)
		(layer "In4.Cu")
	)
	(gr_line
		(start 4.2672 -49.7586)
		(end 12.8016 -49.7586)
		(stroke
			(width 2.54)
			(type default)
		)
		(layer "In4.Cu")
	)
	(gr_line
		(start 4.2926 -49.2506)
		(end 12.827 -49.2506)
		(stroke
			(width 2.54)
			(type default)
		)
		(layer "In4.Cu")
	)
	(gr_line
		(start 4.318 -48.8188)
		(end 12.8524 -48.8188)
		(stroke
			(width 2.54)
			(type default)
		)
		(layer "In4.Cu")
	)
	(gr_line
		(start 4.3434 -50.8254)
		(end 12.8778 -50.8254)
		(stroke
			(width 2.54)
			(type default)
		)
		(layer "In4.Cu")
	)
	(gr_line
		(start 4.3434 -48.895)
		(end 12.8778 -48.895)
		(stroke
			(width 2.54)
			(type default)
		)
		(layer "In4.Cu")
	)
	(gr_line
		(start 4.3688 -50.6222)
		(end 12.9032 -50.6222)
		(stroke
			(width 2.54)
			(type default)
		)
		(layer "In4.Cu")
	)
	(gr_line
		(start 4.3688 -50.4444)
		(end 12.9032 -50.4444)
		(stroke
			(width 2.54)
			(type default)
		)
		(layer "In4.Cu")
	)
	(gr_line
		(start 4.3688 -50.1142)
		(end 12.9032 -50.1142)
		(stroke
			(width 2.54)
			(type default)
		)
		(layer "In4.Cu")
	)
	(gr_line
		(start 4.3942 -51.8668)
		(end 9.271 -51.8668)
		(stroke
			(width 2.54)
			(type default)
		)
		(layer "In4.Cu")
	)
	(gr_line
		(start 4.3942 -49.9364)
		(end 12.9286 -49.9364)
		(stroke
			(width 2.54)
			(type default)
		)
		(layer "In4.Cu")
	)
	(gr_line
		(start 4.3942 -48.4632)
		(end 12.9286 -48.4632)
		(stroke
			(width 2.54)
			(type default)
		)
		(layer "In4.Cu")
	)
	(gr_line
		(start 4.4196 -48.2092)
		(end 12.954 -48.2092)
		(stroke
			(width 2.54)
			(type default)
		)
		(layer "In4.Cu")
	)
	(gr_line
		(start 4.445 -48.5394)
		(end 12.9794 -48.5394)
		(stroke
			(width 2.54)
			(type default)
		)
		(layer "In4.Cu")
	)
	(gr_line
		(start 4.445 -48.4378)
		(end 12.9794 -48.4378)
		(stroke
			(width 2.54)
			(type default)
		)
		(layer "In4.Cu")
	)
	(gr_line
		(start 4.445 -48.0314)
		(end 12.9794 -48.0314)
		(stroke
			(width 2.54)
			(type default)
		)
		(layer "In4.Cu")
	)
	(gr_line
		(start 4.445 -47.9044)
		(end 12.9794 -47.9044)
		(stroke
			(width 2.54)
			(type default)
		)
		(layer "In4.Cu")
	)
	(gr_line
		(start 4.4704 -48.8442)
		(end 13.0048 -48.8442)
		(stroke
			(width 2.54)
			(type default)
		)
		(layer "In4.Cu")
	)
	(gr_line
		(start 4.49961 -34.99993)
		(end 4.499864 -35.000184)
		(stroke
			(width 4.064)
			(type default)
		)
		(layer "In4.Cu")
	)
	(gr_line
		(start 4.49961 -28.999688)
		(end 4.49961 -34.99993)
		(stroke
			(width 4.064)
			(type default)
		)
		(layer "In4.Cu")
	)
	(gr_line
		(start 4.499864 -35.000184)
		(end 4.499864 -34.99993)
		(stroke
			(width 6.604)
			(type default)
		)
		(layer "In4.Cu")
	)
	(gr_line
		(start 4.500118 -4.700016)
		(end 4.500118 -4.699762)
		(stroke
			(width 8.128)
			(type default)
		)
		(layer "In4.Cu")
	)
	(gr_line
		(start 4.6736 -49.0728)
		(end 13.208 -49.0728)
		(stroke
			(width 2.54)
			(type default)
		)
		(layer "In4.Cu")
	)
	(gr_line
		(start 4.826 -49.4284)
		(end 13.3604 -49.4284)
		(stroke
			(width 2.54)
			(type default)
		)
		(layer "In4.Cu")
	)
	(gr_line
		(start 4.8514 -49.5808)
		(end 13.3858 -49.5808)
		(stroke
			(width 2.54)
			(type default)
		)
		(layer "In4.Cu")
	)
	(gr_line
		(start 4.8514 -48.7934)
		(end 13.3858 -48.7934)
		(stroke
			(width 2.54)
			(type default)
		)
		(layer "In4.Cu")
	)
	(gr_line
		(start 4.9022 -49.8856)
		(end 13.4366 -49.8856)
		(stroke
			(width 2.54)
			(type default)
		)
		(layer "In4.Cu")
	)
	(gr_line
		(start 4.9276 -50.2666)
		(end 13.462 -50.2666)
		(stroke
			(width 2.54)
			(type default)
		)
		(layer "In4.Cu")
	)
	(gr_line
		(start 4.953 -50.419)
		(end 13.4874 -50.419)
		(stroke
			(width 2.54)
			(type default)
		)
		(layer "In4.Cu")
	)
	(gr_line
		(start 4.953 -50.0634)
		(end 13.4874 -50.0634)
		(stroke
			(width 2.54)
			(type default)
		)
		(layer "In4.Cu")
	)
	(gr_line
		(start 5.0038 -50.7238)
		(end 13.5382 -50.7238)
		(stroke
			(width 2.54)
			(type default)
		)
		(layer "In4.Cu")
	)
	(gr_line
		(start 5.0546 -51.181)
		(end 9.9314 -51.181)
		(stroke
			(width 2.54)
			(type default)
		)
		(layer "In4.Cu")
	)
	(gr_line
		(start 6.249924 -32.520128)
		(end 6.249924 -28.999942)
		(stroke
			(width 2.032)
			(type default)
		)
		(layer "In4.Cu")
	)
	(gr_arc
		(start 6.249924 -28.999942)
		(mid 4.401168 -27.252413)
		(end 2.760726 -29.197046)
		(stroke
			(width 2.032)
			(type default)
		)
		(layer "In4.Cu")
	)
	(gr_line
		(start 6.45033 -32.720534)
		(end 6.249924 -32.520128)
		(stroke
			(width 2.032)
			(type default)
		)
		(layer "In4.Cu")
	)
	(gr_line
		(start 8.950198 -53.299868)
		(end 1.49987 -53.299868)
		(stroke
			(width 2.032)
			(type default)
		)
		(layer "In4.Cu")
	)
	(gr_line
		(start 10.450068 -51.799998)
		(end 8.950198 -53.299868)
		(stroke
			(width 2.032)
			(type default)
		)
		(layer "In4.Cu")
	)
	(gr_line
		(start 10.450068 -42.650664)
		(end 10.450068 -51.799998)
		(stroke
			(width 2.032)
			(type default)
		)
		(layer "In4.Cu")
	)
	(gr_arc
		(start 10.450068 -42.650664)
		(mid 11.047577 -42.898154)
		(end 10.80008 -42.300652)
		(stroke
			(width 2.032)
			(type default)
		)
		(layer "In4.Cu")
	)
	(gr_line
		(start 10.541 -46.8376)
		(end 10.9982 -46.3804)
		(stroke
			(width 0.508)
			(type default)
		)
		(layer "In4.Cu")
	)
	(gr_line
		(start 10.7188 -45.6692)
		(end 10.7696 -45.6184)
		(stroke
			(width 0.762)
			(type default)
		)
		(layer "In4.Cu")
	)
	(gr_line
		(start 10.7696 -45.72)
		(end 10.7188 -45.6692)
		(stroke
			(width 0.762)
			(type default)
		)
		(layer "In4.Cu")
	)
	(gr_line
		(start 10.7696 -45.6184)
		(end 51.9176 -45.6184)
		(stroke
			(width 0.762)
			(type default)
		)
		(layer "In4.Cu")
	)
	(gr_line
		(start 10.9982 -46.3804)
		(end 11.4554 -45.9232)
		(stroke
			(width 1.27)
			(type default)
		)
		(layer "In4.Cu")
	)
	(gr_line
		(start 11.150092 -51.799998)
		(end 12.649962 -53.299868)
		(stroke
			(width 2.032)
			(type default)
		)
		(layer "In4.Cu")
	)
	(gr_arc
		(start 11.150092 -42.650664)
		(mid 11.047562 -42.403198)
		(end 10.80008 -42.300652)
		(stroke
			(width 2.032)
			(type default)
		)
		(layer "In4.Cu")
	)
	(gr_line
		(start 11.150092 -42.650664)
		(end 11.150092 -51.799998)
		(stroke
			(width 2.032)
			(type default)
		)
		(layer "In4.Cu")
	)
	(gr_line
		(start 11.1506 -45.7962)
		(end 11.3284 -45.6184)
		(stroke
			(width 0.762)
			(type default)
		)
		(layer "In4.Cu")
	)
	(gr_line
		(start 11.303 -45.9486)
		(end 11.1506 -45.7962)
		(stroke
			(width 1.27)
			(type default)
		)
		(layer "In4.Cu")
	)
	(gr_line
		(start 11.3284 -45.6184)
		(end 51.9176 -45.6184)
		(stroke
			(width 0.762)
			(type default)
		)
		(layer "In4.Cu")
	)
	(gr_line
		(start 11.4554 -45.9232)
		(end 51.943 -45.9232)
		(stroke
			(width 1.27)
			(type default)
		)
		(layer "In4.Cu")
	)
	(gr_line
		(start 11.5062 -50.7238)
		(end 11.5062 -46.5836)
		(stroke
			(width 2.54)
			(type default)
		)
		(layer "In4.Cu")
	)
	(gr_line
		(start 11.5062 -50.6222)
		(end 11.5062 -46.482)
		(stroke
			(width 2.54)
			(type default)
		)
		(layer "In4.Cu")
	)
	(gr_line
		(start 12.192 -51.6382)
		(end 12.192 -47.498)
		(stroke
			(width 2.54)
			(type default)
		)
		(layer "In4.Cu")
	)
	(gr_line
		(start 12.3444 -51.5874)
		(end 12.3444 -47.4472)
		(stroke
			(width 2.54)
			(type default)
		)
		(layer "In4.Cu")
	)
	(gr_line
		(start 12.649962 -53.299868)
		(end 50.580036 -53.299868)
		(stroke
			(width 2.032)
			(type default)
		)
		(layer "In4.Cu")
	)
	(gr_line
		(start 13.0302 -52.578)
		(end 13.0302 -48.4378)
		(stroke
			(width 2.54)
			(type default)
		)
		(layer "In4.Cu")
	)
	(gr_line
		(start 13.6906 -49.3268)
		(end 42.545 -49.3268)
		(stroke
			(width 7.62)
			(type default)
		)
		(layer "In4.Cu")
	)
	(gr_line
		(start 13.716 -52.197)
		(end 13.716 -48.0568)
		(stroke
			(width 2.54)
			(type default)
		)
		(layer "In4.Cu")
	)
	(gr_line
		(start 13.843 -49.276)
		(end 42.6974 -49.276)
		(stroke
			(width 7.62)
			(type default)
		)
		(layer "In4.Cu")
	)
	(gr_line
		(start 14.1986 -49.9872)
		(end 43.053 -49.9872)
		(stroke
			(width 7.62)
			(type default)
		)
		(layer "In4.Cu")
	)
	(gr_line
		(start 14.6304 -52.4002)
		(end 14.6304 -48.26)
		(stroke
			(width 2.54)
			(type default)
		)
		(layer "In4.Cu")
	)
	(gr_line
		(start 15.5448 -49.276)
		(end 44.3992 -49.276)
		(stroke
			(width 7.62)
			(type default)
		)
		(layer "In4.Cu")
	)
	(gr_line
		(start 15.9258 -52.5272)
		(end 15.9258 -48.387)
		(stroke
			(width 2.54)
			(type default)
		)
		(layer "In4.Cu")
	)
	(gr_line
		(start 18.4912 -49.5808)
		(end 47.3456 -49.5808)
		(stroke
			(width 7.62)
			(type default)
		)
		(layer "In4.Cu")
	)
	(gr_line
		(start 18.6436 -49.4792)
		(end 47.498 -49.4792)
		(stroke
			(width 7.62)
			(type default)
		)
		(layer "In4.Cu")
	)
	(gr_line
		(start 18.9738 -49.3776)
		(end 47.8282 -49.3776)
		(stroke
			(width 7.62)
			(type default)
		)
		(layer "In4.Cu")
	)
	(gr_line
		(start 19.3294 -49.9872)
		(end 48.1838 -49.9872)
		(stroke
			(width 7.62)
			(type default)
		)
		(layer "In4.Cu")
	)
	(gr_line
		(start 19.7866 -49.8348)
		(end 48.641 -49.8348)
		(stroke
			(width 7.62)
			(type default)
		)
		(layer "In4.Cu")
	)
	(gr_line
		(start 19.7866 -49.276)
		(end 48.641 -49.276)
		(stroke
			(width 7.62)
			(type default)
		)
		(layer "In4.Cu")
	)
	(gr_line
		(start 19.8882 -49.022)
		(end 48.7426 -49.022)
		(stroke
			(width 7.62)
			(type default)
		)
		(layer "In4.Cu")
	)
	(gr_line
		(start 49.9872 -52.5272)
		(end 49.9872 -48.387)
		(stroke
			(width 2.54)
			(type default)
		)
		(layer "In4.Cu")
	)
	(gr_line
		(start 50.038 -51.1556)
		(end 50.038 -47.0154)
		(stroke
			(width 2.54)
			(type default)
		)
		(layer "In4.Cu")
	)
	(gr_line
		(start 50.3174 -52.451)
		(end 50.3174 -48.3108)
		(stroke
			(width 2.54)
			(type default)
		)
		(layer "In4.Cu")
	)
	(gr_line
		(start 50.546 -52.2224)
		(end 50.546 -48.0822)
		(stroke
			(width 2.54)
			(type default)
		)
		(layer "In4.Cu")
	)
	(gr_line
		(start 50.580036 -53.299868)
		(end 52.079906 -51.799998)
		(stroke
			(width 2.032)
			(type default)
		)
		(layer "In4.Cu")
	)
	(gr_line
		(start 50.8254 -51.8922)
		(end 50.8254 -47.752)
		(stroke
			(width 2.54)
			(type default)
		)
		(layer "In4.Cu")
	)
	(gr_line
		(start 50.927 -50.7746)
		(end 50.927 -46.6344)
		(stroke
			(width 2.54)
			(type default)
		)
		(layer "In4.Cu")
	)
	(gr_line
		(start 51.0286 -50.6984)
		(end 51.0286 -46.5582)
		(stroke
			(width 2.54)
			(type default)
		)
		(layer "In4.Cu")
	)
	(gr_line
		(start 51.2318 -51.4858)
		(end 51.2318 -47.3456)
		(stroke
			(width 2.54)
			(type default)
		)
		(layer "In4.Cu")
	)
	(gr_line
		(start 51.2826 -50.7238)
		(end 51.2826 -46.5836)
		(stroke
			(width 2.54)
			(type default)
		)
		(layer "In4.Cu")
	)
	(gr_line
		(start 51.816 -45.72)
		(end 10.7696 -45.72)
		(stroke
			(width 0.762)
			(type default)
		)
		(layer "In4.Cu")
	)
	(gr_line
		(start 51.9176 -45.9486)
		(end 11.303 -45.9486)
		(stroke
			(width 1.27)
			(type default)
		)
		(layer "In4.Cu")
	)
	(gr_line
		(start 51.9176 -45.6184)
		(end 51.816 -45.72)
		(stroke
			(width 0.762)
			(type default)
		)
		(layer "In4.Cu")
	)
	(gr_line
		(start 51.943 -45.9232)
		(end 51.9176 -45.9486)
		(stroke
			(width 1.27)
			(type default)
		)
		(layer "In4.Cu")
	)
	(gr_line
		(start 52.079906 -51.799998)
		(end 52.079906 -43.319954)
		(stroke
			(width 2.032)
			(type default)
		)
		(layer "In4.Cu")
	)
	(gr_arc
		(start 53.079904 -42.319956)
		(mid 52.37278 -42.612844)
		(end 52.079906 -43.319954)
		(stroke
			(width 2.032)
			(type default)
		)
		(layer "In4.Cu")
	)
	(gr_line
		(start 53.079904 -42.319956)
		(end 55.0799 -42.319956)
		(stroke
			(width 2.032)
			(type default)
		)
		(layer "In4.Cu")
	)
	(gr_arc
		(start 56.079898 -50.31994)
		(mid 56.665683 -51.734151)
		(end 58.079894 -52.319936)
		(stroke
			(width 2.032)
			(type default)
		)
		(layer "In4.Cu")
	)
	(gr_arc
		(start 56.079898 -43.319954)
		(mid 55.786989 -42.612878)
		(end 55.0799 -42.319956)
		(stroke
			(width 2.032)
			(type default)
		)
		(layer "In4.Cu")
	)
	(gr_line
		(start 56.079898 -43.319954)
		(end 56.079898 -50.31994)
		(stroke
			(width 2.032)
			(type default)
		)
		(layer "In4.Cu")
	)
	(gr_line
		(start 58.079894 -52.319936)
		(end 94.681802 -52.319936)
		(stroke
			(width 2.032)
			(type default)
		)
		(layer "In4.Cu")
	)
	(gr_arc
		(start 78.060042 -45.063664)
		(mid 79.682839 -50.497558)
		(end 81.760314 -45.22089)
		(stroke
			(width 2.032)
			(type default)
		)
		(layer "In4.Cu")
	)
	(gr_line
		(start 78.060042 -41.70807)
		(end 78.060042 -45.063664)
		(stroke
			(width 2.032)
			(type default)
		)
		(layer "In4.Cu")
	)
	(gr_line
		(start 78.07071 -41.697402)
		(end 78.060042 -41.70807)
		(stroke
			(width 2.032)
			(type default)
		)
		(layer "In4.Cu")
	)
	(gr_line
		(start 79.809594 -47.500286)
		(end 79.809848 -47.50054)
		(stroke
			(width 4.064)
			(type default)
		)
		(layer "In4.Cu")
	)
	(gr_line
		(start 79.809594 -41.500044)
		(end 79.809594 -47.500286)
		(stroke
			(width 4.064)
			(type default)
		)
		(layer "In4.Cu")
	)
	(gr_line
		(start 79.809848 -47.50054)
		(end 79.809848 -47.500286)
		(stroke
			(width 6.604)
			(type default)
		)
		(layer "In4.Cu")
	)
	(gr_line
		(start 81.559908 -45.020484)
		(end 81.559908 -41.500298)
		(stroke
			(width 2.032)
			(type default)
		)
		(layer "In4.Cu")
	)
	(gr_arc
		(start 81.559908 -41.500298)
		(mid 79.711152 -39.752769)
		(end 78.07071 -41.697402)
		(stroke
			(width 2.032)
			(type default)
		)
		(layer "In4.Cu")
	)
	(gr_line
		(start 81.760314 -45.22089)
		(end 81.559908 -45.020484)
		(stroke
			(width 2.032)
			(type default)
		)
		(layer "In4.Cu")
	)
	(gr_arc
		(start 94.681802 -52.319936)
		(mid 95.388907 -52.027043)
		(end 95.6818 -51.319938)
		(stroke
			(width 2.032)
			(type default)
		)
		(layer "In4.Cu")
	)
	(gr_line
		(start 95.6818 -51.319938)
		(end 95.6818 -50.8)
		(stroke
			(width 2.032)
			(type default)
		)
		(layer "In4.Cu")
	)
	(gr_arc
		(start 96.681798 -49.800002)
		(mid 95.974694 -50.092895)
		(end 95.6818 -50.8)
		(stroke
			(width 2.032)
			(type default)
		)
		(layer "In4.Cu")
	)
	(gr_line
		(start 96.681798 -49.800002)
		(end 112.06988 -49.800002)
		(stroke
			(width 2.032)
			(type default)
		)
		(layer "In4.Cu")
	)
	(gr_line
		(start 101.576632 -11.378946)
		(end 101.576632 -9.194546)
		(stroke
			(width 0.254)
			(type default)
		)
		(layer "In4.Cu")
	)
	(gr_line
		(start 101.576632 -9.194546)
		(end 103.151432 -9.194546)
		(stroke
			(width 0.254)
			(type default)
		)
		(layer "In4.Cu")
	)
	(gr_line
		(start 101.602032 -11.378946)
		(end 101.602032 -9.245346)
		(stroke
			(width 0.254)
			(type default)
		)
		(layer "In4.Cu")
	)
	(gr_line
		(start 101.602032 -9.245346)
		(end 103.126032 -9.245346)
		(stroke
			(width 0.254)
			(type default)
		)
		(layer "In4.Cu")
	)
	(gr_line
		(start 101.652832 -11.353546)
		(end 101.652832 -9.372346)
		(stroke
			(width 0.254)
			(type default)
		)
		(layer "In4.Cu")
	)
	(gr_line
		(start 101.652832 -9.372346)
		(end 103.100632 -9.372346)
		(stroke
			(width 0.254)
			(type default)
		)
		(layer "In4.Cu")
	)
	(gr_line
		(start 101.706934 -11.302746)
		(end 102.011734 -11.302746)
		(stroke
			(width 0.1016)
			(type default)
		)
		(layer "In4.Cu")
	)
	(gr_line
		(start 101.706934 -9.296146)
		(end 101.706934 -11.302746)
		(stroke
			(width 0.1016)
			(type default)
		)
		(layer "In4.Cu")
	)
	(gr_line
		(start 101.757734 -11.226546)
		(end 102.849934 -11.226546)
		(stroke
			(width 0.2032)
			(type default)
		)
		(layer "In4.Cu")
	)
	(gr_line
		(start 101.757734 -9.372346)
		(end 101.757734 -11.226546)
		(stroke
			(width 0.2032)
			(type default)
		)
		(layer "In4.Cu")
	)
	(gr_line
		(start 101.783134 -11.226546)
		(end 102.951534 -11.226546)
		(stroke
			(width 0.2032)
			(type default)
		)
		(layer "In4.Cu")
	)
	(gr_line
		(start 101.783134 -9.423146)
		(end 101.783134 -11.226546)
		(stroke
			(width 0.2032)
			(type default)
		)
		(layer "In4.Cu")
	)
	(gr_line
		(start 101.830632 -11.124946)
		(end 101.830632 -9.575546)
		(stroke
			(width 0.762)
			(type default)
		)
		(layer "In4.Cu")
	)
	(gr_line
		(start 101.830632 -11.124946)
		(end 102.745032 -11.124946)
		(stroke
			(width 0.762)
			(type default)
		)
		(layer "In4.Cu")
	)
	(gr_line
		(start 101.830632 -11.099546)
		(end 101.830632 -9.550146)
		(stroke
			(width 0.762)
			(type default)
		)
		(layer "In4.Cu")
	)
	(gr_line
		(start 101.830632 -10.997946)
		(end 101.830632 -9.448546)
		(stroke
			(width 0.762)
			(type default)
		)
		(layer "In4.Cu")
	)
	(gr_line
		(start 101.830632 -9.448546)
		(end 102.745032 -9.448546)
		(stroke
			(width 0.762)
			(type default)
		)
		(layer "In4.Cu")
	)
	(gr_line
		(start 101.833934 -11.175746)
		(end 102.926134 -11.175746)
		(stroke
			(width 0.2032)
			(type default)
		)
		(layer "In4.Cu")
	)
	(gr_line
		(start 101.833934 -9.473946)
		(end 101.833934 -11.175746)
		(stroke
			(width 0.2032)
			(type default)
		)
		(layer "In4.Cu")
	)
	(gr_line
		(start 101.856032 -10.997946)
		(end 102.770432 -10.997946)
		(stroke
			(width 0.762)
			(type default)
		)
		(layer "In4.Cu")
	)
	(gr_line
		(start 101.856032 -9.575546)
		(end 102.770432 -9.575546)
		(stroke
			(width 0.762)
			(type default)
		)
		(layer "In4.Cu")
	)
	(gr_line
		(start 101.935534 -11.074146)
		(end 102.722934 -11.074146)
		(stroke
			(width 0.508)
			(type default)
		)
		(layer "In4.Cu")
	)
	(gr_line
		(start 101.935534 -11.048746)
		(end 101.935534 -9.524746)
		(stroke
			(width 0.508)
			(type default)
		)
		(layer "In4.Cu")
	)
	(gr_line
		(start 101.960934 -11.074146)
		(end 101.960934 -9.550146)
		(stroke
			(width 0.508)
			(type default)
		)
		(layer "In4.Cu")
	)
	(gr_line
		(start 101.983032 -11.124946)
		(end 102.897432 -11.124946)
		(stroke
			(width 0.762)
			(type default)
		)
		(layer "In4.Cu")
	)
	(gr_line
		(start 101.983032 -9.448546)
		(end 102.897432 -9.448546)
		(stroke
			(width 0.762)
			(type default)
		)
		(layer "In4.Cu")
	)
	(gr_line
		(start 101.986334 -9.524746)
		(end 102.722934 -9.524746)
		(stroke
			(width 0.508)
			(type default)
		)
		(layer "In4.Cu")
	)
	(gr_line
		(start 102.011734 -11.302746)
		(end 103.002334 -11.302746)
		(stroke
			(width 0.1016)
			(type default)
		)
		(layer "In4.Cu")
	)
	(gr_line
		(start 102.011734 -11.074146)
		(end 102.011734 -9.550146)
		(stroke
			(width 0.508)
			(type default)
		)
		(layer "In4.Cu")
	)
	(gr_line
		(start 102.037134 -11.074146)
		(end 102.037134 -9.550146)
		(stroke
			(width 0.508)
			(type default)
		)
		(layer "In4.Cu")
	)
	(gr_line
		(start 102.062534 -11.074146)
		(end 102.062534 -9.550146)
		(stroke
			(width 0.508)
			(type default)
		)
		(layer "In4.Cu")
	)
	(gr_line
		(start 102.087934 -11.074146)
		(end 102.087934 -9.550146)
		(stroke
			(width 0.508)
			(type default)
		)
		(layer "In4.Cu")
	)
	(gr_line
		(start 102.087934 -11.048746)
		(end 102.087934 -9.524746)
		(stroke
			(width 0.508)
			(type default)
		)
		(layer "In4.Cu")
	)
	(gr_line
		(start 102.113334 -11.074146)
		(end 102.113334 -9.550146)
		(stroke
			(width 0.508)
			(type default)
		)
		(layer "In4.Cu")
	)
	(gr_line
		(start 102.138734 -11.074146)
		(end 102.138734 -9.550146)
		(stroke
			(width 0.508)
			(type default)
		)
		(layer "In4.Cu")
	)
	(gr_line
		(start 102.189534 -11.074146)
		(end 102.189534 -9.550146)
		(stroke
			(width 0.508)
			(type default)
		)
		(layer "In4.Cu")
	)
	(gr_line
		(start 102.189534 -11.048746)
		(end 102.189534 -9.524746)
		(stroke
			(width 0.508)
			(type default)
		)
		(layer "In4.Cu")
	)
	(gr_line
		(start 102.214934 -11.074146)
		(end 102.214934 -9.550146)
		(stroke
			(width 0.508)
			(type default)
		)
		(layer "In4.Cu")
	)
	(gr_line
		(start 102.240334 -11.074146)
		(end 102.240334 -9.550146)
		(stroke
			(width 0.508)
			(type default)
		)
		(layer "In4.Cu")
	)
	(gr_line
		(start 102.265734 -11.074146)
		(end 102.265734 -9.550146)
		(stroke
			(width 0.508)
			(type default)
		)
		(layer "In4.Cu")
	)
	(gr_line
		(start 102.316534 -11.074146)
		(end 102.316534 -9.550146)
		(stroke
			(width 0.508)
			(type default)
		)
		(layer "In4.Cu")
	)
	(gr_line
		(start 102.341934 -11.074146)
		(end 102.341934 -9.550146)
		(stroke
			(width 0.508)
			(type default)
		)
		(layer "In4.Cu")
	)
	(gr_line
		(start 102.341934 -11.048746)
		(end 102.341934 -9.524746)
		(stroke
			(width 0.508)
			(type default)
		)
		(layer "In4.Cu")
	)
	(gr_line
		(start 102.367334 -11.074146)
		(end 102.367334 -9.550146)
		(stroke
			(width 0.508)
			(type default)
		)
		(layer "In4.Cu")
	)
	(gr_line
		(start 102.392734 -11.074146)
		(end 102.392734 -9.550146)
		(stroke
			(width 0.508)
			(type default)
		)
		(layer "In4.Cu")
	)
	(gr_line
		(start 102.418134 -11.074146)
		(end 102.418134 -9.550146)
		(stroke
			(width 0.508)
			(type default)
		)
		(layer "In4.Cu")
	)
	(gr_line
		(start 102.418134 -11.048746)
		(end 102.418134 -9.524746)
		(stroke
			(width 0.508)
			(type default)
		)
		(layer "In4.Cu")
	)
	(gr_line
		(start 102.443534 -11.074146)
		(end 102.443534 -9.550146)
		(stroke
			(width 0.508)
			(type default)
		)
		(layer "In4.Cu")
	)
	(gr_line
		(start 102.468934 -11.074146)
		(end 102.468934 -9.550146)
		(stroke
			(width 0.508)
			(type default)
		)
		(layer "In4.Cu")
	)
	(gr_line
		(start 102.468934 -11.048746)
		(end 102.468934 -9.524746)
		(stroke
			(width 0.508)
			(type default)
		)
		(layer "In4.Cu")
	)
	(gr_line
		(start 102.494334 -11.074146)
		(end 102.494334 -9.550146)
		(stroke
			(width 0.508)
			(type default)
		)
		(layer "In4.Cu")
	)
	(gr_line
		(start 102.494334 -11.048746)
		(end 102.494334 -9.524746)
		(stroke
			(width 0.508)
			(type default)
		)
		(layer "In4.Cu")
	)
	(gr_line
		(start 102.519734 -11.048746)
		(end 102.519734 -9.524746)
		(stroke
			(width 0.508)
			(type default)
		)
		(layer "In4.Cu")
	)
	(gr_line
		(start 102.545134 -11.074146)
		(end 102.545134 -9.550146)
		(stroke
			(width 0.508)
			(type default)
		)
		(layer "In4.Cu")
	)
	(gr_line
		(start 102.567232 -11.378946)
		(end 101.576632 -11.378946)
		(stroke
			(width 0.254)
			(type default)
		)
		(layer "In4.Cu")
	)
	(gr_line
		(start 102.570534 -11.048746)
		(end 102.570534 -9.524746)
		(stroke
			(width 0.508)
			(type default)
		)
		(layer "In4.Cu")
	)
	(gr_line
		(start 102.595934 -11.048746)
		(end 102.595934 -9.524746)
		(stroke
			(width 0.508)
			(type default)
		)
		(layer "In4.Cu")
	)
	(gr_line
		(start 102.621334 -11.074146)
		(end 102.621334 -9.550146)
		(stroke
			(width 0.508)
			(type default)
		)
		(layer "In4.Cu")
	)
	(gr_line
		(start 102.646734 -11.074146)
		(end 102.646734 -9.550146)
		(stroke
			(width 0.508)
			(type default)
		)
		(layer "In4.Cu")
	)
	(gr_line
		(start 102.646734 -11.048746)
		(end 102.646734 -9.524746)
		(stroke
			(width 0.508)
			(type default)
		)
		(layer "In4.Cu")
	)
	(gr_line
		(start 102.697534 -11.074146)
		(end 102.697534 -9.550146)
		(stroke
			(width 0.508)
			(type default)
		)
		(layer "In4.Cu")
	)
	(gr_line
		(start 102.697534 -11.048746)
		(end 102.697534 -9.524746)
		(stroke
			(width 0.508)
			(type default)
		)
		(layer "In4.Cu")
	)
	(gr_line
		(start 102.748334 -11.074146)
		(end 102.748334 -9.550146)
		(stroke
			(width 0.508)
			(type default)
		)
		(layer "In4.Cu")
	)
	(gr_line
		(start 102.748334 -11.048746)
		(end 102.748334 -9.524746)
		(stroke
			(width 0.508)
			(type default)
		)
		(layer "In4.Cu")
	)
	(gr_line
		(start 102.770432 -11.099546)
		(end 102.770432 -9.550146)
		(stroke
			(width 0.762)
			(type default)
		)
		(layer "In4.Cu")
	)
	(gr_line
		(start 102.773734 -11.074146)
		(end 102.773734 -9.550146)
		(stroke
			(width 0.508)
			(type default)
		)
		(layer "In4.Cu")
	)
	(gr_line
		(start 102.799134 -11.074146)
		(end 102.799134 -9.550146)
		(stroke
			(width 0.508)
			(type default)
		)
		(layer "In4.Cu")
	)
	(gr_line
		(start 102.849934 -11.226546)
		(end 102.875334 -11.226546)
		(stroke
			(width 0.2032)
			(type default)
		)
		(layer "In4.Cu")
	)
	(gr_line
		(start 102.875334 -11.226546)
		(end 102.875334 -9.473946)
		(stroke
			(width 0.2032)
			(type default)
		)
		(layer "In4.Cu")
	)
	(gr_line
		(start 102.875334 -9.473946)
		(end 101.833934 -9.473946)
		(stroke
			(width 0.2032)
			(type default)
		)
		(layer "In4.Cu")
	)
	(gr_line
		(start 102.897432 -11.124946)
		(end 102.897432 -9.575546)
		(stroke
			(width 0.762)
			(type default)
		)
		(layer "In4.Cu")
	)
	(gr_line
		(start 102.897432 -11.099546)
		(end 102.897432 -9.600946)
		(stroke
			(width 0.762)
			(type default)
		)
		(layer "In4.Cu")
	)
	(gr_line
		(start 102.897432 -10.997946)
		(end 102.897432 -9.448546)
		(stroke
			(width 0.762)
			(type default)
		)
		(layer "In4.Cu")
	)
	(gr_line
		(start 102.926134 -11.175746)
		(end 102.926134 -9.423146)
		(stroke
			(width 0.2032)
			(type default)
		)
		(layer "In4.Cu")
	)
	(gr_line
		(start 102.926134 -9.423146)
		(end 101.783134 -9.423146)
		(stroke
			(width 0.2032)
			(type default)
		)
		(layer "In4.Cu")
	)
	(gr_line
		(start 102.951534 -11.226546)
		(end 102.951534 -9.372346)
		(stroke
			(width 0.2032)
			(type default)
		)
		(layer "In4.Cu")
	)
	(gr_line
		(start 102.951534 -9.372346)
		(end 101.757734 -9.372346)
		(stroke
			(width 0.2032)
			(type default)
		)
		(layer "In4.Cu")
	)
	(gr_line
		(start 103.002334 -11.302746)
		(end 103.002334 -9.296146)
		(stroke
			(width 0.1016)
			(type default)
		)
		(layer "In4.Cu")
	)
	(gr_line
		(start 103.002334 -9.296146)
		(end 101.706934 -9.296146)
		(stroke
			(width 0.1016)
			(type default)
		)
		(layer "In4.Cu")
	)
	(gr_line
		(start 103.004874 -5.57784)
		(end 101.734874 -5.57784)
		(stroke
			(width 1.016)
			(type default)
		)
		(layer "In4.Cu")
	)
	(gr_line
		(start 103.100632 -11.226546)
		(end 102.849934 -11.226546)
		(stroke
			(width 0.254)
			(type default)
		)
		(layer "In4.Cu")
	)
	(gr_line
		(start 103.100632 -9.372346)
		(end 103.100632 -11.226546)
		(stroke
			(width 0.254)
			(type default)
		)
		(layer "In4.Cu")
	)
	(gr_line
		(start 103.126032 -11.353546)
		(end 101.652832 -11.353546)
		(stroke
			(width 0.254)
			(type default)
		)
		(layer "In4.Cu")
	)
	(gr_line
		(start 103.126032 -9.245346)
		(end 103.126032 -11.353546)
		(stroke
			(width 0.254)
			(type default)
		)
		(layer "In4.Cu")
	)
	(gr_line
		(start 103.151432 -11.378946)
		(end 101.602032 -11.378946)
		(stroke
			(width 0.254)
			(type default)
		)
		(layer "In4.Cu")
	)
	(gr_line
		(start 103.151432 -9.194546)
		(end 103.151432 -11.378946)
		(stroke
			(width 0.254)
			(type default)
		)
		(layer "In4.Cu")
	)
	(gr_line
		(start 106.376724 -11.378946)
		(end 106.376724 -9.194546)
		(stroke
			(width 0.254)
			(type default)
		)
		(layer "In4.Cu")
	)
	(gr_line
		(start 106.376724 -9.194546)
		(end 107.951524 -9.194546)
		(stroke
			(width 0.254)
			(type default)
		)
		(layer "In4.Cu")
	)
	(gr_line
		(start 106.402124 -11.378946)
		(end 106.402124 -9.245346)
		(stroke
			(width 0.254)
			(type default)
		)
		(layer "In4.Cu")
	)
	(gr_line
		(start 106.402124 -9.245346)
		(end 107.926124 -9.245346)
		(stroke
			(width 0.254)
			(type default)
		)
		(layer "In4.Cu")
	)
	(gr_line
		(start 106.452924 -11.353546)
		(end 106.452924 -9.372346)
		(stroke
			(width 0.254)
			(type default)
		)
		(layer "In4.Cu")
	)
	(gr_line
		(start 106.452924 -9.372346)
		(end 107.900724 -9.372346)
		(stroke
			(width 0.254)
			(type default)
		)
		(layer "In4.Cu")
	)
	(gr_line
		(start 106.507026 -11.302746)
		(end 106.811826 -11.302746)
		(stroke
			(width 0.1016)
			(type default)
		)
		(layer "In4.Cu")
	)
	(gr_line
		(start 106.507026 -9.296146)
		(end 106.507026 -11.302746)
		(stroke
			(width 0.1016)
			(type default)
		)
		(layer "In4.Cu")
	)
	(gr_line
		(start 106.557826 -11.226546)
		(end 107.650026 -11.226546)
		(stroke
			(width 0.2032)
			(type default)
		)
		(layer "In4.Cu")
	)
	(gr_line
		(start 106.557826 -9.372346)
		(end 106.557826 -11.226546)
		(stroke
			(width 0.2032)
			(type default)
		)
		(layer "In4.Cu")
	)
	(gr_line
		(start 106.583226 -11.226546)
		(end 107.751626 -11.226546)
		(stroke
			(width 0.2032)
			(type default)
		)
		(layer "In4.Cu")
	)
	(gr_line
		(start 106.583226 -9.423146)
		(end 106.583226 -11.226546)
		(stroke
			(width 0.2032)
			(type default)
		)
		(layer "In4.Cu")
	)
	(gr_line
		(start 106.630724 -11.124946)
		(end 106.630724 -9.575546)
		(stroke
			(width 0.762)
			(type default)
		)
		(layer "In4.Cu")
	)
	(gr_line
		(start 106.630724 -11.124946)
		(end 107.545124 -11.124946)
		(stroke
			(width 0.762)
			(type default)
		)
		(layer "In4.Cu")
	)
	(gr_line
		(start 106.630724 -11.099546)
		(end 106.630724 -9.550146)
		(stroke
			(width 0.762)
			(type default)
		)
		(layer "In4.Cu")
	)
	(gr_line
		(start 106.630724 -10.997946)
		(end 106.630724 -9.448546)
		(stroke
			(width 0.762)
			(type default)
		)
		(layer "In4.Cu")
	)
	(gr_line
		(start 106.630724 -9.448546)
		(end 107.545124 -9.448546)
		(stroke
			(width 0.762)
			(type default)
		)
		(layer "In4.Cu")
	)
	(gr_line
		(start 106.634026 -11.175746)
		(end 107.726226 -11.175746)
		(stroke
			(width 0.2032)
			(type default)
		)
		(layer "In4.Cu")
	)
	(gr_line
		(start 106.634026 -9.473946)
		(end 106.634026 -11.175746)
		(stroke
			(width 0.2032)
			(type default)
		)
		(layer "In4.Cu")
	)
	(gr_line
		(start 106.656124 -10.997946)
		(end 107.570524 -10.997946)
		(stroke
			(width 0.762)
			(type default)
		)
		(layer "In4.Cu")
	)
	(gr_line
		(start 106.656124 -9.575546)
		(end 107.570524 -9.575546)
		(stroke
			(width 0.762)
			(type default)
		)
		(layer "In4.Cu")
	)
	(gr_line
		(start 106.735626 -11.074146)
		(end 107.523026 -11.074146)
		(stroke
			(width 0.508)
			(type default)
		)
		(layer "In4.Cu")
	)
	(gr_line
		(start 106.735626 -11.048746)
		(end 106.735626 -9.524746)
		(stroke
			(width 0.508)
			(type default)
		)
		(layer "In4.Cu")
	)
	(gr_line
		(start 106.761026 -11.074146)
		(end 106.761026 -9.550146)
		(stroke
			(width 0.508)
			(type default)
		)
		(layer "In4.Cu")
	)
	(gr_line
		(start 106.783124 -11.124946)
		(end 107.697524 -11.124946)
		(stroke
			(width 0.762)
			(type default)
		)
		(layer "In4.Cu")
	)
	(gr_line
		(start 106.783124 -9.448546)
		(end 107.697524 -9.448546)
		(stroke
			(width 0.762)
			(type default)
		)
		(layer "In4.Cu")
	)
	(gr_line
		(start 106.786426 -9.524746)
		(end 107.523026 -9.524746)
		(stroke
			(width 0.508)
			(type default)
		)
		(layer "In4.Cu")
	)
	(gr_line
		(start 106.811826 -11.302746)
		(end 107.802426 -11.302746)
		(stroke
			(width 0.1016)
			(type default)
		)
		(layer "In4.Cu")
	)
	(gr_line
		(start 106.811826 -11.074146)
		(end 106.811826 -9.550146)
		(stroke
			(width 0.508)
			(type default)
		)
		(layer "In4.Cu")
	)
	(gr_line
		(start 106.837226 -11.074146)
		(end 106.837226 -9.550146)
		(stroke
			(width 0.508)
			(type default)
		)
		(layer "In4.Cu")
	)
	(gr_line
		(start 106.862626 -11.074146)
		(end 106.862626 -9.550146)
		(stroke
			(width 0.508)
			(type default)
		)
		(layer "In4.Cu")
	)
	(gr_line
		(start 106.888026 -11.074146)
		(end 106.888026 -9.550146)
		(stroke
			(width 0.508)
			(type default)
		)
		(layer "In4.Cu")
	)
	(gr_line
		(start 106.888026 -11.048746)
		(end 106.888026 -9.524746)
		(stroke
			(width 0.508)
			(type default)
		)
		(layer "In4.Cu")
	)
	(gr_line
		(start 106.913426 -11.074146)
		(end 106.913426 -9.550146)
		(stroke
			(width 0.508)
			(type default)
		)
		(layer "In4.Cu")
	)
	(gr_line
		(start 106.938826 -11.074146)
		(end 106.938826 -9.550146)
		(stroke
			(width 0.508)
			(type default)
		)
		(layer "In4.Cu")
	)
	(gr_line
		(start 106.989626 -11.074146)
		(end 106.989626 -9.550146)
		(stroke
			(width 0.508)
			(type default)
		)
		(layer "In4.Cu")
	)
	(gr_line
		(start 106.989626 -11.048746)
		(end 106.989626 -9.524746)
		(stroke
			(width 0.508)
			(type default)
		)
		(layer "In4.Cu")
	)
	(gr_line
		(start 107.015026 -11.074146)
		(end 107.015026 -9.550146)
		(stroke
			(width 0.508)
			(type default)
		)
		(layer "In4.Cu")
	)
	(gr_line
		(start 107.040426 -11.074146)
		(end 107.040426 -9.550146)
		(stroke
			(width 0.508)
			(type default)
		)
		(layer "In4.Cu")
	)
	(gr_line
		(start 107.065826 -11.074146)
		(end 107.065826 -9.550146)
		(stroke
			(width 0.508)
			(type default)
		)
		(layer "In4.Cu")
	)
	(gr_line
		(start 107.116626 -11.074146)
		(end 107.116626 -9.550146)
		(stroke
			(width 0.508)
			(type default)
		)
		(layer "In4.Cu")
	)
	(gr_line
		(start 107.142026 -11.074146)
		(end 107.142026 -9.550146)
		(stroke
			(width 0.508)
			(type default)
		)
		(layer "In4.Cu")
	)
	(gr_line
		(start 107.142026 -11.048746)
		(end 107.142026 -9.524746)
		(stroke
			(width 0.508)
			(type default)
		)
		(layer "In4.Cu")
	)
	(gr_line
		(start 107.167426 -11.074146)
		(end 107.167426 -9.550146)
		(stroke
			(width 0.508)
			(type default)
		)
		(layer "In4.Cu")
	)
	(gr_line
		(start 107.192826 -11.074146)
		(end 107.192826 -9.550146)
		(stroke
			(width 0.508)
			(type default)
		)
		(layer "In4.Cu")
	)
	(gr_line
		(start 107.218226 -11.074146)
		(end 107.218226 -9.550146)
		(stroke
			(width 0.508)
			(type default)
		)
		(layer "In4.Cu")
	)
	(gr_line
		(start 107.218226 -11.048746)
		(end 107.218226 -9.524746)
		(stroke
			(width 0.508)
			(type default)
		)
		(layer "In4.Cu")
	)
	(gr_line
		(start 107.243626 -11.074146)
		(end 107.243626 -9.550146)
		(stroke
			(width 0.508)
			(type default)
		)
		(layer "In4.Cu")
	)
	(gr_line
		(start 107.269026 -11.074146)
		(end 107.269026 -9.550146)
		(stroke
			(width 0.508)
			(type default)
		)
		(layer "In4.Cu")
	)
	(gr_line
		(start 107.269026 -11.048746)
		(end 107.269026 -9.524746)
		(stroke
			(width 0.508)
			(type default)
		)
		(layer "In4.Cu")
	)
	(gr_line
		(start 107.294426 -11.074146)
		(end 107.294426 -9.550146)
		(stroke
			(width 0.508)
			(type default)
		)
		(layer "In4.Cu")
	)
	(gr_line
		(start 107.294426 -11.048746)
		(end 107.294426 -9.524746)
		(stroke
			(width 0.508)
			(type default)
		)
		(layer "In4.Cu")
	)
	(gr_line
		(start 107.319826 -11.048746)
		(end 107.319826 -9.524746)
		(stroke
			(width 0.508)
			(type default)
		)
		(layer "In4.Cu")
	)
	(gr_line
		(start 107.345226 -11.074146)
		(end 107.345226 -9.550146)
		(stroke
			(width 0.508)
			(type default)
		)
		(layer "In4.Cu")
	)
	(gr_line
		(start 107.367324 -11.378946)
		(end 106.376724 -11.378946)
		(stroke
			(width 0.254)
			(type default)
		)
		(layer "In4.Cu")
	)
	(gr_line
		(start 107.370626 -11.048746)
		(end 107.370626 -9.524746)
		(stroke
			(width 0.508)
			(type default)
		)
		(layer "In4.Cu")
	)
	(gr_line
		(start 107.396026 -11.048746)
		(end 107.396026 -9.524746)
		(stroke
			(width 0.508)
			(type default)
		)
		(layer "In4.Cu")
	)
	(gr_line
		(start 107.421426 -11.074146)
		(end 107.421426 -9.550146)
		(stroke
			(width 0.508)
			(type default)
		)
		(layer "In4.Cu")
	)
	(gr_line
		(start 107.446826 -11.074146)
		(end 107.446826 -9.550146)
		(stroke
			(width 0.508)
			(type default)
		)
		(layer "In4.Cu")
	)
	(gr_line
		(start 107.446826 -11.048746)
		(end 107.446826 -9.524746)
		(stroke
			(width 0.508)
			(type default)
		)
		(layer "In4.Cu")
	)
	(gr_line
		(start 107.497626 -11.074146)
		(end 107.497626 -9.550146)
		(stroke
			(width 0.508)
			(type default)
		)
		(layer "In4.Cu")
	)
	(gr_line
		(start 107.497626 -11.048746)
		(end 107.497626 -9.524746)
		(stroke
			(width 0.508)
			(type default)
		)
		(layer "In4.Cu")
	)
	(gr_line
		(start 107.548426 -11.074146)
		(end 107.548426 -9.550146)
		(stroke
			(width 0.508)
			(type default)
		)
		(layer "In4.Cu")
	)
	(gr_line
		(start 107.548426 -11.048746)
		(end 107.548426 -9.524746)
		(stroke
			(width 0.508)
			(type default)
		)
		(layer "In4.Cu")
	)
	(gr_line
		(start 107.570524 -11.099546)
		(end 107.570524 -9.550146)
		(stroke
			(width 0.762)
			(type default)
		)
		(layer "In4.Cu")
	)
	(gr_line
		(start 107.573826 -11.074146)
		(end 107.573826 -9.550146)
		(stroke
			(width 0.508)
			(type default)
		)
		(layer "In4.Cu")
	)
	(gr_line
		(start 107.599226 -11.074146)
		(end 107.599226 -9.550146)
		(stroke
			(width 0.508)
			(type default)
		)
		(layer "In4.Cu")
	)
	(gr_line
		(start 107.650026 -11.226546)
		(end 107.675426 -11.226546)
		(stroke
			(width 0.2032)
			(type default)
		)
		(layer "In4.Cu")
	)
	(gr_line
		(start 107.675426 -11.226546)
		(end 107.675426 -9.473946)
		(stroke
			(width 0.2032)
			(type default)
		)
		(layer "In4.Cu")
	)
	(gr_line
		(start 107.675426 -9.473946)
		(end 106.634026 -9.473946)
		(stroke
			(width 0.2032)
			(type default)
		)
		(layer "In4.Cu")
	)
	(gr_line
		(start 107.697524 -11.124946)
		(end 107.697524 -9.575546)
		(stroke
			(width 0.762)
			(type default)
		)
		(layer "In4.Cu")
	)
	(gr_line
		(start 107.697524 -11.099546)
		(end 107.697524 -9.600946)
		(stroke
			(width 0.762)
			(type default)
		)
		(layer "In4.Cu")
	)
	(gr_line
		(start 107.697524 -10.997946)
		(end 107.697524 -9.448546)
		(stroke
			(width 0.762)
			(type default)
		)
		(layer "In4.Cu")
	)
	(gr_line
		(start 107.726226 -11.175746)
		(end 107.726226 -9.423146)
		(stroke
			(width 0.2032)
			(type default)
		)
		(layer "In4.Cu")
	)
	(gr_line
		(start 107.726226 -9.423146)
		(end 106.583226 -9.423146)
		(stroke
			(width 0.2032)
			(type default)
		)
		(layer "In4.Cu")
	)
	(gr_line
		(start 107.751626 -11.226546)
		(end 107.751626 -9.372346)
		(stroke
			(width 0.2032)
			(type default)
		)
		(layer "In4.Cu")
	)
	(gr_line
		(start 107.751626 -9.372346)
		(end 106.557826 -9.372346)
		(stroke
			(width 0.2032)
			(type default)
		)
		(layer "In4.Cu")
	)
	(gr_line
		(start 107.802426 -11.302746)
		(end 107.802426 -9.296146)
		(stroke
			(width 0.1016)
			(type default)
		)
		(layer "In4.Cu")
	)
	(gr_line
		(start 107.802426 -9.296146)
		(end 106.507026 -9.296146)
		(stroke
			(width 0.1016)
			(type default)
		)
		(layer "In4.Cu")
	)
	(gr_line
		(start 107.900724 -11.226546)
		(end 107.650026 -11.226546)
		(stroke
			(width 0.254)
			(type default)
		)
		(layer "In4.Cu")
	)
	(gr_line
		(start 107.900724 -9.372346)
		(end 107.900724 -11.226546)
		(stroke
			(width 0.254)
			(type default)
		)
		(layer "In4.Cu")
	)
	(gr_line
		(start 107.926124 -11.353546)
		(end 106.452924 -11.353546)
		(stroke
			(width 0.254)
			(type default)
		)
		(layer "In4.Cu")
	)
	(gr_line
		(start 107.926124 -9.245346)
		(end 107.926124 -11.353546)
		(stroke
			(width 0.254)
			(type default)
		)
		(layer "In4.Cu")
	)
	(gr_line
		(start 107.951524 -11.378946)
		(end 106.402124 -11.378946)
		(stroke
			(width 0.254)
			(type default)
		)
		(layer "In4.Cu")
	)
	(gr_line
		(start 107.951524 -9.194546)
		(end 107.951524 -11.378946)
		(stroke
			(width 0.254)
			(type default)
		)
		(layer "In4.Cu")
	)
	(gr_arc
		(start 113.069878 -51.319938)
		(mid 113.362771 -52.027043)
		(end 114.069876 -52.319936)
		(stroke
			(width 2.032)
			(type default)
		)
		(layer "In4.Cu")
	)
	(gr_arc
		(start 113.069878 -50.8)
		(mid 112.776984 -50.092902)
		(end 112.06988 -49.800002)
		(stroke
			(width 2.032)
			(type default)
		)
		(layer "In4.Cu")
	)
	(gr_line
		(start 113.069878 -50.8)
		(end 113.069878 -51.319938)
		(stroke
			(width 2.032)
			(type default)
		)
		(layer "In4.Cu")
	)
	(gr_line
		(start 113.76152 -9.1948)
		(end 115.18392 -9.1948)
		(stroke
			(width 1.016)
			(type default)
		)
		(layer "In4.Cu")
	)
	(gr_line
		(start 114.069876 -52.319936)
		(end 132.990082 -52.319936)
		(stroke
			(width 2.032)
			(type default)
		)
		(layer "In4.Cu")
	)
	(gr_line
		(start 117.856 -13.843)
		(end 118.6942 -13.843)
		(stroke
			(width 0.1016)
			(type default)
		)
		(layer "In4.Cu")
	)
	(gr_line
		(start 117.856 -11.1252)
		(end 117.856 -13.843)
		(stroke
			(width 0.1016)
			(type default)
		)
		(layer "In4.Cu")
	)
	(gr_line
		(start 117.856 -9.64311)
		(end 118.6942 -9.64311)
		(stroke
			(width 0.1016)
			(type default)
		)
		(layer "In4.Cu")
	)
	(gr_line
		(start 117.856 -6.92531)
		(end 117.856 -9.64311)
		(stroke
			(width 0.1016)
			(type default)
		)
		(layer "In4.Cu")
	)
	(gr_line
		(start 117.8814 -13.8176)
		(end 117.8814 -11.1506)
		(stroke
			(width 0.127)
			(type default)
		)
		(layer "In4.Cu")
	)
	(gr_line
		(start 117.8814 -11.1506)
		(end 119.1768 -11.1506)
		(stroke
			(width 0.127)
			(type default)
		)
		(layer "In4.Cu")
	)
	(gr_line
		(start 117.8814 -9.61771)
		(end 117.8814 -6.95071)
		(stroke
			(width 0.127)
			(type default)
		)
		(layer "In4.Cu")
	)
	(gr_line
		(start 117.8814 -6.95071)
		(end 119.1768 -6.95071)
		(stroke
			(width 0.127)
			(type default)
		)
		(layer "In4.Cu")
	)
	(gr_line
		(start 117.9068 -13.8176)
		(end 117.9068 -11.176)
		(stroke
			(width 0.127)
			(type default)
		)
		(layer "In4.Cu")
	)
	(gr_line
		(start 117.9068 -13.7922)
		(end 117.9068 -11.176)
		(stroke
			(width 0.1778)
			(type default)
		)
		(layer "In4.Cu")
	)
	(gr_line
		(start 117.9068 -11.176)
		(end 119.1514 -11.176)
		(stroke
			(width 0.127)
			(type default)
		)
		(layer "In4.Cu")
	)
	(gr_line
		(start 117.9068 -11.176)
		(end 119.1514 -11.176)
		(stroke
			(width 0.1778)
			(type default)
		)
		(layer "In4.Cu")
	)
	(gr_line
		(start 117.9068 -9.61771)
		(end 117.9068 -6.97611)
		(stroke
			(width 0.127)
			(type default)
		)
		(layer "In4.Cu")
	)
	(gr_line
		(start 117.9068 -9.59231)
		(end 117.9068 -6.97611)
		(stroke
			(width 0.1778)
			(type default)
		)
		(layer "In4.Cu")
	)
	(gr_line
		(start 117.9068 -6.97611)
		(end 119.1514 -6.97611)
		(stroke
			(width 0.127)
			(type default)
		)
		(layer "In4.Cu")
	)
	(gr_line
		(start 117.9068 -6.97611)
		(end 119.1514 -6.97611)
		(stroke
			(width 0.1778)
			(type default)
		)
		(layer "In4.Cu")
	)
	(gr_line
		(start 117.9322 -13.7922)
		(end 117.9322 -11.2014)
		(stroke
			(width 0.1778)
			(type default)
		)
		(layer "In4.Cu")
	)
	(gr_line
		(start 117.9322 -11.2014)
		(end 119.126 -11.2014)
		(stroke
			(width 0.1778)
			(type default)
		)
		(layer "In4.Cu")
	)
	(gr_line
		(start 117.9322 -9.59231)
		(end 117.9322 -7.00151)
		(stroke
			(width 0.1778)
			(type default)
		)
		(layer "In4.Cu")
	)
	(gr_line
		(start 117.9322 -7.00151)
		(end 119.126 -7.00151)
		(stroke
			(width 0.1778)
			(type default)
		)
		(layer "In4.Cu")
	)
	(gr_line
		(start 117.9576 -13.7668)
		(end 117.9576 -11.2268)
		(stroke
			(width 0.254)
			(type default)
		)
		(layer "In4.Cu")
	)
	(gr_line
		(start 117.9576 -11.2268)
		(end 119.126 -11.2268)
		(stroke
			(width 0.254)
			(type default)
		)
		(layer "In4.Cu")
	)
	(gr_line
		(start 117.9576 -9.56691)
		(end 117.9576 -7.02691)
		(stroke
			(width 0.254)
			(type default)
		)
		(layer "In4.Cu")
	)
	(gr_line
		(start 117.9576 -7.02691)
		(end 119.126 -7.02691)
		(stroke
			(width 0.254)
			(type default)
		)
		(layer "In4.Cu")
	)
	(gr_line
		(start 117.983 -13.7668)
		(end 117.983 -11.2522)
		(stroke
			(width 0.254)
			(type default)
		)
		(layer "In4.Cu")
	)
	(gr_line
		(start 117.983 -11.2522)
		(end 119.1006 -11.2522)
		(stroke
			(width 0.254)
			(type default)
		)
		(layer "In4.Cu")
	)
	(gr_line
		(start 117.983 -9.56691)
		(end 117.983 -7.05231)
		(stroke
			(width 0.254)
			(type default)
		)
		(layer "In4.Cu")
	)
	(gr_line
		(start 117.983 -7.05231)
		(end 119.1006 -7.05231)
		(stroke
			(width 0.254)
			(type default)
		)
		(layer "In4.Cu")
	)
	(gr_line
		(start 118.0084 -13.716)
		(end 118.0084 -11.2776)
		(stroke
			(width 0.3556)
			(type default)
		)
		(layer "In4.Cu")
	)
	(gr_line
		(start 118.0084 -11.2776)
		(end 119.0498 -11.2776)
		(stroke
			(width 0.3556)
			(type default)
		)
		(layer "In4.Cu")
	)
	(gr_line
		(start 118.0084 -9.51611)
		(end 118.0084 -7.07771)
		(stroke
			(width 0.3556)
			(type default)
		)
		(layer "In4.Cu")
	)
	(gr_line
		(start 118.0084 -7.07771)
		(end 119.0498 -7.07771)
		(stroke
			(width 0.3556)
			(type default)
		)
		(layer "In4.Cu")
	)
	(gr_line
		(start 118.0592 -13.6906)
		(end 118.0592 -11.3284)
		(stroke
			(width 0.381)
			(type default)
		)
		(layer "In4.Cu")
	)
	(gr_line
		(start 118.0592 -11.3284)
		(end 118.999 -11.3284)
		(stroke
			(width 0.381)
			(type default)
		)
		(layer "In4.Cu")
	)
	(gr_line
		(start 118.0592 -9.49071)
		(end 118.0592 -7.12851)
		(stroke
			(width 0.381)
			(type default)
		)
		(layer "In4.Cu")
	)
	(gr_line
		(start 118.0592 -7.12851)
		(end 118.999 -7.12851)
		(stroke
			(width 0.381)
			(type default)
		)
		(layer "In4.Cu")
	)
	(gr_line
		(start 118.1354 -13.6398)
		(end 118.1354 -11.3792)
		(stroke
			(width 0.381)
			(type default)
		)
		(layer "In4.Cu")
	)
	(gr_line
		(start 118.1354 -11.3792)
		(end 118.9482 -11.3792)
		(stroke
			(width 0.381)
			(type default)
		)
		(layer "In4.Cu")
	)
	(gr_line
		(start 118.1354 -9.43991)
		(end 118.1354 -7.17931)
		(stroke
			(width 0.381)
			(type default)
		)
		(layer "In4.Cu")
	)
	(gr_line
		(start 118.1354 -7.17931)
		(end 118.9482 -7.17931)
		(stroke
			(width 0.381)
			(type default)
		)
		(layer "In4.Cu")
	)
	(gr_line
		(start 118.1608 -13.5636)
		(end 118.1608 -11.3792)
		(stroke
			(width 0.508)
			(type default)
		)
		(layer "In4.Cu")
	)
	(gr_line
		(start 118.1608 -11.3792)
		(end 118.9228 -11.3792)
		(stroke
			(width 0.508)
			(type default)
		)
		(layer "In4.Cu")
	)
	(gr_line
		(start 118.1608 -9.36371)
		(end 118.1608 -7.17931)
		(stroke
			(width 0.508)
			(type default)
		)
		(layer "In4.Cu")
	)
	(gr_line
		(start 118.1608 -7.17931)
		(end 118.9228 -7.17931)
		(stroke
			(width 0.508)
			(type default)
		)
		(layer "In4.Cu")
	)
	(gr_line
		(start 118.1862 -13.4112)
		(end 118.7704 -13.4112)
		(stroke
			(width 0.762)
			(type default)
		)
		(layer "In4.Cu")
	)
	(gr_line
		(start 118.1862 -11.5824)
		(end 118.7704 -11.5824)
		(stroke
			(width 0.762)
			(type default)
		)
		(layer "In4.Cu")
	)
	(gr_line
		(start 118.1862 -9.21131)
		(end 118.7704 -9.21131)
		(stroke
			(width 0.762)
			(type default)
		)
		(layer "In4.Cu")
	)
	(gr_line
		(start 118.1862 -7.38251)
		(end 118.7704 -7.38251)
		(stroke
			(width 0.762)
			(type default)
		)
		(layer "In4.Cu")
	)
	(gr_line
		(start 118.2116 -13.5636)
		(end 118.2116 -11.43)
		(stroke
			(width 0.635)
			(type default)
		)
		(layer "In4.Cu")
	)
	(gr_line
		(start 118.2116 -13.5128)
		(end 118.2116 -11.4808)
		(stroke
			(width 0.762)
			(type default)
		)
		(layer "In4.Cu")
	)
	(gr_line
		(start 118.2116 -11.43)
		(end 118.8974 -11.43)
		(stroke
			(width 0.635)
			(type default)
		)
		(layer "In4.Cu")
	)
	(gr_line
		(start 118.2116 -9.36371)
		(end 118.2116 -7.23011)
		(stroke
			(width 0.635)
			(type default)
		)
		(layer "In4.Cu")
	)
	(gr_line
		(start 118.2116 -9.31291)
		(end 118.2116 -7.28091)
		(stroke
			(width 0.762)
			(type default)
		)
		(layer "In4.Cu")
	)
	(gr_line
		(start 118.2116 -7.23011)
		(end 118.8974 -7.23011)
		(stroke
			(width 0.635)
			(type default)
		)
		(layer "In4.Cu")
	)
	(gr_line
		(start 118.237 -13.5128)
		(end 118.237 -11.4808)
		(stroke
			(width 0.762)
			(type default)
		)
		(layer "In4.Cu")
	)
	(gr_line
		(start 118.237 -11.4808)
		(end 118.8212 -11.4808)
		(stroke
			(width 0.762)
			(type default)
		)
		(layer "In4.Cu")
	)
	(gr_line
		(start 118.237 -9.31291)
		(end 118.237 -7.28091)
		(stroke
			(width 0.762)
			(type default)
		)
		(layer "In4.Cu")
	)
	(gr_line
		(start 118.237 -7.28091)
		(end 118.8212 -7.28091)
		(stroke
			(width 0.762)
			(type default)
		)
		(layer "In4.Cu")
	)
	(gr_line
		(start 118.2624 -13.5128)
		(end 118.2624 -11.4808)
		(stroke
			(width 0.762)
			(type default)
		)
		(layer "In4.Cu")
	)
	(gr_line
		(start 118.2624 -13.5128)
		(end 118.8466 -13.5128)
		(stroke
			(width 0.762)
			(type default)
		)
		(layer "In4.Cu")
	)
	(gr_line
		(start 118.2624 -13.4874)
		(end 118.2624 -11.4554)
		(stroke
			(width 0.762)
			(type default)
		)
		(layer "In4.Cu")
	)
	(gr_line
		(start 118.2624 -9.31291)
		(end 118.2624 -7.28091)
		(stroke
			(width 0.762)
			(type default)
		)
		(layer "In4.Cu")
	)
	(gr_line
		(start 118.2624 -9.31291)
		(end 118.8466 -9.31291)
		(stroke
			(width 0.762)
			(type default)
		)
		(layer "In4.Cu")
	)
	(gr_line
		(start 118.2624 -9.28751)
		(end 118.2624 -7.25551)
		(stroke
			(width 0.762)
			(type default)
		)
		(layer "In4.Cu")
	)
	(gr_line
		(start 118.2878 -13.5128)
		(end 118.2878 -11.4808)
		(stroke
			(width 0.762)
			(type default)
		)
		(layer "In4.Cu")
	)
	(gr_line
		(start 118.2878 -9.31291)
		(end 118.2878 -7.28091)
		(stroke
			(width 0.762)
			(type default)
		)
		(layer "In4.Cu")
	)
	(gr_line
		(start 118.3132 -13.5128)
		(end 118.3132 -11.4808)
		(stroke
			(width 0.762)
			(type default)
		)
		(layer "In4.Cu")
	)
	(gr_line
		(start 118.3132 -9.31291)
		(end 118.3132 -7.28091)
		(stroke
			(width 0.762)
			(type default)
		)
		(layer "In4.Cu")
	)
	(gr_line
		(start 118.3386 -13.5128)
		(end 118.3386 -11.4808)
		(stroke
			(width 0.762)
			(type default)
		)
		(layer "In4.Cu")
	)
	(gr_line
		(start 118.3386 -9.31291)
		(end 118.3386 -7.28091)
		(stroke
			(width 0.762)
			(type default)
		)
		(layer "In4.Cu")
	)
	(gr_line
		(start 118.3894 -13.5128)
		(end 118.3894 -11.4808)
		(stroke
			(width 0.762)
			(type default)
		)
		(layer "In4.Cu")
	)
	(gr_line
		(start 118.3894 -9.31291)
		(end 118.3894 -7.28091)
		(stroke
			(width 0.762)
			(type default)
		)
		(layer "In4.Cu")
	)
	(gr_line
		(start 118.4148 -13.5128)
		(end 118.4148 -11.4808)
		(stroke
			(width 0.762)
			(type default)
		)
		(layer "In4.Cu")
	)
	(gr_line
		(start 118.4148 -9.31291)
		(end 118.4148 -7.28091)
		(stroke
			(width 0.762)
			(type default)
		)
		(layer "In4.Cu")
	)
	(gr_line
		(start 118.4402 -13.5128)
		(end 118.4402 -11.7094)
		(stroke
			(width 0.635)
			(type default)
		)
		(layer "In4.Cu")
	)
	(gr_line
		(start 118.4402 -11.7094)
		(end 118.5418 -11.7094)
		(stroke
			(width 0.635)
			(type default)
		)
		(layer "In4.Cu")
	)
	(gr_line
		(start 118.4402 -9.31291)
		(end 118.4402 -7.50951)
		(stroke
			(width 0.635)
			(type default)
		)
		(layer "In4.Cu")
	)
	(gr_line
		(start 118.4402 -7.50951)
		(end 118.5418 -7.50951)
		(stroke
			(width 0.635)
			(type default)
		)
		(layer "In4.Cu")
	)
	(gr_line
		(start 118.4656 -13.5128)
		(end 118.4656 -11.4808)
		(stroke
			(width 0.762)
			(type default)
		)
		(layer "In4.Cu")
	)
	(gr_line
		(start 118.4656 -13.4874)
		(end 118.4656 -11.4554)
		(stroke
			(width 0.762)
			(type default)
		)
		(layer "In4.Cu")
	)
	(gr_line
		(start 118.4656 -13.4366)
		(end 118.4656 -11.6586)
		(stroke
			(width 0.635)
			(type default)
		)
		(layer "In4.Cu")
	)
	(gr_line
		(start 118.4656 -9.31291)
		(end 118.4656 -7.28091)
		(stroke
			(width 0.762)
			(type default)
		)
		(layer "In4.Cu")
	)
	(gr_line
		(start 118.4656 -9.28751)
		(end 118.4656 -7.25551)
		(stroke
			(width 0.762)
			(type default)
		)
		(layer "In4.Cu")
	)
	(gr_line
		(start 118.4656 -9.23671)
		(end 118.4656 -7.45871)
		(stroke
			(width 0.635)
			(type default)
		)
		(layer "In4.Cu")
	)
	(gr_line
		(start 118.5164 -13.5128)
		(end 118.5164 -11.4808)
		(stroke
			(width 0.762)
			(type default)
		)
		(layer "In4.Cu")
	)
	(gr_line
		(start 118.5164 -9.31291)
		(end 118.5164 -7.28091)
		(stroke
			(width 0.762)
			(type default)
		)
		(layer "In4.Cu")
	)
	(gr_line
		(start 118.5418 -13.5128)
		(end 118.5418 -11.4808)
		(stroke
			(width 0.762)
			(type default)
		)
		(layer "In4.Cu")
	)
	(gr_line
		(start 118.5418 -13.4874)
		(end 118.5418 -11.4554)
		(stroke
			(width 0.762)
			(type default)
		)
		(layer "In4.Cu")
	)
	(gr_line
		(start 118.5418 -13.4366)
		(end 118.4656 -13.4366)
		(stroke
			(width 0.635)
			(type default)
		)
		(layer "In4.Cu")
	)
	(gr_line
		(start 118.5418 -11.7094)
		(end 118.5418 -13.4366)
		(stroke
			(width 0.635)
			(type default)
		)
		(layer "In4.Cu")
	)
	(gr_line
		(start 118.5418 -9.31291)
		(end 118.5418 -7.28091)
		(stroke
			(width 0.762)
			(type default)
		)
		(layer "In4.Cu")
	)
	(gr_line
		(start 118.5418 -9.28751)
		(end 118.5418 -7.25551)
		(stroke
			(width 0.762)
			(type default)
		)
		(layer "In4.Cu")
	)
	(gr_line
		(start 118.5418 -9.23671)
		(end 118.4656 -9.23671)
		(stroke
			(width 0.635)
			(type default)
		)
		(layer "In4.Cu")
	)
	(gr_line
		(start 118.5418 -7.50951)
		(end 118.5418 -9.23671)
		(stroke
			(width 0.635)
			(type default)
		)
		(layer "In4.Cu")
	)
	(gr_line
		(start 118.5926 -13.4874)
		(end 118.5926 -11.4554)
		(stroke
			(width 0.762)
			(type default)
		)
		(layer "In4.Cu")
	)
	(gr_line
		(start 118.5926 -9.28751)
		(end 118.5926 -7.25551)
		(stroke
			(width 0.762)
			(type default)
		)
		(layer "In4.Cu")
	)
	(gr_line
		(start 118.618 -13.4874)
		(end 118.618 -11.4554)
		(stroke
			(width 0.762)
			(type default)
		)
		(layer "In4.Cu")
	)
	(gr_line
		(start 118.618 -9.28751)
		(end 118.618 -7.25551)
		(stroke
			(width 0.762)
			(type default)
		)
		(layer "In4.Cu")
	)
	(gr_line
		(start 118.6688 -13.5128)
		(end 118.6688 -11.4808)
		(stroke
			(width 0.762)
			(type default)
		)
		(layer "In4.Cu")
	)
	(gr_line
		(start 118.6688 -9.31291)
		(end 118.6688 -7.28091)
		(stroke
			(width 0.762)
			(type default)
		)
		(layer "In4.Cu")
	)
	(gr_line
		(start 118.6942 -13.843)
		(end 119.2022 -13.843)
		(stroke
			(width 0.1016)
			(type default)
		)
		(layer "In4.Cu")
	)
	(gr_line
		(start 118.6942 -13.4874)
		(end 118.6942 -11.4554)
		(stroke
			(width 0.762)
			(type default)
		)
		(layer "In4.Cu")
	)
	(gr_line
		(start 118.6942 -9.64311)
		(end 119.2022 -9.64311)
		(stroke
			(width 0.1016)
			(type default)
		)
		(layer "In4.Cu")
	)
	(gr_line
		(start 118.6942 -9.28751)
		(end 118.6942 -7.25551)
		(stroke
			(width 0.762)
			(type default)
		)
		(layer "In4.Cu")
	)
	(gr_line
		(start 118.745 -13.5128)
		(end 118.745 -11.4808)
		(stroke
			(width 0.762)
			(type default)
		)
		(layer "In4.Cu")
	)
	(gr_line
		(start 118.745 -13.4874)
		(end 118.745 -11.4554)
		(stroke
			(width 0.762)
			(type default)
		)
		(layer "In4.Cu")
	)
	(gr_line
		(start 118.745 -9.31291)
		(end 118.745 -7.28091)
		(stroke
			(width 0.762)
			(type default)
		)
		(layer "In4.Cu")
	)
	(gr_line
		(start 118.745 -9.28751)
		(end 118.745 -7.25551)
		(stroke
			(width 0.762)
			(type default)
		)
		(layer "In4.Cu")
	)
	(gr_line
		(start 118.7704 -13.4874)
		(end 118.7704 -11.4554)
		(stroke
			(width 0.762)
			(type default)
		)
		(layer "In4.Cu")
	)
	(gr_line
		(start 118.7704 -9.28751)
		(end 118.7704 -7.25551)
		(stroke
			(width 0.762)
			(type default)
		)
		(layer "In4.Cu")
	)
	(gr_line
		(start 118.7958 -13.5636)
		(end 118.1608 -13.5636)
		(stroke
			(width 0.508)
			(type default)
		)
		(layer "In4.Cu")
	)
	(gr_line
		(start 118.7958 -13.5636)
		(end 118.2116 -13.5636)
		(stroke
			(width 0.635)
			(type default)
		)
		(layer "In4.Cu")
	)
	(gr_line
		(start 118.7958 -9.36371)
		(end 118.1608 -9.36371)
		(stroke
			(width 0.508)
			(type default)
		)
		(layer "In4.Cu")
	)
	(gr_line
		(start 118.7958 -9.36371)
		(end 118.2116 -9.36371)
		(stroke
			(width 0.635)
			(type default)
		)
		(layer "In4.Cu")
	)
	(gr_line
		(start 118.8212 -13.4874)
		(end 118.8212 -11.4554)
		(stroke
			(width 0.762)
			(type default)
		)
		(layer "In4.Cu")
	)
	(gr_line
		(start 118.8212 -9.28751)
		(end 118.8212 -7.25551)
		(stroke
			(width 0.762)
			(type default)
		)
		(layer "In4.Cu")
	)
	(gr_line
		(start 118.8466 -13.716)
		(end 118.0084 -13.716)
		(stroke
			(width 0.3556)
			(type default)
		)
		(layer "In4.Cu")
	)
	(gr_line
		(start 118.8466 -13.6906)
		(end 118.0592 -13.6906)
		(stroke
			(width 0.381)
			(type default)
		)
		(layer "In4.Cu")
	)
	(gr_line
		(start 118.8466 -9.51611)
		(end 118.0084 -9.51611)
		(stroke
			(width 0.3556)
			(type default)
		)
		(layer "In4.Cu")
	)
	(gr_line
		(start 118.8466 -9.49071)
		(end 118.0592 -9.49071)
		(stroke
			(width 0.381)
			(type default)
		)
		(layer "In4.Cu")
	)
	(gr_line
		(start 118.872 -13.5128)
		(end 118.872 -11.4808)
		(stroke
			(width 0.762)
			(type default)
		)
		(layer "In4.Cu")
	)
	(gr_line
		(start 118.872 -9.31291)
		(end 118.872 -7.28091)
		(stroke
			(width 0.762)
			(type default)
		)
		(layer "In4.Cu")
	)
	(gr_line
		(start 118.8974 -13.7668)
		(end 117.9576 -13.7668)
		(stroke
			(width 0.254)
			(type default)
		)
		(layer "In4.Cu")
	)
	(gr_line
		(start 118.8974 -13.5128)
		(end 118.4402 -13.5128)
		(stroke
			(width 0.635)
			(type default)
		)
		(layer "In4.Cu")
	)
	(gr_line
		(start 118.8974 -11.43)
		(end 118.8974 -13.5128)
		(stroke
			(width 0.635)
			(type default)
		)
		(layer "In4.Cu")
	)
	(gr_line
		(start 118.8974 -9.56691)
		(end 117.9576 -9.56691)
		(stroke
			(width 0.254)
			(type default)
		)
		(layer "In4.Cu")
	)
	(gr_line
		(start 118.8974 -9.31291)
		(end 118.4402 -9.31291)
		(stroke
			(width 0.635)
			(type default)
		)
		(layer "In4.Cu")
	)
	(gr_line
		(start 118.8974 -7.23011)
		(end 118.8974 -9.31291)
		(stroke
			(width 0.635)
			(type default)
		)
		(layer "In4.Cu")
	)
	(gr_line
		(start 118.9228 -13.7922)
		(end 117.9068 -13.7922)
		(stroke
			(width 0.1778)
			(type default)
		)
		(layer "In4.Cu")
	)
	(gr_line
		(start 118.9228 -13.5636)
		(end 118.7958 -13.5636)
		(stroke
			(width 0.508)
			(type default)
		)
		(layer "In4.Cu")
	)
	(gr_line
		(start 118.9228 -11.3792)
		(end 118.9228 -13.5636)
		(stroke
			(width 0.508)
			(type default)
		)
		(layer "In4.Cu")
	)
	(gr_line
		(start 118.9228 -9.59231)
		(end 117.9068 -9.59231)
		(stroke
			(width 0.1778)
			(type default)
		)
		(layer "In4.Cu")
	)
	(gr_line
		(start 118.9228 -9.36371)
		(end 118.7958 -9.36371)
		(stroke
			(width 0.508)
			(type default)
		)
		(layer "In4.Cu")
	)
	(gr_line
		(start 118.9228 -7.17931)
		(end 118.9228 -9.36371)
		(stroke
			(width 0.508)
			(type default)
		)
		(layer "In4.Cu")
	)
	(gr_line
		(start 118.9482 -13.5636)
		(end 118.7958 -13.5636)
		(stroke
			(width 0.381)
			(type default)
		)
		(layer "In4.Cu")
	)
	(gr_line
		(start 118.9482 -11.3792)
		(end 118.9482 -13.5636)
		(stroke
			(width 0.381)
			(type default)
		)
		(layer "In4.Cu")
	)
	(gr_line
		(start 118.9482 -9.36371)
		(end 118.7958 -9.36371)
		(stroke
			(width 0.381)
			(type default)
		)
		(layer "In4.Cu")
	)
	(gr_line
		(start 118.9482 -7.17931)
		(end 118.9482 -9.36371)
		(stroke
			(width 0.381)
			(type default)
		)
		(layer "In4.Cu")
	)
	(gr_line
		(start 118.999 -13.6398)
		(end 118.1354 -13.6398)
		(stroke
			(width 0.381)
			(type default)
		)
		(layer "In4.Cu")
	)
	(gr_line
		(start 118.999 -11.3284)
		(end 118.999 -13.6398)
		(stroke
			(width 0.381)
			(type default)
		)
		(layer "In4.Cu")
	)
	(gr_line
		(start 118.999 -9.43991)
		(end 118.1354 -9.43991)
		(stroke
			(width 0.381)
			(type default)
		)
		(layer "In4.Cu")
	)
	(gr_line
		(start 118.999 -7.12851)
		(end 118.999 -9.43991)
		(stroke
			(width 0.381)
			(type default)
		)
		(layer "In4.Cu")
	)
	(gr_line
		(start 119.0498 -13.6906)
		(end 118.8466 -13.6906)
		(stroke
			(width 0.3556)
			(type default)
		)
		(layer "In4.Cu")
	)
	(gr_line
		(start 119.0498 -11.2776)
		(end 119.0498 -13.6906)
		(stroke
			(width 0.3556)
			(type default)
		)
		(layer "In4.Cu")
	)
	(gr_line
		(start 119.0498 -9.49071)
		(end 118.8466 -9.49071)
		(stroke
			(width 0.3556)
			(type default)
		)
		(layer "In4.Cu")
	)
	(gr_line
		(start 119.0498 -7.07771)
		(end 119.0498 -9.49071)
		(stroke
			(width 0.3556)
			(type default)
		)
		(layer "In4.Cu")
	)
	(gr_line
		(start 119.0752 -13.8176)
		(end 117.8814 -13.8176)
		(stroke
			(width 0.127)
			(type default)
		)
		(layer "In4.Cu")
	)
	(gr_line
		(start 119.0752 -9.61771)
		(end 117.8814 -9.61771)
		(stroke
			(width 0.127)
			(type default)
		)
		(layer "In4.Cu")
	)
	(gr_line
		(start 119.1006 -13.716)
		(end 118.8466 -13.716)
		(stroke
			(width 0.254)
			(type default)
		)
		(layer "In4.Cu")
	)
	(gr_line
		(start 119.1006 -11.2522)
		(end 119.1006 -13.716)
		(stroke
			(width 0.254)
			(type default)
		)
		(layer "In4.Cu")
	)
	(gr_line
		(start 119.1006 -9.51611)
		(end 118.8466 -9.51611)
		(stroke
			(width 0.254)
			(type default)
		)
		(layer "In4.Cu")
	)
	(gr_line
		(start 119.1006 -7.05231)
		(end 119.1006 -9.51611)
		(stroke
			(width 0.254)
			(type default)
		)
		(layer "In4.Cu")
	)
	(gr_line
		(start 119.126 -13.7668)
		(end 117.983 -13.7668)
		(stroke
			(width 0.254)
			(type default)
		)
		(layer "In4.Cu")
	)
	(gr_line
		(start 119.126 -13.7668)
		(end 118.8974 -13.7668)
		(stroke
			(width 0.1778)
			(type default)
		)
		(layer "In4.Cu")
	)
	(gr_line
		(start 119.126 -11.2268)
		(end 119.126 -13.7668)
		(stroke
			(width 0.254)
			(type default)
		)
		(layer "In4.Cu")
	)
	(gr_line
		(start 119.126 -11.2014)
		(end 119.126 -13.7668)
		(stroke
			(width 0.1778)
			(type default)
		)
		(layer "In4.Cu")
	)
	(gr_line
		(start 119.126 -9.56691)
		(end 117.983 -9.56691)
		(stroke
			(width 0.254)
			(type default)
		)
		(layer "In4.Cu")
	)
	(gr_line
		(start 119.126 -9.56691)
		(end 118.8974 -9.56691)
		(stroke
			(width 0.1778)
			(type default)
		)
		(layer "In4.Cu")
	)
	(gr_line
		(start 119.126 -7.02691)
		(end 119.126 -9.56691)
		(stroke
			(width 0.254)
			(type default)
		)
		(layer "In4.Cu")
	)
	(gr_line
		(start 119.126 -7.00151)
		(end 119.126 -9.56691)
		(stroke
			(width 0.1778)
			(type default)
		)
		(layer "In4.Cu")
	)
	(gr_line
		(start 119.1514 -13.7922)
		(end 117.9322 -13.7922)
		(stroke
			(width 0.1778)
			(type default)
		)
		(layer "In4.Cu")
	)
	(gr_line
		(start 119.1514 -13.7922)
		(end 118.9228 -13.7922)
		(stroke
			(width 0.127)
			(type default)
		)
		(layer "In4.Cu")
	)
	(gr_line
		(start 119.1514 -11.176)
		(end 119.1514 -13.7922)
		(stroke
			(width 0.127)
			(type default)
		)
		(layer "In4.Cu")
	)
	(gr_line
		(start 119.1514 -11.176)
		(end 119.1514 -13.7922)
		(stroke
			(width 0.1778)
			(type default)
		)
		(layer "In4.Cu")
	)
	(gr_line
		(start 119.1514 -9.59231)
		(end 117.9322 -9.59231)
		(stroke
			(width 0.1778)
			(type default)
		)
		(layer "In4.Cu")
	)
	(gr_line
		(start 119.1514 -9.59231)
		(end 118.9228 -9.59231)
		(stroke
			(width 0.127)
			(type default)
		)
		(layer "In4.Cu")
	)
	(gr_line
		(start 119.1514 -6.97611)
		(end 119.1514 -9.59231)
		(stroke
			(width 0.127)
			(type default)
		)
		(layer "In4.Cu")
	)
	(gr_line
		(start 119.1514 -6.97611)
		(end 119.1514 -9.59231)
		(stroke
			(width 0.1778)
			(type default)
		)
		(layer "In4.Cu")
	)
	(gr_line
		(start 119.1768 -13.8176)
		(end 117.9068 -13.8176)
		(stroke
			(width 0.127)
			(type default)
		)
		(layer "In4.Cu")
	)
	(gr_line
		(start 119.1768 -11.1506)
		(end 119.1768 -13.8176)
		(stroke
			(width 0.127)
			(type default)
		)
		(layer "In4.Cu")
	)
	(gr_line
		(start 119.1768 -9.61771)
		(end 117.9068 -9.61771)
		(stroke
			(width 0.127)
			(type default)
		)
		(layer "In4.Cu")
	)
	(gr_line
		(start 119.1768 -6.95071)
		(end 119.1768 -9.61771)
		(stroke
			(width 0.127)
			(type default)
		)
		(layer "In4.Cu")
	)
	(gr_line
		(start 119.2022 -13.843)
		(end 119.2022 -11.1252)
		(stroke
			(width 0.1016)
			(type default)
		)
		(layer "In4.Cu")
	)
	(gr_line
		(start 119.2022 -11.1252)
		(end 117.856 -11.1252)
		(stroke
			(width 0.1016)
			(type default)
		)
		(layer "In4.Cu")
	)
	(gr_line
		(start 119.2022 -9.64311)
		(end 119.2022 -6.92531)
		(stroke
			(width 0.1016)
			(type default)
		)
		(layer "In4.Cu")
	)
	(gr_line
		(start 119.2022 -6.92531)
		(end 117.856 -6.92531)
		(stroke
			(width 0.1016)
			(type default)
		)
		(layer "In4.Cu")
	)
	(gr_line
		(start 127.85598 -12.543028)
		(end 128.69418 -12.543028)
		(stroke
			(width 0.1016)
			(type default)
		)
		(layer "In4.Cu")
	)
	(gr_line
		(start 127.85598 -9.825228)
		(end 127.85598 -12.543028)
		(stroke
			(width 0.1016)
			(type default)
		)
		(layer "In4.Cu")
	)
	(gr_line
		(start 127.85598 -8.343138)
		(end 128.69418 -8.343138)
		(stroke
			(width 0.1016)
			(type default)
		)
		(layer "In4.Cu")
	)
	(gr_line
		(start 127.85598 -5.625338)
		(end 127.85598 -8.343138)
		(stroke
			(width 0.1016)
			(type default)
		)
		(layer "In4.Cu")
	)
	(gr_line
		(start 127.88138 -12.517628)
		(end 127.88138 -9.850628)
		(stroke
			(width 0.127)
			(type default)
		)
		(layer "In4.Cu")
	)
	(gr_line
		(start 127.88138 -9.850628)
		(end 129.17678 -9.850628)
		(stroke
			(width 0.127)
			(type default)
		)
		(layer "In4.Cu")
	)
	(gr_line
		(start 127.88138 -8.317738)
		(end 127.88138 -5.650738)
		(stroke
			(width 0.127)
			(type default)
		)
		(layer "In4.Cu")
	)
	(gr_line
		(start 127.88138 -5.650738)
		(end 129.17678 -5.650738)
		(stroke
			(width 0.127)
			(type default)
		)
		(layer "In4.Cu")
	)
	(gr_line
		(start 127.90678 -12.517628)
		(end 127.90678 -9.876028)
		(stroke
			(width 0.127)
			(type default)
		)
		(layer "In4.Cu")
	)
	(gr_line
		(start 127.90678 -12.492228)
		(end 127.90678 -9.876028)
		(stroke
			(width 0.1778)
			(type default)
		)
		(layer "In4.Cu")
	)
	(gr_line
		(start 127.90678 -9.876028)
		(end 129.15138 -9.876028)
		(stroke
			(width 0.127)
			(type default)
		)
		(layer "In4.Cu")
	)
	(gr_line
		(start 127.90678 -9.876028)
		(end 129.15138 -9.876028)
		(stroke
			(width 0.1778)
			(type default)
		)
		(layer "In4.Cu")
	)
	(gr_line
		(start 127.90678 -8.317738)
		(end 127.90678 -5.676138)
		(stroke
			(width 0.127)
			(type default)
		)
		(layer "In4.Cu")
	)
	(gr_line
		(start 127.90678 -8.292338)
		(end 127.90678 -5.676138)
		(stroke
			(width 0.1778)
			(type default)
		)
		(layer "In4.Cu")
	)
	(gr_line
		(start 127.90678 -5.676138)
		(end 129.15138 -5.676138)
		(stroke
			(width 0.127)
			(type default)
		)
		(layer "In4.Cu")
	)
	(gr_line
		(start 127.90678 -5.676138)
		(end 129.15138 -5.676138)
		(stroke
			(width 0.1778)
			(type default)
		)
		(layer "In4.Cu")
	)
	(gr_line
		(start 127.93218 -12.492228)
		(end 127.93218 -9.901428)
		(stroke
			(width 0.1778)
			(type default)
		)
		(layer "In4.Cu")
	)
	(gr_line
		(start 127.93218 -9.901428)
		(end 129.12598 -9.901428)
		(stroke
			(width 0.1778)
			(type default)
		)
		(layer "In4.Cu")
	)
	(gr_line
		(start 127.93218 -8.292338)
		(end 127.93218 -5.701538)
		(stroke
			(width 0.1778)
			(type default)
		)
		(layer "In4.Cu")
	)
	(gr_line
		(start 127.93218 -5.701538)
		(end 129.12598 -5.701538)
		(stroke
			(width 0.1778)
			(type default)
		)
		(layer "In4.Cu")
	)
	(gr_line
		(start 127.95758 -12.466828)
		(end 127.95758 -9.926828)
		(stroke
			(width 0.254)
			(type default)
		)
		(layer "In4.Cu")
	)
	(gr_line
		(start 127.95758 -9.926828)
		(end 129.12598 -9.926828)
		(stroke
			(width 0.254)
			(type default)
		)
		(layer "In4.Cu")
	)
	(gr_line
		(start 127.95758 -8.266938)
		(end 127.95758 -5.726938)
		(stroke
			(width 0.254)
			(type default)
		)
		(layer "In4.Cu")
	)
	(gr_line
		(start 127.95758 -5.726938)
		(end 129.12598 -5.726938)
		(stroke
			(width 0.254)
			(type default)
		)
		(layer "In4.Cu")
	)
	(gr_line
		(start 127.98298 -12.466828)
		(end 127.98298 -9.952228)
		(stroke
			(width 0.254)
			(type default)
		)
		(layer "In4.Cu")
	)
	(gr_line
		(start 127.98298 -9.952228)
		(end 129.10058 -9.952228)
		(stroke
			(width 0.254)
			(type default)
		)
		(layer "In4.Cu")
	)
	(gr_line
		(start 127.98298 -8.266938)
		(end 127.98298 -5.752338)
		(stroke
			(width 0.254)
			(type default)
		)
		(layer "In4.Cu")
	)
	(gr_line
		(start 127.98298 -5.752338)
		(end 129.10058 -5.752338)
		(stroke
			(width 0.254)
			(type default)
		)
		(layer "In4.Cu")
	)
	(gr_line
		(start 128.00838 -12.416028)
		(end 128.00838 -9.977628)
		(stroke
			(width 0.3556)
			(type default)
		)
		(layer "In4.Cu")
	)
	(gr_line
		(start 128.00838 -9.977628)
		(end 129.04978 -9.977628)
		(stroke
			(width 0.3556)
			(type default)
		)
		(layer "In4.Cu")
	)
	(gr_line
		(start 128.00838 -8.216138)
		(end 128.00838 -5.777738)
		(stroke
			(width 0.3556)
			(type default)
		)
		(layer "In4.Cu")
	)
	(gr_line
		(start 128.00838 -5.777738)
		(end 129.04978 -5.777738)
		(stroke
			(width 0.3556)
			(type default)
		)
		(layer "In4.Cu")
	)
	(gr_line
		(start 128.05918 -12.390628)
		(end 128.05918 -10.028428)
		(stroke
			(width 0.381)
			(type default)
		)
		(layer "In4.Cu")
	)
	(gr_line
		(start 128.05918 -10.028428)
		(end 128.99898 -10.028428)
		(stroke
			(width 0.381)
			(type default)
		)
		(layer "In4.Cu")
	)
	(gr_line
		(start 128.05918 -8.190738)
		(end 128.05918 -5.828538)
		(stroke
			(width 0.381)
			(type default)
		)
		(layer "In4.Cu")
	)
	(gr_line
		(start 128.05918 -5.828538)
		(end 128.99898 -5.828538)
		(stroke
			(width 0.381)
			(type default)
		)
		(layer "In4.Cu")
	)
	(gr_line
		(start 128.13538 -12.339828)
		(end 128.13538 -10.079228)
		(stroke
			(width 0.381)
			(type default)
		)
		(layer "In4.Cu")
	)
	(gr_line
		(start 128.13538 -10.079228)
		(end 128.94818 -10.079228)
		(stroke
			(width 0.381)
			(type default)
		)
		(layer "In4.Cu")
	)
	(gr_line
		(start 128.13538 -8.139938)
		(end 128.13538 -5.879338)
		(stroke
			(width 0.381)
			(type default)
		)
		(layer "In4.Cu")
	)
	(gr_line
		(start 128.13538 -5.879338)
		(end 128.94818 -5.879338)
		(stroke
			(width 0.381)
			(type default)
		)
		(layer "In4.Cu")
	)
	(gr_line
		(start 128.16078 -12.263628)
		(end 128.16078 -10.079228)
		(stroke
			(width 0.508)
			(type default)
		)
		(layer "In4.Cu")
	)
	(gr_line
		(start 128.16078 -10.079228)
		(end 128.92278 -10.079228)
		(stroke
			(width 0.508)
			(type default)
		)
		(layer "In4.Cu")
	)
	(gr_line
		(start 128.16078 -8.063738)
		(end 128.16078 -5.879338)
		(stroke
			(width 0.508)
			(type default)
		)
		(layer "In4.Cu")
	)
	(gr_line
		(start 128.16078 -5.879338)
		(end 128.92278 -5.879338)
		(stroke
			(width 0.508)
			(type default)
		)
		(layer "In4.Cu")
	)
	(gr_line
		(start 128.18618 -12.111228)
		(end 128.77038 -12.111228)
		(stroke
			(width 0.762)
			(type default)
		)
		(layer "In4.Cu")
	)
	(gr_line
		(start 128.18618 -10.282428)
		(end 128.77038 -10.282428)
		(stroke
			(width 0.762)
			(type default)
		)
		(layer "In4.Cu")
	)
	(gr_line
		(start 128.18618 -7.911338)
		(end 128.77038 -7.911338)
		(stroke
			(width 0.762)
			(type default)
		)
		(layer "In4.Cu")
	)
	(gr_line
		(start 128.18618 -6.082538)
		(end 128.77038 -6.082538)
		(stroke
			(width 0.762)
			(type default)
		)
		(layer "In4.Cu")
	)
	(gr_line
		(start 128.21158 -12.263628)
		(end 128.21158 -10.130028)
		(stroke
			(width 0.635)
			(type default)
		)
		(layer "In4.Cu")
	)
	(gr_line
		(start 128.21158 -12.212828)
		(end 128.21158 -10.180828)
		(stroke
			(width 0.762)
			(type default)
		)
		(layer "In4.Cu")
	)
	(gr_line
		(start 128.21158 -10.130028)
		(end 128.89738 -10.130028)
		(stroke
			(width 0.635)
			(type default)
		)
		(layer "In4.Cu")
	)
	(gr_line
		(start 128.21158 -8.063738)
		(end 128.21158 -5.930138)
		(stroke
			(width 0.635)
			(type default)
		)
		(layer "In4.Cu")
	)
	(gr_line
		(start 128.21158 -8.012938)
		(end 128.21158 -5.980938)
		(stroke
			(width 0.762)
			(type default)
		)
		(layer "In4.Cu")
	)
	(gr_line
		(start 128.21158 -5.930138)
		(end 128.89738 -5.930138)
		(stroke
			(width 0.635)
			(type default)
		)
		(layer "In4.Cu")
	)
	(gr_line
		(start 128.23698 -12.212828)
		(end 128.23698 -10.180828)
		(stroke
			(width 0.762)
			(type default)
		)
		(layer "In4.Cu")
	)
	(gr_line
		(start 128.23698 -10.180828)
		(end 128.82118 -10.180828)
		(stroke
			(width 0.762)
			(type default)
		)
		(layer "In4.Cu")
	)
	(gr_line
		(start 128.23698 -8.012938)
		(end 128.23698 -5.980938)
		(stroke
			(width 0.762)
			(type default)
		)
		(layer "In4.Cu")
	)
	(gr_line
		(start 128.23698 -5.980938)
		(end 128.82118 -5.980938)
		(stroke
			(width 0.762)
			(type default)
		)
		(layer "In4.Cu")
	)
	(gr_line
		(start 128.26238 -12.212828)
		(end 128.26238 -10.180828)
		(stroke
			(width 0.762)
			(type default)
		)
		(layer "In4.Cu")
	)
	(gr_line
		(start 128.26238 -12.212828)
		(end 128.84658 -12.212828)
		(stroke
			(width 0.762)
			(type default)
		)
		(layer "In4.Cu")
	)
	(gr_line
		(start 128.26238 -12.187428)
		(end 128.26238 -10.155428)
		(stroke
			(width 0.762)
			(type default)
		)
		(layer "In4.Cu")
	)
	(gr_line
		(start 128.26238 -8.012938)
		(end 128.26238 -5.980938)
		(stroke
			(width 0.762)
			(type default)
		)
		(layer "In4.Cu")
	)
	(gr_line
		(start 128.26238 -8.012938)
		(end 128.84658 -8.012938)
		(stroke
			(width 0.762)
			(type default)
		)
		(layer "In4.Cu")
	)
	(gr_line
		(start 128.26238 -7.987538)
		(end 128.26238 -5.955538)
		(stroke
			(width 0.762)
			(type default)
		)
		(layer "In4.Cu")
	)
	(gr_line
		(start 128.28778 -12.212828)
		(end 128.28778 -10.180828)
		(stroke
			(width 0.762)
			(type default)
		)
		(layer "In4.Cu")
	)
	(gr_line
		(start 128.28778 -8.012938)
		(end 128.28778 -5.980938)
		(stroke
			(width 0.762)
			(type default)
		)
		(layer "In4.Cu")
	)
	(gr_line
		(start 128.31318 -12.212828)
		(end 128.31318 -10.180828)
		(stroke
			(width 0.762)
			(type default)
		)
		(layer "In4.Cu")
	)
	(gr_line
		(start 128.31318 -8.012938)
		(end 128.31318 -5.980938)
		(stroke
			(width 0.762)
			(type default)
		)
		(layer "In4.Cu")
	)
	(gr_line
		(start 128.33858 -12.212828)
		(end 128.33858 -10.180828)
		(stroke
			(width 0.762)
			(type default)
		)
		(layer "In4.Cu")
	)
	(gr_line
		(start 128.33858 -8.012938)
		(end 128.33858 -5.980938)
		(stroke
			(width 0.762)
			(type default)
		)
		(layer "In4.Cu")
	)
	(gr_line
		(start 128.38938 -12.212828)
		(end 128.38938 -10.180828)
		(stroke
			(width 0.762)
			(type default)
		)
		(layer "In4.Cu")
	)
	(gr_line
		(start 128.38938 -8.012938)
		(end 128.38938 -5.980938)
		(stroke
			(width 0.762)
			(type default)
		)
		(layer "In4.Cu")
	)
	(gr_line
		(start 128.41478 -12.212828)
		(end 128.41478 -10.180828)
		(stroke
			(width 0.762)
			(type default)
		)
		(layer "In4.Cu")
	)
	(gr_line
		(start 128.41478 -8.012938)
		(end 128.41478 -5.980938)
		(stroke
			(width 0.762)
			(type default)
		)
		(layer "In4.Cu")
	)
	(gr_line
		(start 128.44018 -12.212828)
		(end 128.44018 -10.409428)
		(stroke
			(width 0.635)
			(type default)
		)
		(layer "In4.Cu")
	)
	(gr_line
		(start 128.44018 -10.409428)
		(end 128.54178 -10.409428)
		(stroke
			(width 0.635)
			(type default)
		)
		(layer "In4.Cu")
	)
	(gr_line
		(start 128.44018 -8.012938)
		(end 128.44018 -6.209538)
		(stroke
			(width 0.635)
			(type default)
		)
		(layer "In4.Cu")
	)
	(gr_line
		(start 128.44018 -6.209538)
		(end 128.54178 -6.209538)
		(stroke
			(width 0.635)
			(type default)
		)
		(layer "In4.Cu")
	)
	(gr_line
		(start 128.46558 -12.212828)
		(end 128.46558 -10.180828)
		(stroke
			(width 0.762)
			(type default)
		)
		(layer "In4.Cu")
	)
	(gr_line
		(start 128.46558 -12.187428)
		(end 128.46558 -10.155428)
		(stroke
			(width 0.762)
			(type default)
		)
		(layer "In4.Cu")
	)
	(gr_line
		(start 128.46558 -12.136628)
		(end 128.46558 -10.358628)
		(stroke
			(width 0.635)
			(type default)
		)
		(layer "In4.Cu")
	)
	(gr_line
		(start 128.46558 -8.012938)
		(end 128.46558 -5.980938)
		(stroke
			(width 0.762)
			(type default)
		)
		(layer "In4.Cu")
	)
	(gr_line
		(start 128.46558 -7.987538)
		(end 128.46558 -5.955538)
		(stroke
			(width 0.762)
			(type default)
		)
		(layer "In4.Cu")
	)
	(gr_line
		(start 128.46558 -7.936738)
		(end 128.46558 -6.158738)
		(stroke
			(width 0.635)
			(type default)
		)
		(layer "In4.Cu")
	)
	(gr_line
		(start 128.51638 -12.212828)
		(end 128.51638 -10.180828)
		(stroke
			(width 0.762)
			(type default)
		)
		(layer "In4.Cu")
	)
	(gr_line
		(start 128.51638 -8.012938)
		(end 128.51638 -5.980938)
		(stroke
			(width 0.762)
			(type default)
		)
		(layer "In4.Cu")
	)
	(gr_line
		(start 128.54178 -12.212828)
		(end 128.54178 -10.180828)
		(stroke
			(width 0.762)
			(type default)
		)
		(layer "In4.Cu")
	)
	(gr_line
		(start 128.54178 -12.187428)
		(end 128.54178 -10.155428)
		(stroke
			(width 0.762)
			(type default)
		)
		(layer "In4.Cu")
	)
	(gr_line
		(start 128.54178 -12.136628)
		(end 128.46558 -12.136628)
		(stroke
			(width 0.635)
			(type default)
		)
		(layer "In4.Cu")
	)
	(gr_line
		(start 128.54178 -10.409428)
		(end 128.54178 -12.136628)
		(stroke
			(width 0.635)
			(type default)
		)
		(layer "In4.Cu")
	)
	(gr_line
		(start 128.54178 -8.012938)
		(end 128.54178 -5.980938)
		(stroke
			(width 0.762)
			(type default)
		)
		(layer "In4.Cu")
	)
	(gr_line
		(start 128.54178 -7.987538)
		(end 128.54178 -5.955538)
		(stroke
			(width 0.762)
			(type default)
		)
		(layer "In4.Cu")
	)
	(gr_line
		(start 128.54178 -7.936738)
		(end 128.46558 -7.936738)
		(stroke
			(width 0.635)
			(type default)
		)
		(layer "In4.Cu")
	)
	(gr_line
		(start 128.54178 -6.209538)
		(end 128.54178 -7.936738)
		(stroke
			(width 0.635)
			(type default)
		)
		(layer "In4.Cu")
	)
	(gr_line
		(start 128.59258 -12.187428)
		(end 128.59258 -10.155428)
		(stroke
			(width 0.762)
			(type default)
		)
		(layer "In4.Cu")
	)
	(gr_line
		(start 128.59258 -7.987538)
		(end 128.59258 -5.955538)
		(stroke
			(width 0.762)
			(type default)
		)
		(layer "In4.Cu")
	)
	(gr_line
		(start 128.61798 -12.187428)
		(end 128.61798 -10.155428)
		(stroke
			(width 0.762)
			(type default)
		)
		(layer "In4.Cu")
	)
	(gr_line
		(start 128.61798 -7.987538)
		(end 128.61798 -5.955538)
		(stroke
			(width 0.762)
			(type default)
		)
		(layer "In4.Cu")
	)
	(gr_line
		(start 128.66878 -12.212828)
		(end 128.66878 -10.180828)
		(stroke
			(width 0.762)
			(type default)
		)
		(layer "In4.Cu")
	)
	(gr_line
		(start 128.66878 -8.012938)
		(end 128.66878 -5.980938)
		(stroke
			(width 0.762)
			(type default)
		)
		(layer "In4.Cu")
	)
	(gr_line
		(start 128.69418 -12.543028)
		(end 129.20218 -12.543028)
		(stroke
			(width 0.1016)
			(type default)
		)
		(layer "In4.Cu")
	)
	(gr_line
		(start 128.69418 -12.187428)
		(end 128.69418 -10.155428)
		(stroke
			(width 0.762)
			(type default)
		)
		(layer "In4.Cu")
	)
	(gr_line
		(start 128.69418 -8.343138)
		(end 129.20218 -8.343138)
		(stroke
			(width 0.1016)
			(type default)
		)
		(layer "In4.Cu")
	)
	(gr_line
		(start 128.69418 -7.987538)
		(end 128.69418 -5.955538)
		(stroke
			(width 0.762)
			(type default)
		)
		(layer "In4.Cu")
	)
	(gr_line
		(start 128.74498 -12.212828)
		(end 128.74498 -10.180828)
		(stroke
			(width 0.762)
			(type default)
		)
		(layer "In4.Cu")
	)
	(gr_line
		(start 128.74498 -12.187428)
		(end 128.74498 -10.155428)
		(stroke
			(width 0.762)
			(type default)
		)
		(layer "In4.Cu")
	)
	(gr_line
		(start 128.74498 -8.012938)
		(end 128.74498 -5.980938)
		(stroke
			(width 0.762)
			(type default)
		)
		(layer "In4.Cu")
	)
	(gr_line
		(start 128.74498 -7.987538)
		(end 128.74498 -5.955538)
		(stroke
			(width 0.762)
			(type default)
		)
		(layer "In4.Cu")
	)
	(gr_line
		(start 128.77038 -12.187428)
		(end 128.77038 -10.155428)
		(stroke
			(width 0.762)
			(type default)
		)
		(layer "In4.Cu")
	)
	(gr_line
		(start 128.77038 -7.987538)
		(end 128.77038 -5.955538)
		(stroke
			(width 0.762)
			(type default)
		)
		(layer "In4.Cu")
	)
	(gr_line
		(start 128.79578 -12.263628)
		(end 128.16078 -12.263628)
		(stroke
			(width 0.508)
			(type default)
		)
		(layer "In4.Cu")
	)
	(gr_line
		(start 128.79578 -12.263628)
		(end 128.21158 -12.263628)
		(stroke
			(width 0.635)
			(type default)
		)
		(layer "In4.Cu")
	)
	(gr_line
		(start 128.79578 -8.063738)
		(end 128.16078 -8.063738)
		(stroke
			(width 0.508)
			(type default)
		)
		(layer "In4.Cu")
	)
	(gr_line
		(start 128.79578 -8.063738)
		(end 128.21158 -8.063738)
		(stroke
			(width 0.635)
			(type default)
		)
		(layer "In4.Cu")
	)
	(gr_line
		(start 128.82118 -12.187428)
		(end 128.82118 -10.155428)
		(stroke
			(width 0.762)
			(type default)
		)
		(layer "In4.Cu")
	)
	(gr_line
		(start 128.82118 -7.987538)
		(end 128.82118 -5.955538)
		(stroke
			(width 0.762)
			(type default)
		)
		(layer "In4.Cu")
	)
	(gr_line
		(start 128.84658 -12.416028)
		(end 128.00838 -12.416028)
		(stroke
			(width 0.3556)
			(type default)
		)
		(layer "In4.Cu")
	)
	(gr_line
		(start 128.84658 -12.390628)
		(end 128.05918 -12.390628)
		(stroke
			(width 0.381)
			(type default)
		)
		(layer "In4.Cu")
	)
	(gr_line
		(start 128.84658 -8.216138)
		(end 128.00838 -8.216138)
		(stroke
			(width 0.3556)
			(type default)
		)
		(layer "In4.Cu")
	)
	(gr_line
		(start 128.84658 -8.190738)
		(end 128.05918 -8.190738)
		(stroke
			(width 0.381)
			(type default)
		)
		(layer "In4.Cu")
	)
	(gr_line
		(start 128.87198 -12.212828)
		(end 128.87198 -10.180828)
		(stroke
			(width 0.762)
			(type default)
		)
		(layer "In4.Cu")
	)
	(gr_line
		(start 128.87198 -8.012938)
		(end 128.87198 -5.980938)
		(stroke
			(width 0.762)
			(type default)
		)
		(layer "In4.Cu")
	)
	(gr_line
		(start 128.89738 -12.466828)
		(end 127.95758 -12.466828)
		(stroke
			(width 0.254)
			(type default)
		)
		(layer "In4.Cu")
	)
	(gr_line
		(start 128.89738 -12.212828)
		(end 128.44018 -12.212828)
		(stroke
			(width 0.635)
			(type default)
		)
		(layer "In4.Cu")
	)
	(gr_line
		(start 128.89738 -10.130028)
		(end 128.89738 -12.212828)
		(stroke
			(width 0.635)
			(type default)
		)
		(layer "In4.Cu")
	)
	(gr_line
		(start 128.89738 -8.266938)
		(end 127.95758 -8.266938)
		(stroke
			(width 0.254)
			(type default)
		)
		(layer "In4.Cu")
	)
	(gr_line
		(start 128.89738 -8.012938)
		(end 128.44018 -8.012938)
		(stroke
			(width 0.635)
			(type default)
		)
		(layer "In4.Cu")
	)
	(gr_line
		(start 128.89738 -5.930138)
		(end 128.89738 -8.012938)
		(stroke
			(width 0.635)
			(type default)
		)
		(layer "In4.Cu")
	)
	(gr_line
		(start 128.92278 -12.492228)
		(end 127.90678 -12.492228)
		(stroke
			(width 0.1778)
			(type default)
		)
		(layer "In4.Cu")
	)
	(gr_line
		(start 128.92278 -12.263628)
		(end 128.79578 -12.263628)
		(stroke
			(width 0.508)
			(type default)
		)
		(layer "In4.Cu")
	)
	(gr_line
		(start 128.92278 -10.079228)
		(end 128.92278 -12.263628)
		(stroke
			(width 0.508)
			(type default)
		)
		(layer "In4.Cu")
	)
	(gr_line
		(start 128.92278 -8.292338)
		(end 127.90678 -8.292338)
		(stroke
			(width 0.1778)
			(type default)
		)
		(layer "In4.Cu")
	)
	(gr_line
		(start 128.92278 -8.063738)
		(end 128.79578 -8.063738)
		(stroke
			(width 0.508)
			(type default)
		)
		(layer "In4.Cu")
	)
	(gr_line
		(start 128.92278 -5.879338)
		(end 128.92278 -8.063738)
		(stroke
			(width 0.508)
			(type default)
		)
		(layer "In4.Cu")
	)
	(gr_line
		(start 128.94818 -12.263628)
		(end 128.79578 -12.263628)
		(stroke
			(width 0.381)
			(type default)
		)
		(layer "In4.Cu")
	)
	(gr_line
		(start 128.94818 -10.079228)
		(end 128.94818 -12.263628)
		(stroke
			(width 0.381)
			(type default)
		)
		(layer "In4.Cu")
	)
	(gr_line
		(start 128.94818 -8.063738)
		(end 128.79578 -8.063738)
		(stroke
			(width 0.381)
			(type default)
		)
		(layer "In4.Cu")
	)
	(gr_line
		(start 128.94818 -5.879338)
		(end 128.94818 -8.063738)
		(stroke
			(width 0.381)
			(type default)
		)
		(layer "In4.Cu")
	)
	(gr_line
		(start 128.99898 -12.339828)
		(end 128.13538 -12.339828)
		(stroke
			(width 0.381)
			(type default)
		)
		(layer "In4.Cu")
	)
	(gr_line
		(start 128.99898 -10.028428)
		(end 128.99898 -12.339828)
		(stroke
			(width 0.381)
			(type default)
		)
		(layer "In4.Cu")
	)
	(gr_line
		(start 128.99898 -8.139938)
		(end 128.13538 -8.139938)
		(stroke
			(width 0.381)
			(type default)
		)
		(layer "In4.Cu")
	)
	(gr_line
		(start 128.99898 -5.828538)
		(end 128.99898 -8.139938)
		(stroke
			(width 0.381)
			(type default)
		)
		(layer "In4.Cu")
	)
	(gr_line
		(start 129.04978 -12.390628)
		(end 128.84658 -12.390628)
		(stroke
			(width 0.3556)
			(type default)
		)
		(layer "In4.Cu")
	)
	(gr_line
		(start 129.04978 -9.977628)
		(end 129.04978 -12.390628)
		(stroke
			(width 0.3556)
			(type default)
		)
		(layer "In4.Cu")
	)
	(gr_line
		(start 129.04978 -8.190738)
		(end 128.84658 -8.190738)
		(stroke
			(width 0.3556)
			(type default)
		)
		(layer "In4.Cu")
	)
	(gr_line
		(start 129.04978 -5.777738)
		(end 129.04978 -8.190738)
		(stroke
			(width 0.3556)
			(type default)
		)
		(layer "In4.Cu")
	)
	(gr_line
		(start 129.07518 -12.517628)
		(end 127.88138 -12.517628)
		(stroke
			(width 0.127)
			(type default)
		)
		(layer "In4.Cu")
	)
	(gr_line
		(start 129.07518 -8.317738)
		(end 127.88138 -8.317738)
		(stroke
			(width 0.127)
			(type default)
		)
		(layer "In4.Cu")
	)
	(gr_line
		(start 129.10058 -12.416028)
		(end 128.84658 -12.416028)
		(stroke
			(width 0.254)
			(type default)
		)
		(layer "In4.Cu")
	)
	(gr_line
		(start 129.10058 -9.952228)
		(end 129.10058 -12.416028)
		(stroke
			(width 0.254)
			(type default)
		)
		(layer "In4.Cu")
	)
	(gr_line
		(start 129.10058 -8.216138)
		(end 128.84658 -8.216138)
		(stroke
			(width 0.254)
			(type default)
		)
		(layer "In4.Cu")
	)
	(gr_line
		(start 129.10058 -5.752338)
		(end 129.10058 -8.216138)
		(stroke
			(width 0.254)
			(type default)
		)
		(layer "In4.Cu")
	)
	(gr_line
		(start 129.12598 -12.466828)
		(end 127.98298 -12.466828)
		(stroke
			(width 0.254)
			(type default)
		)
		(layer "In4.Cu")
	)
	(gr_line
		(start 129.12598 -12.466828)
		(end 128.89738 -12.466828)
		(stroke
			(width 0.1778)
			(type default)
		)
		(layer "In4.Cu")
	)
	(gr_line
		(start 129.12598 -9.926828)
		(end 129.12598 -12.466828)
		(stroke
			(width 0.254)
			(type default)
		)
		(layer "In4.Cu")
	)
	(gr_line
		(start 129.12598 -9.901428)
		(end 129.12598 -12.466828)
		(stroke
			(width 0.1778)
			(type default)
		)
		(layer "In4.Cu")
	)
	(gr_line
		(start 129.12598 -8.266938)
		(end 127.98298 -8.266938)
		(stroke
			(width 0.254)
			(type default)
		)
		(layer "In4.Cu")
	)
	(gr_line
		(start 129.12598 -8.266938)
		(end 128.89738 -8.266938)
		(stroke
			(width 0.1778)
			(type default)
		)
		(layer "In4.Cu")
	)
	(gr_line
		(start 129.12598 -5.726938)
		(end 129.12598 -8.266938)
		(stroke
			(width 0.254)
			(type default)
		)
		(layer "In4.Cu")
	)
	(gr_line
		(start 129.12598 -5.701538)
		(end 129.12598 -8.266938)
		(stroke
			(width 0.1778)
			(type default)
		)
		(layer "In4.Cu")
	)
	(gr_line
		(start 129.15138 -12.492228)
		(end 127.93218 -12.492228)
		(stroke
			(width 0.1778)
			(type default)
		)
		(layer "In4.Cu")
	)
	(gr_line
		(start 129.15138 -12.492228)
		(end 128.92278 -12.492228)
		(stroke
			(width 0.127)
			(type default)
		)
		(layer "In4.Cu")
	)
	(gr_line
		(start 129.15138 -9.876028)
		(end 129.15138 -12.492228)
		(stroke
			(width 0.127)
			(type default)
		)
		(layer "In4.Cu")
	)
	(gr_line
		(start 129.15138 -9.876028)
		(end 129.15138 -12.492228)
		(stroke
			(width 0.1778)
			(type default)
		)
		(layer "In4.Cu")
	)
	(gr_line
		(start 129.15138 -8.292338)
		(end 127.93218 -8.292338)
		(stroke
			(width 0.1778)
			(type default)
		)
		(layer "In4.Cu")
	)
	(gr_line
		(start 129.15138 -8.292338)
		(end 128.92278 -8.292338)
		(stroke
			(width 0.127)
			(type default)
		)
		(layer "In4.Cu")
	)
	(gr_line
		(start 129.15138 -5.676138)
		(end 129.15138 -8.292338)
		(stroke
			(width 0.127)
			(type default)
		)
		(layer "In4.Cu")
	)
	(gr_line
		(start 129.15138 -5.676138)
		(end 129.15138 -8.292338)
		(stroke
			(width 0.1778)
			(type default)
		)
		(layer "In4.Cu")
	)
	(gr_line
		(start 129.17678 -12.517628)
		(end 127.90678 -12.517628)
		(stroke
			(width 0.127)
			(type default)
		)
		(layer "In4.Cu")
	)
	(gr_line
		(start 129.17678 -9.850628)
		(end 129.17678 -12.517628)
		(stroke
			(width 0.127)
			(type default)
		)
		(layer "In4.Cu")
	)
	(gr_line
		(start 129.17678 -8.317738)
		(end 127.90678 -8.317738)
		(stroke
			(width 0.127)
			(type default)
		)
		(layer "In4.Cu")
	)
	(gr_line
		(start 129.17678 -5.650738)
		(end 129.17678 -8.317738)
		(stroke
			(width 0.127)
			(type default)
		)
		(layer "In4.Cu")
	)
	(gr_line
		(start 129.20218 -12.543028)
		(end 129.20218 -9.825228)
		(stroke
			(width 0.1016)
			(type default)
		)
		(layer "In4.Cu")
	)
	(gr_line
		(start 129.20218 -9.825228)
		(end 127.85598 -9.825228)
		(stroke
			(width 0.1016)
			(type default)
		)
		(layer "In4.Cu")
	)
	(gr_line
		(start 129.20218 -8.343138)
		(end 129.20218 -5.625338)
		(stroke
			(width 0.1016)
			(type default)
		)
		(layer "In4.Cu")
	)
	(gr_line
		(start 129.20218 -5.625338)
		(end 127.85598 -5.625338)
		(stroke
			(width 0.1016)
			(type default)
		)
		(layer "In4.Cu")
	)
	(gr_line
		(start 132.9182 -5.22732)
		(end 132.9182 -3.95732)
		(stroke
			(width 1.016)
			(type default)
		)
		(layer "In4.Cu")
	)
	(gr_arc
		(start 132.990082 -52.319936)
		(mid 133.697187 -52.027043)
		(end 133.99008 -51.319938)
		(stroke
			(width 2.032)
			(type default)
		)
		(layer "In4.Cu")
	)
	(gr_line
		(start 133.99008 -51.319938)
		(end 133.99008 -50.8)
		(stroke
			(width 2.032)
			(type default)
		)
		(layer "In4.Cu")
	)
	(gr_arc
		(start 134.990078 -49.800002)
		(mid 134.282987 -50.092902)
		(end 133.99008 -50.8)
		(stroke
			(width 2.032)
			(type default)
		)
		(layer "In4.Cu")
	)
	(gr_line
		(start 134.990078 -49.800002)
		(end 149.990048 -49.800002)
		(stroke
			(width 2.032)
			(type default)
		)
		(layer "In4.Cu")
	)
	(gr_line
		(start 139.4968 -11.3792)
		(end 139.4968 -9.1948)
		(stroke
			(width 0.254)
			(type default)
		)
		(layer "In4.Cu")
	)
	(gr_line
		(start 139.4968 -9.1948)
		(end 141.0716 -9.1948)
		(stroke
			(width 0.254)
			(type default)
		)
		(layer "In4.Cu")
	)
	(gr_line
		(start 139.5222 -11.3792)
		(end 139.5222 -9.2456)
		(stroke
			(width 0.254)
			(type default)
		)
		(layer "In4.Cu")
	)
	(gr_line
		(start 139.5222 -9.2456)
		(end 141.0462 -9.2456)
		(stroke
			(width 0.254)
			(type default)
		)
		(layer "In4.Cu")
	)
	(gr_line
		(start 139.573 -11.3538)
		(end 139.573 -9.3726)
		(stroke
			(width 0.254)
			(type default)
		)
		(layer "In4.Cu")
	)
	(gr_line
		(start 139.573 -9.3726)
		(end 141.0208 -9.3726)
		(stroke
			(width 0.254)
			(type default)
		)
		(layer "In4.Cu")
	)
	(gr_line
		(start 139.627102 -11.303)
		(end 139.931902 -11.303)
		(stroke
			(width 0.1016)
			(type default)
		)
		(layer "In4.Cu")
	)
	(gr_line
		(start 139.627102 -9.2964)
		(end 139.627102 -11.303)
		(stroke
			(width 0.1016)
			(type default)
		)
		(layer "In4.Cu")
	)
	(gr_line
		(start 139.677902 -11.2268)
		(end 140.770102 -11.2268)
		(stroke
			(width 0.2032)
			(type default)
		)
		(layer "In4.Cu")
	)
	(gr_line
		(start 139.677902 -9.3726)
		(end 139.677902 -11.2268)
		(stroke
			(width 0.2032)
			(type default)
		)
		(layer "In4.Cu")
	)
	(gr_line
		(start 139.703302 -11.2268)
		(end 140.871702 -11.2268)
		(stroke
			(width 0.2032)
			(type default)
		)
		(layer "In4.Cu")
	)
	(gr_line
		(start 139.703302 -9.4234)
		(end 139.703302 -11.2268)
		(stroke
			(width 0.2032)
			(type default)
		)
		(layer "In4.Cu")
	)
	(gr_line
		(start 139.7508 -11.1252)
		(end 139.7508 -9.5758)
		(stroke
			(width 0.762)
			(type default)
		)
		(layer "In4.Cu")
	)
	(gr_line
		(start 139.7508 -11.1252)
		(end 140.6652 -11.1252)
		(stroke
			(width 0.762)
			(type default)
		)
		(layer "In4.Cu")
	)
	(gr_line
		(start 139.7508 -11.0998)
		(end 139.7508 -9.5504)
		(stroke
			(width 0.762)
			(type default)
		)
		(layer "In4.Cu")
	)
	(gr_line
		(start 139.7508 -10.9982)
		(end 139.7508 -9.4488)
		(stroke
			(width 0.762)
			(type default)
		)
		(layer "In4.Cu")
	)
	(gr_line
		(start 139.7508 -9.4488)
		(end 140.6652 -9.4488)
		(stroke
			(width 0.762)
			(type default)
		)
		(layer "In4.Cu")
	)
	(gr_line
		(start 139.754102 -11.176)
		(end 140.846302 -11.176)
		(stroke
			(width 0.2032)
			(type default)
		)
		(layer "In4.Cu")
	)
	(gr_line
		(start 139.754102 -9.4742)
		(end 139.754102 -11.176)
		(stroke
			(width 0.2032)
			(type default)
		)
		(layer "In4.Cu")
	)
	(gr_line
		(start 139.7762 -10.9982)
		(end 140.6906 -10.9982)
		(stroke
			(width 0.762)
			(type default)
		)
		(layer "In4.Cu")
	)
	(gr_line
		(start 139.7762 -9.5758)
		(end 140.6906 -9.5758)
		(stroke
			(width 0.762)
			(type default)
		)
		(layer "In4.Cu")
	)
	(gr_line
		(start 139.855702 -11.0744)
		(end 140.643102 -11.0744)
		(stroke
			(width 0.508)
			(type default)
		)
		(layer "In4.Cu")
	)
	(gr_line
		(start 139.855702 -11.049)
		(end 139.855702 -9.525)
		(stroke
			(width 0.508)
			(type default)
		)
		(layer "In4.Cu")
	)
	(gr_line
		(start 139.881102 -11.0744)
		(end 139.881102 -9.5504)
		(stroke
			(width 0.508)
			(type default)
		)
		(layer "In4.Cu")
	)
	(gr_line
		(start 139.9032 -11.1252)
		(end 140.8176 -11.1252)
		(stroke
			(width 0.762)
			(type default)
		)
		(layer "In4.Cu")
	)
	(gr_line
		(start 139.9032 -9.4488)
		(end 140.8176 -9.4488)
		(stroke
			(width 0.762)
			(type default)
		)
		(layer "In4.Cu")
	)
	(gr_line
		(start 139.906502 -9.525)
		(end 140.643102 -9.525)
		(stroke
			(width 0.508)
			(type default)
		)
		(layer "In4.Cu")
	)
	(gr_line
		(start 139.931902 -11.303)
		(end 140.922502 -11.303)
		(stroke
			(width 0.1016)
			(type default)
		)
		(layer "In4.Cu")
	)
	(gr_line
		(start 139.931902 -11.0744)
		(end 139.931902 -9.5504)
		(stroke
			(width 0.508)
			(type default)
		)
		(layer "In4.Cu")
	)
	(gr_line
		(start 139.957302 -11.0744)
		(end 139.957302 -9.5504)
		(stroke
			(width 0.508)
			(type default)
		)
		(layer "In4.Cu")
	)
	(gr_line
		(start 139.982702 -11.0744)
		(end 139.982702 -9.5504)
		(stroke
			(width 0.508)
			(type default)
		)
		(layer "In4.Cu")
	)
	(gr_line
		(start 140.008102 -11.0744)
		(end 140.008102 -9.5504)
		(stroke
			(width 0.508)
			(type default)
		)
		(layer "In4.Cu")
	)
	(gr_line
		(start 140.008102 -11.049)
		(end 140.008102 -9.525)
		(stroke
			(width 0.508)
			(type default)
		)
		(layer "In4.Cu")
	)
	(gr_line
		(start 140.033502 -11.0744)
		(end 140.033502 -9.5504)
		(stroke
			(width 0.508)
			(type default)
		)
		(layer "In4.Cu")
	)
	(gr_line
		(start 140.058902 -11.0744)
		(end 140.058902 -9.5504)
		(stroke
			(width 0.508)
			(type default)
		)
		(layer "In4.Cu")
	)
	(gr_line
		(start 140.109702 -11.0744)
		(end 140.109702 -9.5504)
		(stroke
			(width 0.508)
			(type default)
		)
		(layer "In4.Cu")
	)
	(gr_line
		(start 140.109702 -11.049)
		(end 140.109702 -9.525)
		(stroke
			(width 0.508)
			(type default)
		)
		(layer "In4.Cu")
	)
	(gr_line
		(start 140.135102 -11.0744)
		(end 140.135102 -9.5504)
		(stroke
			(width 0.508)
			(type default)
		)
		(layer "In4.Cu")
	)
	(gr_line
		(start 140.160502 -11.0744)
		(end 140.160502 -9.5504)
		(stroke
			(width 0.508)
			(type default)
		)
		(layer "In4.Cu")
	)
	(gr_line
		(start 140.185902 -11.0744)
		(end 140.185902 -9.5504)
		(stroke
			(width 0.508)
			(type default)
		)
		(layer "In4.Cu")
	)
	(gr_line
		(start 140.236702 -11.0744)
		(end 140.236702 -9.5504)
		(stroke
			(width 0.508)
			(type default)
		)
		(layer "In4.Cu")
	)
	(gr_line
		(start 140.262102 -11.0744)
		(end 140.262102 -9.5504)
		(stroke
			(width 0.508)
			(type default)
		)
		(layer "In4.Cu")
	)
	(gr_line
		(start 140.262102 -11.049)
		(end 140.262102 -9.525)
		(stroke
			(width 0.508)
			(type default)
		)
		(layer "In4.Cu")
	)
	(gr_line
		(start 140.287502 -11.0744)
		(end 140.287502 -9.5504)
		(stroke
			(width 0.508)
			(type default)
		)
		(layer "In4.Cu")
	)
	(gr_line
		(start 140.312902 -11.0744)
		(end 140.312902 -9.5504)
		(stroke
			(width 0.508)
			(type default)
		)
		(layer "In4.Cu")
	)
	(gr_line
		(start 140.338302 -11.0744)
		(end 140.338302 -9.5504)
		(stroke
			(width 0.508)
			(type default)
		)
		(layer "In4.Cu")
	)
	(gr_line
		(start 140.338302 -11.049)
		(end 140.338302 -9.525)
		(stroke
			(width 0.508)
			(type default)
		)
		(layer "In4.Cu")
	)
	(gr_line
		(start 140.363702 -11.0744)
		(end 140.363702 -9.5504)
		(stroke
			(width 0.508)
			(type default)
		)
		(layer "In4.Cu")
	)
	(gr_line
		(start 140.389102 -11.0744)
		(end 140.389102 -9.5504)
		(stroke
			(width 0.508)
			(type default)
		)
		(layer "In4.Cu")
	)
	(gr_line
		(start 140.389102 -11.049)
		(end 140.389102 -9.525)
		(stroke
			(width 0.508)
			(type default)
		)
		(layer "In4.Cu")
	)
	(gr_line
		(start 140.414502 -11.0744)
		(end 140.414502 -9.5504)
		(stroke
			(width 0.508)
			(type default)
		)
		(layer "In4.Cu")
	)
	(gr_line
		(start 140.414502 -11.049)
		(end 140.414502 -9.525)
		(stroke
			(width 0.508)
			(type default)
		)
		(layer "In4.Cu")
	)
	(gr_line
		(start 140.439902 -11.049)
		(end 140.439902 -9.525)
		(stroke
			(width 0.508)
			(type default)
		)
		(layer "In4.Cu")
	)
	(gr_line
		(start 140.465302 -11.0744)
		(end 140.465302 -9.5504)
		(stroke
			(width 0.508)
			(type default)
		)
		(layer "In4.Cu")
	)
	(gr_line
		(start 140.4874 -11.3792)
		(end 139.4968 -11.3792)
		(stroke
			(width 0.254)
			(type default)
		)
		(layer "In4.Cu")
	)
	(gr_line
		(start 140.490702 -11.049)
		(end 140.490702 -9.525)
		(stroke
			(width 0.508)
			(type default)
		)
		(layer "In4.Cu")
	)
	(gr_line
		(start 140.516102 -11.049)
		(end 140.516102 -9.525)
		(stroke
			(width 0.508)
			(type default)
		)
		(layer "In4.Cu")
	)
	(gr_line
		(start 140.541502 -11.0744)
		(end 140.541502 -9.5504)
		(stroke
			(width 0.508)
			(type default)
		)
		(layer "In4.Cu")
	)
	(gr_line
		(start 140.566902 -11.0744)
		(end 140.566902 -9.5504)
		(stroke
			(width 0.508)
			(type default)
		)
		(layer "In4.Cu")
	)
	(gr_line
		(start 140.566902 -11.049)
		(end 140.566902 -9.525)
		(stroke
			(width 0.508)
			(type default)
		)
		(layer "In4.Cu")
	)
	(gr_line
		(start 140.617702 -11.0744)
		(end 140.617702 -9.5504)
		(stroke
			(width 0.508)
			(type default)
		)
		(layer "In4.Cu")
	)
	(gr_line
		(start 140.617702 -11.049)
		(end 140.617702 -9.525)
		(stroke
			(width 0.508)
			(type default)
		)
		(layer "In4.Cu")
	)
	(gr_line
		(start 140.668502 -11.0744)
		(end 140.668502 -9.5504)
		(stroke
			(width 0.508)
			(type default)
		)
		(layer "In4.Cu")
	)
	(gr_line
		(start 140.668502 -11.049)
		(end 140.668502 -9.525)
		(stroke
			(width 0.508)
			(type default)
		)
		(layer "In4.Cu")
	)
	(gr_line
		(start 140.6906 -11.0998)
		(end 140.6906 -9.5504)
		(stroke
			(width 0.762)
			(type default)
		)
		(layer "In4.Cu")
	)
	(gr_line
		(start 140.693902 -11.0744)
		(end 140.693902 -9.5504)
		(stroke
			(width 0.508)
			(type default)
		)
		(layer "In4.Cu")
	)
	(gr_line
		(start 140.719302 -11.0744)
		(end 140.719302 -9.5504)
		(stroke
			(width 0.508)
			(type default)
		)
		(layer "In4.Cu")
	)
	(gr_line
		(start 140.770102 -11.2268)
		(end 140.795502 -11.2268)
		(stroke
			(width 0.2032)
			(type default)
		)
		(layer "In4.Cu")
	)
	(gr_line
		(start 140.795502 -11.2268)
		(end 140.795502 -9.4742)
		(stroke
			(width 0.2032)
			(type default)
		)
		(layer "In4.Cu")
	)
	(gr_line
		(start 140.795502 -9.4742)
		(end 139.754102 -9.4742)
		(stroke
			(width 0.2032)
			(type default)
		)
		(layer "In4.Cu")
	)
	(gr_line
		(start 140.8176 -11.1252)
		(end 140.8176 -9.5758)
		(stroke
			(width 0.762)
			(type default)
		)
		(layer "In4.Cu")
	)
	(gr_line
		(start 140.8176 -11.0998)
		(end 140.8176 -9.6012)
		(stroke
			(width 0.762)
			(type default)
		)
		(layer "In4.Cu")
	)
	(gr_line
		(start 140.8176 -10.9982)
		(end 140.8176 -9.4488)
		(stroke
			(width 0.762)
			(type default)
		)
		(layer "In4.Cu")
	)
	(gr_line
		(start 140.846302 -11.176)
		(end 140.846302 -9.4234)
		(stroke
			(width 0.2032)
			(type default)
		)
		(layer "In4.Cu")
	)
	(gr_line
		(start 140.846302 -9.4234)
		(end 139.703302 -9.4234)
		(stroke
			(width 0.2032)
			(type default)
		)
		(layer "In4.Cu")
	)
	(gr_line
		(start 140.871702 -11.2268)
		(end 140.871702 -9.3726)
		(stroke
			(width 0.2032)
			(type default)
		)
		(layer "In4.Cu")
	)
	(gr_line
		(start 140.871702 -9.3726)
		(end 139.677902 -9.3726)
		(stroke
			(width 0.2032)
			(type default)
		)
		(layer "In4.Cu")
	)
	(gr_line
		(start 140.922502 -11.303)
		(end 140.922502 -9.2964)
		(stroke
			(width 0.1016)
			(type default)
		)
		(layer "In4.Cu")
	)
	(gr_line
		(start 140.922502 -9.2964)
		(end 139.627102 -9.2964)
		(stroke
			(width 0.1016)
			(type default)
		)
		(layer "In4.Cu")
	)
	(gr_line
		(start 141.0208 -11.2268)
		(end 140.770102 -11.2268)
		(stroke
			(width 0.254)
			(type default)
		)
		(layer "In4.Cu")
	)
	(gr_line
		(start 141.0208 -9.3726)
		(end 141.0208 -11.2268)
		(stroke
			(width 0.254)
			(type default)
		)
		(layer "In4.Cu")
	)
	(gr_line
		(start 141.0462 -11.3538)
		(end 139.573 -11.3538)
		(stroke
			(width 0.254)
			(type default)
		)
		(layer "In4.Cu")
	)
	(gr_line
		(start 141.0462 -9.2456)
		(end 141.0462 -11.3538)
		(stroke
			(width 0.254)
			(type default)
		)
		(layer "In4.Cu")
	)
	(gr_line
		(start 141.0716 -11.3792)
		(end 139.5222 -11.3792)
		(stroke
			(width 0.254)
			(type default)
		)
		(layer "In4.Cu")
	)
	(gr_line
		(start 141.0716 -9.1948)
		(end 141.0716 -11.3792)
		(stroke
			(width 0.254)
			(type default)
		)
		(layer "In4.Cu")
	)
	(gr_line
		(start 144.296892 -11.3792)
		(end 144.296892 -9.1948)
		(stroke
			(width 0.254)
			(type default)
		)
		(layer "In4.Cu")
	)
	(gr_line
		(start 144.296892 -9.1948)
		(end 145.871692 -9.1948)
		(stroke
			(width 0.254)
			(type default)
		)
		(layer "In4.Cu")
	)
	(gr_line
		(start 144.322292 -11.3792)
		(end 144.322292 -9.2456)
		(stroke
			(width 0.254)
			(type default)
		)
		(layer "In4.Cu")
	)
	(gr_line
		(start 144.322292 -9.2456)
		(end 145.846292 -9.2456)
		(stroke
			(width 0.254)
			(type default)
		)
		(layer "In4.Cu")
	)
	(gr_line
		(start 144.373092 -11.3538)
		(end 144.373092 -9.3726)
		(stroke
			(width 0.254)
			(type default)
		)
		(layer "In4.Cu")
	)
	(gr_line
		(start 144.373092 -9.3726)
		(end 145.820892 -9.3726)
		(stroke
			(width 0.254)
			(type default)
		)
		(layer "In4.Cu")
	)
	(gr_line
		(start 144.427194 -11.303)
		(end 144.731994 -11.303)
		(stroke
			(width 0.1016)
			(type default)
		)
		(layer "In4.Cu")
	)
	(gr_line
		(start 144.427194 -9.2964)
		(end 144.427194 -11.303)
		(stroke
			(width 0.1016)
			(type default)
		)
		(layer "In4.Cu")
	)
	(gr_line
		(start 144.477994 -11.2268)
		(end 145.570194 -11.2268)
		(stroke
			(width 0.2032)
			(type default)
		)
		(layer "In4.Cu")
	)
	(gr_line
		(start 144.477994 -9.3726)
		(end 144.477994 -11.2268)
		(stroke
			(width 0.2032)
			(type default)
		)
		(layer "In4.Cu")
	)
	(gr_line
		(start 144.503394 -11.2268)
		(end 145.671794 -11.2268)
		(stroke
			(width 0.2032)
			(type default)
		)
		(layer "In4.Cu")
	)
	(gr_line
		(start 144.503394 -9.4234)
		(end 144.503394 -11.2268)
		(stroke
			(width 0.2032)
			(type default)
		)
		(layer "In4.Cu")
	)
	(gr_line
		(start 144.550892 -11.1252)
		(end 144.550892 -9.5758)
		(stroke
			(width 0.762)
			(type default)
		)
		(layer "In4.Cu")
	)
	(gr_line
		(start 144.550892 -11.1252)
		(end 145.465292 -11.1252)
		(stroke
			(width 0.762)
			(type default)
		)
		(layer "In4.Cu")
	)
	(gr_line
		(start 144.550892 -11.0998)
		(end 144.550892 -9.5504)
		(stroke
			(width 0.762)
			(type default)
		)
		(layer "In4.Cu")
	)
	(gr_line
		(start 144.550892 -10.9982)
		(end 144.550892 -9.4488)
		(stroke
			(width 0.762)
			(type default)
		)
		(layer "In4.Cu")
	)
	(gr_line
		(start 144.550892 -9.4488)
		(end 145.465292 -9.4488)
		(stroke
			(width 0.762)
			(type default)
		)
		(layer "In4.Cu")
	)
	(gr_line
		(start 144.554194 -11.176)
		(end 145.646394 -11.176)
		(stroke
			(width 0.2032)
			(type default)
		)
		(layer "In4.Cu")
	)
	(gr_line
		(start 144.554194 -9.4742)
		(end 144.554194 -11.176)
		(stroke
			(width 0.2032)
			(type default)
		)
		(layer "In4.Cu")
	)
	(gr_line
		(start 144.576292 -10.9982)
		(end 145.490692 -10.9982)
		(stroke
			(width 0.762)
			(type default)
		)
		(layer "In4.Cu")
	)
	(gr_line
		(start 144.576292 -9.5758)
		(end 145.490692 -9.5758)
		(stroke
			(width 0.762)
			(type default)
		)
		(layer "In4.Cu")
	)
	(gr_line
		(start 144.655794 -11.0744)
		(end 145.443194 -11.0744)
		(stroke
			(width 0.508)
			(type default)
		)
		(layer "In4.Cu")
	)
	(gr_line
		(start 144.655794 -11.049)
		(end 144.655794 -9.525)
		(stroke
			(width 0.508)
			(type default)
		)
		(layer "In4.Cu")
	)
	(gr_line
		(start 144.681194 -11.0744)
		(end 144.681194 -9.5504)
		(stroke
			(width 0.508)
			(type default)
		)
		(layer "In4.Cu")
	)
	(gr_line
		(start 144.703292 -11.1252)
		(end 145.617692 -11.1252)
		(stroke
			(width 0.762)
			(type default)
		)
		(layer "In4.Cu")
	)
	(gr_line
		(start 144.703292 -9.4488)
		(end 145.617692 -9.4488)
		(stroke
			(width 0.762)
			(type default)
		)
		(layer "In4.Cu")
	)
	(gr_line
		(start 144.706594 -9.525)
		(end 145.443194 -9.525)
		(stroke
			(width 0.508)
			(type default)
		)
		(layer "In4.Cu")
	)
	(gr_line
		(start 144.731994 -11.303)
		(end 145.722594 -11.303)
		(stroke
			(width 0.1016)
			(type default)
		)
		(layer "In4.Cu")
	)
	(gr_line
		(start 144.731994 -11.0744)
		(end 144.731994 -9.5504)
		(stroke
			(width 0.508)
			(type default)
		)
		(layer "In4.Cu")
	)
	(gr_line
		(start 144.757394 -11.0744)
		(end 144.757394 -9.5504)
		(stroke
			(width 0.508)
			(type default)
		)
		(layer "In4.Cu")
	)
	(gr_line
		(start 144.782794 -11.0744)
		(end 144.782794 -9.5504)
		(stroke
			(width 0.508)
			(type default)
		)
		(layer "In4.Cu")
	)
	(gr_line
		(start 144.808194 -11.0744)
		(end 144.808194 -9.5504)
		(stroke
			(width 0.508)
			(type default)
		)
		(layer "In4.Cu")
	)
	(gr_line
		(start 144.808194 -11.049)
		(end 144.808194 -9.525)
		(stroke
			(width 0.508)
			(type default)
		)
		(layer "In4.Cu")
	)
	(gr_line
		(start 144.833594 -11.0744)
		(end 144.833594 -9.5504)
		(stroke
			(width 0.508)
			(type default)
		)
		(layer "In4.Cu")
	)
	(gr_line
		(start 144.858994 -11.0744)
		(end 144.858994 -9.5504)
		(stroke
			(width 0.508)
			(type default)
		)
		(layer "In4.Cu")
	)
	(gr_line
		(start 144.909794 -11.0744)
		(end 144.909794 -9.5504)
		(stroke
			(width 0.508)
			(type default)
		)
		(layer "In4.Cu")
	)
	(gr_line
		(start 144.909794 -11.049)
		(end 144.909794 -9.525)
		(stroke
			(width 0.508)
			(type default)
		)
		(layer "In4.Cu")
	)
	(gr_line
		(start 144.935194 -11.0744)
		(end 144.935194 -9.5504)
		(stroke
			(width 0.508)
			(type default)
		)
		(layer "In4.Cu")
	)
	(gr_line
		(start 144.960594 -11.0744)
		(end 144.960594 -9.5504)
		(stroke
			(width 0.508)
			(type default)
		)
		(layer "In4.Cu")
	)
	(gr_line
		(start 144.985994 -11.0744)
		(end 144.985994 -9.5504)
		(stroke
			(width 0.508)
			(type default)
		)
		(layer "In4.Cu")
	)
	(gr_line
		(start 145.036794 -11.0744)
		(end 145.036794 -9.5504)
		(stroke
			(width 0.508)
			(type default)
		)
		(layer "In4.Cu")
	)
	(gr_line
		(start 145.062194 -11.0744)
		(end 145.062194 -9.5504)
		(stroke
			(width 0.508)
			(type default)
		)
		(layer "In4.Cu")
	)
	(gr_line
		(start 145.062194 -11.049)
		(end 145.062194 -9.525)
		(stroke
			(width 0.508)
			(type default)
		)
		(layer "In4.Cu")
	)
	(gr_line
		(start 145.087594 -11.0744)
		(end 145.087594 -9.5504)
		(stroke
			(width 0.508)
			(type default)
		)
		(layer "In4.Cu")
	)
	(gr_line
		(start 145.112994 -11.0744)
		(end 145.112994 -9.5504)
		(stroke
			(width 0.508)
			(type default)
		)
		(layer "In4.Cu")
	)
	(gr_line
		(start 145.138394 -11.0744)
		(end 145.138394 -9.5504)
		(stroke
			(width 0.508)
			(type default)
		)
		(layer "In4.Cu")
	)
	(gr_line
		(start 145.138394 -11.049)
		(end 145.138394 -9.525)
		(stroke
			(width 0.508)
			(type default)
		)
		(layer "In4.Cu")
	)
	(gr_line
		(start 145.163794 -11.0744)
		(end 145.163794 -9.5504)
		(stroke
			(width 0.508)
			(type default)
		)
		(layer "In4.Cu")
	)
	(gr_line
		(start 145.189194 -11.0744)
		(end 145.189194 -9.5504)
		(stroke
			(width 0.508)
			(type default)
		)
		(layer "In4.Cu")
	)
	(gr_line
		(start 145.189194 -11.049)
		(end 145.189194 -9.525)
		(stroke
			(width 0.508)
			(type default)
		)
		(layer "In4.Cu")
	)
	(gr_line
		(start 145.214594 -11.0744)
		(end 145.214594 -9.5504)
		(stroke
			(width 0.508)
			(type default)
		)
		(layer "In4.Cu")
	)
	(gr_line
		(start 145.214594 -11.049)
		(end 145.214594 -9.525)
		(stroke
			(width 0.508)
			(type default)
		)
		(layer "In4.Cu")
	)
	(gr_line
		(start 145.239994 -11.049)
		(end 145.239994 -9.525)
		(stroke
			(width 0.508)
			(type default)
		)
		(layer "In4.Cu")
	)
	(gr_line
		(start 145.265394 -11.0744)
		(end 145.265394 -9.5504)
		(stroke
			(width 0.508)
			(type default)
		)
		(layer "In4.Cu")
	)
	(gr_line
		(start 145.287492 -11.3792)
		(end 144.296892 -11.3792)
		(stroke
			(width 0.254)
			(type default)
		)
		(layer "In4.Cu")
	)
	(gr_line
		(start 145.290794 -11.049)
		(end 145.290794 -9.525)
		(stroke
			(width 0.508)
			(type default)
		)
		(layer "In4.Cu")
	)
	(gr_line
		(start 145.316194 -11.049)
		(end 145.316194 -9.525)
		(stroke
			(width 0.508)
			(type default)
		)
		(layer "In4.Cu")
	)
	(gr_line
		(start 145.341594 -11.0744)
		(end 145.341594 -9.5504)
		(stroke
			(width 0.508)
			(type default)
		)
		(layer "In4.Cu")
	)
	(gr_line
		(start 145.366994 -11.0744)
		(end 145.366994 -9.5504)
		(stroke
			(width 0.508)
			(type default)
		)
		(layer "In4.Cu")
	)
	(gr_line
		(start 145.366994 -11.049)
		(end 145.366994 -9.525)
		(stroke
			(width 0.508)
			(type default)
		)
		(layer "In4.Cu")
	)
	(gr_line
		(start 145.417794 -11.0744)
		(end 145.417794 -9.5504)
		(stroke
			(width 0.508)
			(type default)
		)
		(layer "In4.Cu")
	)
	(gr_line
		(start 145.417794 -11.049)
		(end 145.417794 -9.525)
		(stroke
			(width 0.508)
			(type default)
		)
		(layer "In4.Cu")
	)
	(gr_line
		(start 145.468594 -11.0744)
		(end 145.468594 -9.5504)
		(stroke
			(width 0.508)
			(type default)
		)
		(layer "In4.Cu")
	)
	(gr_line
		(start 145.468594 -11.049)
		(end 145.468594 -9.525)
		(stroke
			(width 0.508)
			(type default)
		)
		(layer "In4.Cu")
	)
	(gr_line
		(start 145.490692 -11.0998)
		(end 145.490692 -9.5504)
		(stroke
			(width 0.762)
			(type default)
		)
		(layer "In4.Cu")
	)
	(gr_line
		(start 145.493994 -11.0744)
		(end 145.493994 -9.5504)
		(stroke
			(width 0.508)
			(type default)
		)
		(layer "In4.Cu")
	)
	(gr_line
		(start 145.519394 -11.0744)
		(end 145.519394 -9.5504)
		(stroke
			(width 0.508)
			(type default)
		)
		(layer "In4.Cu")
	)
	(gr_line
		(start 145.570194 -11.2268)
		(end 145.595594 -11.2268)
		(stroke
			(width 0.2032)
			(type default)
		)
		(layer "In4.Cu")
	)
	(gr_line
		(start 145.595594 -11.2268)
		(end 145.595594 -9.4742)
		(stroke
			(width 0.2032)
			(type default)
		)
		(layer "In4.Cu")
	)
	(gr_line
		(start 145.595594 -9.4742)
		(end 144.554194 -9.4742)
		(stroke
			(width 0.2032)
			(type default)
		)
		(layer "In4.Cu")
	)
	(gr_line
		(start 145.617692 -11.1252)
		(end 145.617692 -9.5758)
		(stroke
			(width 0.762)
			(type default)
		)
		(layer "In4.Cu")
	)
	(gr_line
		(start 145.617692 -11.0998)
		(end 145.617692 -9.6012)
		(stroke
			(width 0.762)
			(type default)
		)
		(layer "In4.Cu")
	)
	(gr_line
		(start 145.617692 -10.9982)
		(end 145.617692 -9.4488)
		(stroke
			(width 0.762)
			(type default)
		)
		(layer "In4.Cu")
	)
	(gr_line
		(start 145.646394 -11.176)
		(end 145.646394 -9.4234)
		(stroke
			(width 0.2032)
			(type default)
		)
		(layer "In4.Cu")
	)
	(gr_line
		(start 145.646394 -9.4234)
		(end 144.503394 -9.4234)
		(stroke
			(width 0.2032)
			(type default)
		)
		(layer "In4.Cu")
	)
	(gr_line
		(start 145.671794 -11.2268)
		(end 145.671794 -9.3726)
		(stroke
			(width 0.2032)
			(type default)
		)
		(layer "In4.Cu")
	)
	(gr_line
		(start 145.671794 -9.3726)
		(end 144.477994 -9.3726)
		(stroke
			(width 0.2032)
			(type default)
		)
		(layer "In4.Cu")
	)
	(gr_line
		(start 145.722594 -11.303)
		(end 145.722594 -9.2964)
		(stroke
			(width 0.1016)
			(type default)
		)
		(layer "In4.Cu")
	)
	(gr_line
		(start 145.722594 -9.2964)
		(end 144.427194 -9.2964)
		(stroke
			(width 0.1016)
			(type default)
		)
		(layer "In4.Cu")
	)
	(gr_line
		(start 145.725134 -5.715)
		(end 144.455134 -5.715)
		(stroke
			(width 1.016)
			(type default)
		)
		(layer "In4.Cu")
	)
	(gr_line
		(start 145.820892 -11.2268)
		(end 145.570194 -11.2268)
		(stroke
			(width 0.254)
			(type default)
		)
		(layer "In4.Cu")
	)
	(gr_line
		(start 145.820892 -9.3726)
		(end 145.820892 -11.2268)
		(stroke
			(width 0.254)
			(type default)
		)
		(layer "In4.Cu")
	)
	(gr_line
		(start 145.846292 -11.3538)
		(end 144.373092 -11.3538)
		(stroke
			(width 0.254)
			(type default)
		)
		(layer "In4.Cu")
	)
	(gr_line
		(start 145.846292 -9.2456)
		(end 145.846292 -11.3538)
		(stroke
			(width 0.254)
			(type default)
		)
		(layer "In4.Cu")
	)
	(gr_line
		(start 145.871692 -11.3792)
		(end 144.322292 -11.3792)
		(stroke
			(width 0.254)
			(type default)
		)
		(layer "In4.Cu")
	)
	(gr_line
		(start 145.871692 -9.1948)
		(end 145.871692 -11.3792)
		(stroke
			(width 0.254)
			(type default)
		)
		(layer "In4.Cu")
	)
	(gr_arc
		(start 150.990046 -51.319938)
		(mid 151.282939 -52.027043)
		(end 151.990044 -52.319936)
		(stroke
			(width 2.032)
			(type default)
		)
		(layer "In4.Cu")
	)
	(gr_arc
		(start 150.990046 -50.8)
		(mid 150.697156 -50.092878)
		(end 149.990048 -49.800002)
		(stroke
			(width 2.032)
			(type default)
		)
		(layer "In4.Cu")
	)
	(gr_line
		(start 150.990046 -50.8)
		(end 150.990046 -51.319938)
		(stroke
			(width 2.032)
			(type default)
		)
		(layer "In4.Cu")
	)
	(gr_line
		(start 151.990044 -52.319936)
		(end 158.99003 -52.319936)
		(stroke
			(width 2.032)
			(type default)
		)
		(layer "In4.Cu")
	)
	(gr_line
		(start 158.99003 -52.319936)
		(end 159.372554 -52.24399)
		(stroke
			(width 2.032)
			(type default)
		)
		(layer "In4.Cu")
	)
	(gr_line
		(start 159.372554 -52.24399)
		(end 159.697166 -52.027074)
		(stroke
			(width 2.032)
			(type default)
		)
		(layer "In4.Cu")
	)
	(gr_line
		(start 159.697166 -52.027074)
		(end 159.913828 -51.702716)
		(stroke
			(width 2.032)
			(type default)
		)
		(layer "In4.Cu")
	)
	(gr_line
		(start 159.913828 -51.702716)
		(end 159.982154 -51.376072)
		(stroke
			(width 2.032)
			(type default)
		)
		(layer "In4.Cu")
	)
	(gr_line
		(start 159.982154 -51.376072)
		(end 160.0708 -50.996088)
		(stroke
			(width 2.032)
			(type default)
		)
		(layer "In4.Cu")
	)
	(gr_line
		(start 160.0708 -50.996088)
		(end 160.288732 -50.677064)
		(stroke
			(width 2.032)
			(type default)
		)
		(layer "In4.Cu")
	)
	(gr_line
		(start 160.288732 -50.677064)
		(end 160.611058 -50.464466)
		(stroke
			(width 2.032)
			(type default)
		)
		(layer "In4.Cu")
	)
	(gr_line
		(start 160.611058 -50.464466)
		(end 160.990026 -50.390044)
		(stroke
			(width 2.032)
			(type default)
		)
		(layer "In4.Cu")
	)
	(gr_line
		(start 160.990026 -50.390044)
		(end 202.989942 -50.390044)
		(stroke
			(width 2.032)
			(type default)
		)
		(layer "In4.Cu")
	)
	(gr_line
		(start 164.2872 -13.8176)
		(end 165.0746 -13.8176)
		(stroke
			(width 0.1016)
			(type default)
		)
		(layer "In4.Cu")
	)
	(gr_line
		(start 164.2872 -13.7668)
		(end 164.2872 -11.1506)
		(stroke
			(width 0.1016)
			(type default)
		)
		(layer "In4.Cu")
	)
	(gr_line
		(start 164.2872 -11.1506)
		(end 164.2872 -13.8176)
		(stroke
			(width 0.1016)
			(type default)
		)
		(layer "In4.Cu")
	)
	(gr_line
		(start 164.2872 -11.1506)
		(end 165.481 -11.1506)
		(stroke
			(width 0.1016)
			(type default)
		)
		(layer "In4.Cu")
	)
	(gr_line
		(start 164.2872 -9.617456)
		(end 165.0746 -9.617456)
		(stroke
			(width 0.1016)
			(type default)
		)
		(layer "In4.Cu")
	)
	(gr_line
		(start 164.2872 -9.566656)
		(end 164.2872 -6.950456)
		(stroke
			(width 0.1016)
			(type default)
		)
		(layer "In4.Cu")
	)
	(gr_line
		(start 164.2872 -6.950456)
		(end 164.2872 -9.617456)
		(stroke
			(width 0.1016)
			(type default)
		)
		(layer "In4.Cu")
	)
	(gr_line
		(start 164.2872 -6.950456)
		(end 165.481 -6.950456)
		(stroke
			(width 0.1016)
			(type default)
		)
		(layer "In4.Cu")
	)
	(gr_line
		(start 164.2872 -5.417312)
		(end 165.0746 -5.417312)
		(stroke
			(width 0.1016)
			(type default)
		)
		(layer "In4.Cu")
	)
	(gr_line
		(start 164.2872 -5.366512)
		(end 164.2872 -2.750312)
		(stroke
			(width 0.1016)
			(type default)
		)
		(layer "In4.Cu")
	)
	(gr_line
		(start 164.2872 -2.750312)
		(end 164.2872 -5.417312)
		(stroke
			(width 0.1016)
			(type default)
		)
		(layer "In4.Cu")
	)
	(gr_line
		(start 164.2872 -2.750312)
		(end 165.481 -2.750312)
		(stroke
			(width 0.1016)
			(type default)
		)
		(layer "In4.Cu")
	)
	(gr_line
		(start 164.3126 -13.7668)
		(end 164.3126 -11.176)
		(stroke
			(width 0.1016)
			(type default)
		)
		(layer "In4.Cu")
	)
	(gr_line
		(start 164.3126 -11.176)
		(end 165.4556 -11.176)
		(stroke
			(width 0.1016)
			(type default)
		)
		(layer "In4.Cu")
	)
	(gr_line
		(start 164.3126 -9.566656)
		(end 164.3126 -6.975856)
		(stroke
			(width 0.1016)
			(type default)
		)
		(layer "In4.Cu")
	)
	(gr_line
		(start 164.3126 -6.975856)
		(end 165.4556 -6.975856)
		(stroke
			(width 0.1016)
			(type default)
		)
		(layer "In4.Cu")
	)
	(gr_line
		(start 164.3126 -5.366512)
		(end 164.3126 -2.775712)
		(stroke
			(width 0.1016)
			(type default)
		)
		(layer "In4.Cu")
	)
	(gr_line
		(start 164.3126 -2.775712)
		(end 165.4556 -2.775712)
		(stroke
			(width 0.1016)
			(type default)
		)
		(layer "In4.Cu")
	)
	(gr_line
		(start 164.338 -13.7668)
		(end 164.338 -11.2014)
		(stroke
			(width 0.1016)
			(type default)
		)
		(layer "In4.Cu")
	)
	(gr_line
		(start 164.338 -11.2014)
		(end 164.592 -11.2014)
		(stroke
			(width 0.1016)
			(type default)
		)
		(layer "In4.Cu")
	)
	(gr_line
		(start 164.338 -9.566656)
		(end 164.338 -7.001256)
		(stroke
			(width 0.1016)
			(type default)
		)
		(layer "In4.Cu")
	)
	(gr_line
		(start 164.338 -7.001256)
		(end 164.592 -7.001256)
		(stroke
			(width 0.1016)
			(type default)
		)
		(layer "In4.Cu")
	)
	(gr_line
		(start 164.338 -5.366512)
		(end 164.338 -2.801112)
		(stroke
			(width 0.1016)
			(type default)
		)
		(layer "In4.Cu")
	)
	(gr_line
		(start 164.338 -2.801112)
		(end 164.592 -2.801112)
		(stroke
			(width 0.1016)
			(type default)
		)
		(layer "In4.Cu")
	)
	(gr_line
		(start 164.3634 -13.7668)
		(end 164.3634 -11.2014)
		(stroke
			(width 0.2032)
			(type default)
		)
		(layer "In4.Cu")
	)
	(gr_line
		(start 164.3634 -11.2014)
		(end 165.3794 -11.2014)
		(stroke
			(width 0.2032)
			(type default)
		)
		(layer "In4.Cu")
	)
	(gr_line
		(start 164.3634 -9.566656)
		(end 164.3634 -7.001256)
		(stroke
			(width 0.2032)
			(type default)
		)
		(layer "In4.Cu")
	)
	(gr_line
		(start 164.3634 -7.001256)
		(end 165.3794 -7.001256)
		(stroke
			(width 0.2032)
			(type default)
		)
		(layer "In4.Cu")
	)
	(gr_line
		(start 164.3634 -5.366512)
		(end 164.3634 -2.801112)
		(stroke
			(width 0.2032)
			(type default)
		)
		(layer "In4.Cu")
	)
	(gr_line
		(start 164.3634 -2.801112)
		(end 165.3794 -2.801112)
		(stroke
			(width 0.2032)
			(type default)
		)
		(layer "In4.Cu")
	)
	(gr_line
		(start 164.4142 -13.7414)
		(end 164.4142 -11.2522)
		(stroke
			(width 0.2032)
			(type default)
		)
		(layer "In4.Cu")
	)
	(gr_line
		(start 164.4142 -13.7414)
		(end 164.4142 -11.2522)
		(stroke
			(width 0.254)
			(type default)
		)
		(layer "In4.Cu")
	)
	(gr_line
		(start 164.4142 -11.2522)
		(end 164.6174 -11.2522)
		(stroke
			(width 0.2032)
			(type default)
		)
		(layer "In4.Cu")
	)
	(gr_line
		(start 164.4142 -11.2522)
		(end 165.3032 -11.2522)
		(stroke
			(width 0.254)
			(type default)
		)
		(layer "In4.Cu")
	)
	(gr_line
		(start 164.4142 -9.541256)
		(end 164.4142 -7.052056)
		(stroke
			(width 0.2032)
			(type default)
		)
		(layer "In4.Cu")
	)
	(gr_line
		(start 164.4142 -9.541256)
		(end 164.4142 -7.052056)
		(stroke
			(width 0.254)
			(type default)
		)
		(layer "In4.Cu")
	)
	(gr_line
		(start 164.4142 -7.052056)
		(end 164.6174 -7.052056)
		(stroke
			(width 0.2032)
			(type default)
		)
		(layer "In4.Cu")
	)
	(gr_line
		(start 164.4142 -7.052056)
		(end 165.3032 -7.052056)
		(stroke
			(width 0.254)
			(type default)
		)
		(layer "In4.Cu")
	)
	(gr_line
		(start 164.4142 -5.341112)
		(end 164.4142 -2.851912)
		(stroke
			(width 0.2032)
			(type default)
		)
		(layer "In4.Cu")
	)
	(gr_line
		(start 164.4142 -5.341112)
		(end 164.4142 -2.851912)
		(stroke
			(width 0.254)
			(type default)
		)
		(layer "In4.Cu")
	)
	(gr_line
		(start 164.4142 -2.851912)
		(end 164.6174 -2.851912)
		(stroke
			(width 0.2032)
			(type default)
		)
		(layer "In4.Cu")
	)
	(gr_line
		(start 164.4142 -2.851912)
		(end 165.3032 -2.851912)
		(stroke
			(width 0.254)
			(type default)
		)
		(layer "In4.Cu")
	)
	(gr_line
		(start 164.4396 -13.716)
		(end 164.4396 -11.2776)
		(stroke
			(width 0.254)
			(type default)
		)
		(layer "In4.Cu")
	)
	(gr_line
		(start 164.4396 -11.2776)
		(end 165.2778 -11.2776)
		(stroke
			(width 0.254)
			(type default)
		)
		(layer "In4.Cu")
	)
	(gr_line
		(start 164.4396 -9.515856)
		(end 164.4396 -7.077456)
		(stroke
			(width 0.254)
			(type default)
		)
		(layer "In4.Cu")
	)
	(gr_line
		(start 164.4396 -7.077456)
		(end 165.2778 -7.077456)
		(stroke
			(width 0.254)
			(type default)
		)
		(layer "In4.Cu")
	)
	(gr_line
		(start 164.4396 -5.315712)
		(end 164.4396 -2.877312)
		(stroke
			(width 0.254)
			(type default)
		)
		(layer "In4.Cu")
	)
	(gr_line
		(start 164.4396 -2.877312)
		(end 165.2778 -2.877312)
		(stroke
			(width 0.254)
			(type default)
		)
		(layer "In4.Cu")
	)
	(gr_line
		(start 164.465 -13.6906)
		(end 164.465 -11.303)
		(stroke
			(width 0.254)
			(type default)
		)
		(layer "In4.Cu")
	)
	(gr_line
		(start 164.465 -11.303)
		(end 165.2524 -11.303)
		(stroke
			(width 0.254)
			(type default)
		)
		(layer "In4.Cu")
	)
	(gr_line
		(start 164.465 -9.490456)
		(end 164.465 -7.102856)
		(stroke
			(width 0.254)
			(type default)
		)
		(layer "In4.Cu")
	)
	(gr_line
		(start 164.465 -7.102856)
		(end 165.2524 -7.102856)
		(stroke
			(width 0.254)
			(type default)
		)
		(layer "In4.Cu")
	)
	(gr_line
		(start 164.465 -5.290312)
		(end 164.465 -2.902712)
		(stroke
			(width 0.254)
			(type default)
		)
		(layer "In4.Cu")
	)
	(gr_line
		(start 164.465 -2.902712)
		(end 165.2524 -2.902712)
		(stroke
			(width 0.254)
			(type default)
		)
		(layer "In4.Cu")
	)
	(gr_line
		(start 164.4904 -13.6144)
		(end 165.1254 -13.6144)
		(stroke
			(width 0.508)
			(type default)
		)
		(layer "In4.Cu")
	)
	(gr_line
		(start 164.4904 -11.43)
		(end 165.1254 -11.43)
		(stroke
			(width 0.508)
			(type default)
		)
		(layer "In4.Cu")
	)
	(gr_line
		(start 164.4904 -11.3792)
		(end 165.1254 -11.3792)
		(stroke
			(width 0.508)
			(type default)
		)
		(layer "In4.Cu")
	)
	(gr_line
		(start 164.4904 -9.414256)
		(end 165.1254 -9.414256)
		(stroke
			(width 0.508)
			(type default)
		)
		(layer "In4.Cu")
	)
	(gr_line
		(start 164.4904 -7.229856)
		(end 165.1254 -7.229856)
		(stroke
			(width 0.508)
			(type default)
		)
		(layer "In4.Cu")
	)
	(gr_line
		(start 164.4904 -7.179056)
		(end 165.1254 -7.179056)
		(stroke
			(width 0.508)
			(type default)
		)
		(layer "In4.Cu")
	)
	(gr_line
		(start 164.4904 -5.214112)
		(end 165.1254 -5.214112)
		(stroke
			(width 0.508)
			(type default)
		)
		(layer "In4.Cu")
	)
	(gr_line
		(start 164.4904 -3.029712)
		(end 165.1254 -3.029712)
		(stroke
			(width 0.508)
			(type default)
		)
		(layer "In4.Cu")
	)
	(gr_line
		(start 164.4904 -2.978912)
		(end 165.1254 -2.978912)
		(stroke
			(width 0.508)
			(type default)
		)
		(layer "In4.Cu")
	)
	(gr_line
		(start 164.5158 -11.684)
		(end 165.1508 -11.684)
		(stroke
			(width 0.508)
			(type default)
		)
		(layer "In4.Cu")
	)
	(gr_line
		(start 164.5158 -7.483856)
		(end 165.1508 -7.483856)
		(stroke
			(width 0.508)
			(type default)
		)
		(layer "In4.Cu")
	)
	(gr_line
		(start 164.5158 -3.283712)
		(end 165.1508 -3.283712)
		(stroke
			(width 0.508)
			(type default)
		)
		(layer "In4.Cu")
	)
	(gr_line
		(start 164.5412 -13.6398)
		(end 164.5412 -11.3792)
		(stroke
			(width 0.254)
			(type default)
		)
		(layer "In4.Cu")
	)
	(gr_line
		(start 164.5412 -13.4874)
		(end 165.1762 -13.4874)
		(stroke
			(width 0.508)
			(type default)
		)
		(layer "In4.Cu")
	)
	(gr_line
		(start 164.5412 -11.3792)
		(end 165.1762 -11.3792)
		(stroke
			(width 0.254)
			(type default)
		)
		(layer "In4.Cu")
	)
	(gr_line
		(start 164.5412 -9.439656)
		(end 164.5412 -7.179056)
		(stroke
			(width 0.254)
			(type default)
		)
		(layer "In4.Cu")
	)
	(gr_line
		(start 164.5412 -9.287256)
		(end 165.1762 -9.287256)
		(stroke
			(width 0.508)
			(type default)
		)
		(layer "In4.Cu")
	)
	(gr_line
		(start 164.5412 -7.179056)
		(end 165.1762 -7.179056)
		(stroke
			(width 0.254)
			(type default)
		)
		(layer "In4.Cu")
	)
	(gr_line
		(start 164.5412 -5.239512)
		(end 164.5412 -2.978912)
		(stroke
			(width 0.254)
			(type default)
		)
		(layer "In4.Cu")
	)
	(gr_line
		(start 164.5412 -5.087112)
		(end 165.1762 -5.087112)
		(stroke
			(width 0.508)
			(type default)
		)
		(layer "In4.Cu")
	)
	(gr_line
		(start 164.5412 -2.978912)
		(end 165.1762 -2.978912)
		(stroke
			(width 0.254)
			(type default)
		)
		(layer "In4.Cu")
	)
	(gr_line
		(start 164.5666 -13.335)
		(end 165.2016 -13.335)
		(stroke
			(width 0.508)
			(type default)
		)
		(layer "In4.Cu")
	)
	(gr_line
		(start 164.5666 -9.134856)
		(end 165.2016 -9.134856)
		(stroke
			(width 0.508)
			(type default)
		)
		(layer "In4.Cu")
	)
	(gr_line
		(start 164.5666 -4.934712)
		(end 165.2016 -4.934712)
		(stroke
			(width 0.508)
			(type default)
		)
		(layer "In4.Cu")
	)
	(gr_line
		(start 164.592 -13.6144)
		(end 165.227 -13.6144)
		(stroke
			(width 0.508)
			(type default)
		)
		(layer "In4.Cu")
	)
	(gr_line
		(start 164.592 -11.2014)
		(end 165.4302 -11.2014)
		(stroke
			(width 0.2032)
			(type default)
		)
		(layer "In4.Cu")
	)
	(gr_line
		(start 164.592 -9.414256)
		(end 165.227 -9.414256)
		(stroke
			(width 0.508)
			(type default)
		)
		(layer "In4.Cu")
	)
	(gr_line
		(start 164.592 -7.001256)
		(end 165.4302 -7.001256)
		(stroke
			(width 0.2032)
			(type default)
		)
		(layer "In4.Cu")
	)
	(gr_line
		(start 164.592 -5.214112)
		(end 165.227 -5.214112)
		(stroke
			(width 0.508)
			(type default)
		)
		(layer "In4.Cu")
	)
	(gr_line
		(start 164.592 -2.801112)
		(end 165.4302 -2.801112)
		(stroke
			(width 0.2032)
			(type default)
		)
		(layer "In4.Cu")
	)
	(gr_line
		(start 164.6174 -13.6144)
		(end 164.6174 -11.43)
		(stroke
			(width 0.254)
			(type default)
		)
		(layer "In4.Cu")
	)
	(gr_line
		(start 164.6174 -11.43)
		(end 165.1 -11.43)
		(stroke
			(width 0.254)
			(type default)
		)
		(layer "In4.Cu")
	)
	(gr_line
		(start 164.6174 -11.2522)
		(end 165.354 -11.2522)
		(stroke
			(width 0.254)
			(type default)
		)
		(layer "In4.Cu")
	)
	(gr_line
		(start 164.6174 -9.414256)
		(end 164.6174 -7.229856)
		(stroke
			(width 0.254)
			(type default)
		)
		(layer "In4.Cu")
	)
	(gr_line
		(start 164.6174 -7.229856)
		(end 165.1 -7.229856)
		(stroke
			(width 0.254)
			(type default)
		)
		(layer "In4.Cu")
	)
	(gr_line
		(start 164.6174 -7.052056)
		(end 165.354 -7.052056)
		(stroke
			(width 0.254)
			(type default)
		)
		(layer "In4.Cu")
	)
	(gr_line
		(start 164.6174 -5.214112)
		(end 164.6174 -3.029712)
		(stroke
			(width 0.254)
			(type default)
		)
		(layer "In4.Cu")
	)
	(gr_line
		(start 164.6174 -3.029712)
		(end 165.1 -3.029712)
		(stroke
			(width 0.254)
			(type default)
		)
		(layer "In4.Cu")
	)
	(gr_line
		(start 164.6174 -2.851912)
		(end 165.354 -2.851912)
		(stroke
			(width 0.254)
			(type default)
		)
		(layer "In4.Cu")
	)
	(gr_line
		(start 164.635942 -11.36523)
		(end 165.270942 -11.36523)
		(stroke
			(width 0.508)
			(type default)
		)
		(layer "In4.Cu")
	)
	(gr_line
		(start 164.635942 -7.165086)
		(end 165.270942 -7.165086)
		(stroke
			(width 0.508)
			(type default)
		)
		(layer "In4.Cu")
	)
	(gr_line
		(start 164.635942 -2.964942)
		(end 165.270942 -2.964942)
		(stroke
			(width 0.508)
			(type default)
		)
		(layer "In4.Cu")
	)
	(gr_line
		(start 164.6428 -13.6144)
		(end 165.2778 -13.6144)
		(stroke
			(width 0.508)
			(type default)
		)
		(layer "In4.Cu")
	)
	(gr_line
		(start 164.6428 -13.4874)
		(end 164.6428 -11.5062)
		(stroke
			(width 0.762)
			(type default)
		)
		(layer "In4.Cu")
	)
	(gr_line
		(start 164.6428 -11.5062)
		(end 165.2778 -11.5062)
		(stroke
			(width 0.508)
			(type default)
		)
		(layer "In4.Cu")
	)
	(gr_line
		(start 164.6428 -9.414256)
		(end 165.2778 -9.414256)
		(stroke
			(width 0.508)
			(type default)
		)
		(layer "In4.Cu")
	)
	(gr_line
		(start 164.6428 -9.287256)
		(end 164.6428 -7.306056)
		(stroke
			(width 0.762)
			(type default)
		)
		(layer "In4.Cu")
	)
	(gr_line
		(start 164.6428 -7.306056)
		(end 165.2778 -7.306056)
		(stroke
			(width 0.508)
			(type default)
		)
		(layer "In4.Cu")
	)
	(gr_line
		(start 164.6428 -5.214112)
		(end 165.2778 -5.214112)
		(stroke
			(width 0.508)
			(type default)
		)
		(layer "In4.Cu")
	)
	(gr_line
		(start 164.6428 -5.087112)
		(end 164.6428 -3.105912)
		(stroke
			(width 0.762)
			(type default)
		)
		(layer "In4.Cu")
	)
	(gr_line
		(start 164.6428 -3.105912)
		(end 165.2778 -3.105912)
		(stroke
			(width 0.508)
			(type default)
		)
		(layer "In4.Cu")
	)
	(gr_line
		(start 164.6936 -13.5382)
		(end 164.6936 -11.5062)
		(stroke
			(width 0.254)
			(type default)
		)
		(layer "In4.Cu")
	)
	(gr_line
		(start 164.6936 -11.5062)
		(end 165.0238 -11.5062)
		(stroke
			(width 0.254)
			(type default)
		)
		(layer "In4.Cu")
	)
	(gr_line
		(start 164.6936 -9.338056)
		(end 164.6936 -7.306056)
		(stroke
			(width 0.254)
			(type default)
		)
		(layer "In4.Cu")
	)
	(gr_line
		(start 164.6936 -7.306056)
		(end 165.0238 -7.306056)
		(stroke
			(width 0.254)
			(type default)
		)
		(layer "In4.Cu")
	)
	(gr_line
		(start 164.6936 -5.137912)
		(end 164.6936 -3.105912)
		(stroke
			(width 0.254)
			(type default)
		)
		(layer "In4.Cu")
	)
	(gr_line
		(start 164.6936 -3.105912)
		(end 165.0238 -3.105912)
		(stroke
			(width 0.254)
			(type default)
		)
		(layer "In4.Cu")
	)
	(gr_line
		(start 164.7952 -13.462)
		(end 164.7952 -11.6586)
		(stroke
			(width 0.254)
			(type default)
		)
		(layer "In4.Cu")
	)
	(gr_line
		(start 164.7952 -13.462)
		(end 164.7952 -11.4808)
		(stroke
			(width 0.762)
			(type default)
		)
		(layer "In4.Cu")
	)
	(gr_line
		(start 164.7952 -11.6586)
		(end 164.8968 -11.6586)
		(stroke
			(width 0.254)
			(type default)
		)
		(layer "In4.Cu")
	)
	(gr_line
		(start 164.7952 -9.261856)
		(end 164.7952 -7.458456)
		(stroke
			(width 0.254)
			(type default)
		)
		(layer "In4.Cu")
	)
	(gr_line
		(start 164.7952 -9.261856)
		(end 164.7952 -7.280656)
		(stroke
			(width 0.762)
			(type default)
		)
		(layer "In4.Cu")
	)
	(gr_line
		(start 164.7952 -7.458456)
		(end 164.8968 -7.458456)
		(stroke
			(width 0.254)
			(type default)
		)
		(layer "In4.Cu")
	)
	(gr_line
		(start 164.7952 -5.061712)
		(end 164.7952 -3.258312)
		(stroke
			(width 0.254)
			(type default)
		)
		(layer "In4.Cu")
	)
	(gr_line
		(start 164.7952 -5.061712)
		(end 164.7952 -3.080512)
		(stroke
			(width 0.762)
			(type default)
		)
		(layer "In4.Cu")
	)
	(gr_line
		(start 164.7952 -3.258312)
		(end 164.8968 -3.258312)
		(stroke
			(width 0.254)
			(type default)
		)
		(layer "In4.Cu")
	)
	(gr_line
		(start 164.8968 -13.5636)
		(end 164.846 -13.5636)
		(stroke
			(width 0.254)
			(type default)
		)
		(layer "In4.Cu")
	)
	(gr_line
		(start 164.8968 -11.6586)
		(end 164.8968 -13.5636)
		(stroke
			(width 0.254)
			(type default)
		)
		(layer "In4.Cu")
	)
	(gr_line
		(start 164.8968 -9.363456)
		(end 164.846 -9.363456)
		(stroke
			(width 0.254)
			(type default)
		)
		(layer "In4.Cu")
	)
	(gr_line
		(start 164.8968 -7.458456)
		(end 164.8968 -9.363456)
		(stroke
			(width 0.254)
			(type default)
		)
		(layer "In4.Cu")
	)
	(gr_line
		(start 164.8968 -5.163312)
		(end 164.846 -5.163312)
		(stroke
			(width 0.254)
			(type default)
		)
		(layer "In4.Cu")
	)
	(gr_line
		(start 164.8968 -3.258312)
		(end 164.8968 -5.163312)
		(stroke
			(width 0.254)
			(type default)
		)
		(layer "In4.Cu")
	)
	(gr_line
		(start 164.9476 -13.4874)
		(end 164.9476 -11.5062)
		(stroke
			(width 0.762)
			(type default)
		)
		(layer "In4.Cu")
	)
	(gr_line
		(start 164.9476 -9.287256)
		(end 164.9476 -7.306056)
		(stroke
			(width 0.762)
			(type default)
		)
		(layer "In4.Cu")
	)
	(gr_line
		(start 164.9476 -5.087112)
		(end 164.9476 -3.105912)
		(stroke
			(width 0.762)
			(type default)
		)
		(layer "In4.Cu")
	)
	(gr_line
		(start 165.0238 -13.462)
		(end 164.7952 -13.462)
		(stroke
			(width 0.254)
			(type default)
		)
		(layer "In4.Cu")
	)
	(gr_line
		(start 165.0238 -11.5062)
		(end 165.0238 -13.462)
		(stroke
			(width 0.254)
			(type default)
		)
		(layer "In4.Cu")
	)
	(gr_line
		(start 165.0238 -9.261856)
		(end 164.7952 -9.261856)
		(stroke
			(width 0.254)
			(type default)
		)
		(layer "In4.Cu")
	)
	(gr_line
		(start 165.0238 -7.306056)
		(end 165.0238 -9.261856)
		(stroke
			(width 0.254)
			(type default)
		)
		(layer "In4.Cu")
	)
	(gr_line
		(start 165.0238 -5.061712)
		(end 164.7952 -5.061712)
		(stroke
			(width 0.254)
			(type default)
		)
		(layer "In4.Cu")
	)
	(gr_line
		(start 165.0238 -3.105912)
		(end 165.0238 -5.061712)
		(stroke
			(width 0.254)
			(type default)
		)
		(layer "In4.Cu")
	)
	(gr_line
		(start 165.0746 -13.8176)
		(end 165.0746 -13.7668)
		(stroke
			(width 0.1016)
			(type default)
		)
		(layer "In4.Cu")
	)
	(gr_line
		(start 165.0746 -13.8176)
		(end 165.481 -13.8176)
		(stroke
			(width 0.1016)
			(type default)
		)
		(layer "In4.Cu")
	)
	(gr_line
		(start 165.0746 -13.7668)
		(end 164.3126 -13.7668)
		(stroke
			(width 0.1016)
			(type default)
		)
		(layer "In4.Cu")
	)
	(gr_line
		(start 165.0746 -13.4874)
		(end 165.0746 -11.5062)
		(stroke
			(width 0.762)
			(type default)
		)
		(layer "In4.Cu")
	)
	(gr_line
		(start 165.0746 -9.617456)
		(end 165.0746 -9.566656)
		(stroke
			(width 0.1016)
			(type default)
		)
		(layer "In4.Cu")
	)
	(gr_line
		(start 165.0746 -9.617456)
		(end 165.481 -9.617456)
		(stroke
			(width 0.1016)
			(type default)
		)
		(layer "In4.Cu")
	)
	(gr_line
		(start 165.0746 -9.566656)
		(end 164.3126 -9.566656)
		(stroke
			(width 0.1016)
			(type default)
		)
		(layer "In4.Cu")
	)
	(gr_line
		(start 165.0746 -9.287256)
		(end 165.0746 -7.306056)
		(stroke
			(width 0.762)
			(type default)
		)
		(layer "In4.Cu")
	)
	(gr_line
		(start 165.0746 -5.417312)
		(end 165.0746 -5.366512)
		(stroke
			(width 0.1016)
			(type default)
		)
		(layer "In4.Cu")
	)
	(gr_line
		(start 165.0746 -5.417312)
		(end 165.481 -5.417312)
		(stroke
			(width 0.1016)
			(type default)
		)
		(layer "In4.Cu")
	)
	(gr_line
		(start 165.0746 -5.366512)
		(end 164.3126 -5.366512)
		(stroke
			(width 0.1016)
			(type default)
		)
		(layer "In4.Cu")
	)
	(gr_line
		(start 165.0746 -5.087112)
		(end 165.0746 -3.105912)
		(stroke
			(width 0.762)
			(type default)
		)
		(layer "In4.Cu")
	)
	(gr_line
		(start 165.1 -13.5382)
		(end 164.6936 -13.5382)
		(stroke
			(width 0.254)
			(type default)
		)
		(layer "In4.Cu")
	)
	(gr_line
		(start 165.1 -11.43)
		(end 165.1 -13.5382)
		(stroke
			(width 0.254)
			(type default)
		)
		(layer "In4.Cu")
	)
	(gr_line
		(start 165.1 -9.338056)
		(end 164.6936 -9.338056)
		(stroke
			(width 0.254)
			(type default)
		)
		(layer "In4.Cu")
	)
	(gr_line
		(start 165.1 -7.229856)
		(end 165.1 -9.338056)
		(stroke
			(width 0.254)
			(type default)
		)
		(layer "In4.Cu")
	)
	(gr_line
		(start 165.1 -5.137912)
		(end 164.6936 -5.137912)
		(stroke
			(width 0.254)
			(type default)
		)
		(layer "In4.Cu")
	)
	(gr_line
		(start 165.1 -3.029712)
		(end 165.1 -5.137912)
		(stroke
			(width 0.254)
			(type default)
		)
		(layer "In4.Cu")
	)
	(gr_line
		(start 165.1508 -13.4874)
		(end 165.1508 -11.5062)
		(stroke
			(width 0.762)
			(type default)
		)
		(layer "In4.Cu")
	)
	(gr_line
		(start 165.1508 -9.287256)
		(end 165.1508 -7.306056)
		(stroke
			(width 0.762)
			(type default)
		)
		(layer "In4.Cu")
	)
	(gr_line
		(start 165.1508 -5.087112)
		(end 165.1508 -3.105912)
		(stroke
			(width 0.762)
			(type default)
		)
		(layer "In4.Cu")
	)
	(gr_line
		(start 165.1762 -13.6144)
		(end 164.6174 -13.6144)
		(stroke
			(width 0.254)
			(type default)
		)
		(layer "In4.Cu")
	)
	(gr_line
		(start 165.1762 -11.3792)
		(end 165.1762 -13.6144)
		(stroke
			(width 0.254)
			(type default)
		)
		(layer "In4.Cu")
	)
	(gr_line
		(start 165.1762 -9.414256)
		(end 164.6174 -9.414256)
		(stroke
			(width 0.254)
			(type default)
		)
		(layer "In4.Cu")
	)
	(gr_line
		(start 165.1762 -7.179056)
		(end 165.1762 -9.414256)
		(stroke
			(width 0.254)
			(type default)
		)
		(layer "In4.Cu")
	)
	(gr_line
		(start 165.1762 -5.214112)
		(end 164.6174 -5.214112)
		(stroke
			(width 0.254)
			(type default)
		)
		(layer "In4.Cu")
	)
	(gr_line
		(start 165.1762 -2.978912)
		(end 165.1762 -5.214112)
		(stroke
			(width 0.254)
			(type default)
		)
		(layer "In4.Cu")
	)
	(gr_line
		(start 165.2524 -13.6398)
		(end 164.5412 -13.6398)
		(stroke
			(width 0.254)
			(type default)
		)
		(layer "In4.Cu")
	)
	(gr_line
		(start 165.2524 -11.303)
		(end 165.2524 -13.6398)
		(stroke
			(width 0.254)
			(type default)
		)
		(layer "In4.Cu")
	)
	(gr_line
		(start 165.2524 -9.439656)
		(end 164.5412 -9.439656)
		(stroke
			(width 0.254)
			(type default)
		)
		(layer "In4.Cu")
	)
	(gr_line
		(start 165.2524 -7.102856)
		(end 165.2524 -9.439656)
		(stroke
			(width 0.254)
			(type default)
		)
		(layer "In4.Cu")
	)
	(gr_line
		(start 165.2524 -5.239512)
		(end 164.5412 -5.239512)
		(stroke
			(width 0.254)
			(type default)
		)
		(layer "In4.Cu")
	)
	(gr_line
		(start 165.2524 -2.902712)
		(end 165.2524 -5.239512)
		(stroke
			(width 0.254)
			(type default)
		)
		(layer "In4.Cu")
	)
	(gr_line
		(start 165.2778 -13.7668)
		(end 164.2872 -13.7668)
		(stroke
			(width 0.1016)
			(type default)
		)
		(layer "In4.Cu")
	)
	(gr_line
		(start 165.2778 -13.6906)
		(end 164.465 -13.6906)
		(stroke
			(width 0.254)
			(type default)
		)
		(layer "In4.Cu")
	)
	(gr_line
		(start 165.2778 -11.2776)
		(end 165.2778 -13.6906)
		(stroke
			(width 0.254)
			(type default)
		)
		(layer "In4.Cu")
	)
	(gr_line
		(start 165.2778 -9.566656)
		(end 164.2872 -9.566656)
		(stroke
			(width 0.1016)
			(type default)
		)
		(layer "In4.Cu")
	)
	(gr_line
		(start 165.2778 -9.490456)
		(end 164.465 -9.490456)
		(stroke
			(width 0.254)
			(type default)
		)
		(layer "In4.Cu")
	)
	(gr_line
		(start 165.2778 -7.077456)
		(end 165.2778 -9.490456)
		(stroke
			(width 0.254)
			(type default)
		)
		(layer "In4.Cu")
	)
	(gr_line
		(start 165.2778 -5.366512)
		(end 164.2872 -5.366512)
		(stroke
			(width 0.1016)
			(type default)
		)
		(layer "In4.Cu")
	)
	(gr_line
		(start 165.2778 -5.290312)
		(end 164.465 -5.290312)
		(stroke
			(width 0.254)
			(type default)
		)
		(layer "In4.Cu")
	)
	(gr_line
		(start 165.2778 -2.877312)
		(end 165.2778 -5.290312)
		(stroke
			(width 0.254)
			(type default)
		)
		(layer "In4.Cu")
	)
	(gr_line
		(start 165.3032 -13.716)
		(end 164.4396 -13.716)
		(stroke
			(width 0.254)
			(type default)
		)
		(layer "In4.Cu")
	)
	(gr_line
		(start 165.3032 -11.2522)
		(end 165.3032 -13.716)
		(stroke
			(width 0.254)
			(type default)
		)
		(layer "In4.Cu")
	)
	(gr_line
		(start 165.3032 -9.515856)
		(end 164.4396 -9.515856)
		(stroke
			(width 0.254)
			(type default)
		)
		(layer "In4.Cu")
	)
	(gr_line
		(start 165.3032 -7.052056)
		(end 165.3032 -9.515856)
		(stroke
			(width 0.254)
			(type default)
		)
		(layer "In4.Cu")
	)
	(gr_line
		(start 165.3032 -5.315712)
		(end 164.4396 -5.315712)
		(stroke
			(width 0.254)
			(type default)
		)
		(layer "In4.Cu")
	)
	(gr_line
		(start 165.3032 -2.851912)
		(end 165.3032 -5.315712)
		(stroke
			(width 0.254)
			(type default)
		)
		(layer "In4.Cu")
	)
	(gr_line
		(start 165.354 -13.7414)
		(end 164.4142 -13.7414)
		(stroke
			(width 0.254)
			(type default)
		)
		(layer "In4.Cu")
	)
	(gr_line
		(start 165.354 -11.2522)
		(end 165.354 -13.7414)
		(stroke
			(width 0.254)
			(type default)
		)
		(layer "In4.Cu")
	)
	(gr_line
		(start 165.354 -9.541256)
		(end 164.4142 -9.541256)
		(stroke
			(width 0.254)
			(type default)
		)
		(layer "In4.Cu")
	)
	(gr_line
		(start 165.354 -7.052056)
		(end 165.354 -9.541256)
		(stroke
			(width 0.254)
			(type default)
		)
		(layer "In4.Cu")
	)
	(gr_line
		(start 165.354 -5.341112)
		(end 164.4142 -5.341112)
		(stroke
			(width 0.254)
			(type default)
		)
		(layer "In4.Cu")
	)
	(gr_line
		(start 165.354 -2.851912)
		(end 165.354 -5.341112)
		(stroke
			(width 0.254)
			(type default)
		)
		(layer "In4.Cu")
	)
	(gr_line
		(start 165.3794 -13.7414)
		(end 164.4142 -13.7414)
		(stroke
			(width 0.2032)
			(type default)
		)
		(layer "In4.Cu")
	)
	(gr_line
		(start 165.3794 -11.2014)
		(end 165.3794 -13.7414)
		(stroke
			(width 0.2032)
			(type default)
		)
		(layer "In4.Cu")
	)
	(gr_line
		(start 165.3794 -9.541256)
		(end 164.4142 -9.541256)
		(stroke
			(width 0.2032)
			(type default)
		)
		(layer "In4.Cu")
	)
	(gr_line
		(start 165.3794 -7.001256)
		(end 165.3794 -9.541256)
		(stroke
			(width 0.2032)
			(type default)
		)
		(layer "In4.Cu")
	)
	(gr_line
		(start 165.3794 -5.341112)
		(end 164.4142 -5.341112)
		(stroke
			(width 0.2032)
			(type default)
		)
		(layer "In4.Cu")
	)
	(gr_line
		(start 165.3794 -2.801112)
		(end 165.3794 -5.341112)
		(stroke
			(width 0.2032)
			(type default)
		)
		(layer "In4.Cu")
	)
	(gr_line
		(start 165.4302 -13.7668)
		(end 164.3634 -13.7668)
		(stroke
			(width 0.2032)
			(type default)
		)
		(layer "In4.Cu")
	)
	(gr_line
		(start 165.4302 -11.2014)
		(end 165.4302 -13.7668)
		(stroke
			(width 0.2032)
			(type default)
		)
		(layer "In4.Cu")
	)
	(gr_line
		(start 165.4302 -9.566656)
		(end 164.3634 -9.566656)
		(stroke
			(width 0.2032)
			(type default)
		)
		(layer "In4.Cu")
	)
	(gr_line
		(start 165.4302 -7.001256)
		(end 165.4302 -9.566656)
		(stroke
			(width 0.2032)
			(type default)
		)
		(layer "In4.Cu")
	)
	(gr_line
		(start 165.4302 -5.366512)
		(end 164.3634 -5.366512)
		(stroke
			(width 0.2032)
			(type default)
		)
		(layer "In4.Cu")
	)
	(gr_line
		(start 165.4302 -2.801112)
		(end 165.4302 -5.366512)
		(stroke
			(width 0.2032)
			(type default)
		)
		(layer "In4.Cu")
	)
	(gr_line
		(start 165.4556 -13.7668)
		(end 164.338 -13.7668)
		(stroke
			(width 0.1016)
			(type default)
		)
		(layer "In4.Cu")
	)
	(gr_line
		(start 165.4556 -11.176)
		(end 165.4556 -13.7668)
		(stroke
			(width 0.1016)
			(type default)
		)
		(layer "In4.Cu")
	)
	(gr_line
		(start 165.4556 -9.566656)
		(end 164.338 -9.566656)
		(stroke
			(width 0.1016)
			(type default)
		)
		(layer "In4.Cu")
	)
	(gr_line
		(start 165.4556 -6.975856)
		(end 165.4556 -9.566656)
		(stroke
			(width 0.1016)
			(type default)
		)
		(layer "In4.Cu")
	)
	(gr_line
		(start 165.4556 -5.366512)
		(end 164.338 -5.366512)
		(stroke
			(width 0.1016)
			(type default)
		)
		(layer "In4.Cu")
	)
	(gr_line
		(start 165.4556 -2.775712)
		(end 165.4556 -5.366512)
		(stroke
			(width 0.1016)
			(type default)
		)
		(layer "In4.Cu")
	)
	(gr_line
		(start 165.481 -13.8176)
		(end 165.0746 -13.8176)
		(stroke
			(width 0.1016)
			(type default)
		)
		(layer "In4.Cu")
	)
	(gr_line
		(start 165.481 -13.8176)
		(end 165.481 -11.1506)
		(stroke
			(width 0.1016)
			(type default)
		)
		(layer "In4.Cu")
	)
	(gr_line
		(start 165.481 -11.1506)
		(end 164.2872 -11.1506)
		(stroke
			(width 0.1016)
			(type default)
		)
		(layer "In4.Cu")
	)
	(gr_line
		(start 165.481 -11.1506)
		(end 165.481 -13.8176)
		(stroke
			(width 0.1016)
			(type default)
		)
		(layer "In4.Cu")
	)
	(gr_line
		(start 165.481 -9.617456)
		(end 165.0746 -9.617456)
		(stroke
			(width 0.1016)
			(type default)
		)
		(layer "In4.Cu")
	)
	(gr_line
		(start 165.481 -9.617456)
		(end 165.481 -6.950456)
		(stroke
			(width 0.1016)
			(type default)
		)
		(layer "In4.Cu")
	)
	(gr_line
		(start 165.481 -6.950456)
		(end 164.2872 -6.950456)
		(stroke
			(width 0.1016)
			(type default)
		)
		(layer "In4.Cu")
	)
	(gr_line
		(start 165.481 -6.950456)
		(end 165.481 -9.617456)
		(stroke
			(width 0.1016)
			(type default)
		)
		(layer "In4.Cu")
	)
	(gr_line
		(start 165.481 -5.417312)
		(end 165.0746 -5.417312)
		(stroke
			(width 0.1016)
			(type default)
		)
		(layer "In4.Cu")
	)
	(gr_line
		(start 165.481 -5.417312)
		(end 165.481 -2.750312)
		(stroke
			(width 0.1016)
			(type default)
		)
		(layer "In4.Cu")
	)
	(gr_line
		(start 165.481 -2.750312)
		(end 164.2872 -2.750312)
		(stroke
			(width 0.1016)
			(type default)
		)
		(layer "In4.Cu")
	)
	(gr_line
		(start 165.481 -2.750312)
		(end 165.481 -5.417312)
		(stroke
			(width 0.1016)
			(type default)
		)
		(layer "In4.Cu")
	)
	(gr_line
		(start 166.2176 -24.6634)
		(end 166.2176 -23.3934)
		(stroke
			(width 0.7874)
			(type default)
		)
		(layer "In4.Cu")
	)
	(gr_line
		(start 166.287196 -12.563348)
		(end 167.074596 -12.563348)
		(stroke
			(width 0.1016)
			(type default)
		)
		(layer "In4.Cu")
	)
	(gr_line
		(start 166.287196 -12.512548)
		(end 166.287196 -9.896348)
		(stroke
			(width 0.1016)
			(type default)
		)
		(layer "In4.Cu")
	)
	(gr_line
		(start 166.287196 -12.463272)
		(end 167.074596 -12.463272)
		(stroke
			(width 0.1016)
			(type default)
		)
		(layer "In4.Cu")
	)
	(gr_line
		(start 166.287196 -12.412472)
		(end 166.287196 -9.796272)
		(stroke
			(width 0.1016)
			(type default)
		)
		(layer "In4.Cu")
	)
	(gr_line
		(start 166.287196 -9.896348)
		(end 166.287196 -12.563348)
		(stroke
			(width 0.1016)
			(type default)
		)
		(layer "In4.Cu")
	)
	(gr_line
		(start 166.287196 -9.896348)
		(end 167.480996 -9.896348)
		(stroke
			(width 0.1016)
			(type default)
		)
		(layer "In4.Cu")
	)
	(gr_line
		(start 166.287196 -9.796272)
		(end 166.287196 -12.463272)
		(stroke
			(width 0.1016)
			(type default)
		)
		(layer "In4.Cu")
	)
	(gr_line
		(start 166.287196 -9.796272)
		(end 167.480996 -9.796272)
		(stroke
			(width 0.1016)
			(type default)
		)
		(layer "In4.Cu")
	)
	(gr_line
		(start 166.287196 -8.363204)
		(end 167.074596 -8.363204)
		(stroke
			(width 0.1016)
			(type default)
		)
		(layer "In4.Cu")
	)
	(gr_line
		(start 166.287196 -8.312404)
		(end 166.287196 -5.696204)
		(stroke
			(width 0.1016)
			(type default)
		)
		(layer "In4.Cu")
	)
	(gr_line
		(start 166.287196 -8.263128)
		(end 167.074596 -8.263128)
		(stroke
			(width 0.1016)
			(type default)
		)
		(layer "In4.Cu")
	)
	(gr_line
		(start 166.287196 -8.212328)
		(end 166.287196 -5.596128)
		(stroke
			(width 0.1016)
			(type default)
		)
		(layer "In4.Cu")
	)
	(gr_line
		(start 166.287196 -5.696204)
		(end 166.287196 -8.363204)
		(stroke
			(width 0.1016)
			(type default)
		)
		(layer "In4.Cu")
	)
	(gr_line
		(start 166.287196 -5.696204)
		(end 167.480996 -5.696204)
		(stroke
			(width 0.1016)
			(type default)
		)
		(layer "In4.Cu")
	)
	(gr_line
		(start 166.287196 -5.596128)
		(end 166.287196 -8.263128)
		(stroke
			(width 0.1016)
			(type default)
		)
		(layer "In4.Cu")
	)
	(gr_line
		(start 166.287196 -5.596128)
		(end 167.480996 -5.596128)
		(stroke
			(width 0.1016)
			(type default)
		)
		(layer "In4.Cu")
	)
	(gr_line
		(start 166.287196 -4.16306)
		(end 167.074596 -4.16306)
		(stroke
			(width 0.1016)
			(type default)
		)
		(layer "In4.Cu")
	)
	(gr_line
		(start 166.287196 -4.11226)
		(end 166.287196 -1.49606)
		(stroke
			(width 0.1016)
			(type default)
		)
		(layer "In4.Cu")
	)
	(gr_line
		(start 166.287196 -4.062984)
		(end 167.074596 -4.062984)
		(stroke
			(width 0.1016)
			(type default)
		)
		(layer "In4.Cu")
	)
	(gr_line
		(start 166.287196 -4.012184)
		(end 166.287196 -1.395984)
		(stroke
			(width 0.1016)
			(type default)
		)
		(layer "In4.Cu")
	)
	(gr_line
		(start 166.287196 -1.49606)
		(end 166.287196 -4.16306)
		(stroke
			(width 0.1016)
			(type default)
		)
		(layer "In4.Cu")
	)
	(gr_line
		(start 166.287196 -1.49606)
		(end 167.480996 -1.49606)
		(stroke
			(width 0.1016)
			(type default)
		)
		(layer "In4.Cu")
	)
	(gr_line
		(start 166.287196 -1.395984)
		(end 166.287196 -4.062984)
		(stroke
			(width 0.1016)
			(type default)
		)
		(layer "In4.Cu")
	)
	(gr_line
		(start 166.287196 -1.395984)
		(end 167.480996 -1.395984)
		(stroke
			(width 0.1016)
			(type default)
		)
		(layer "In4.Cu")
	)
	(gr_line
		(start 166.312596 -12.512548)
		(end 166.312596 -9.921748)
		(stroke
			(width 0.1016)
			(type default)
		)
		(layer "In4.Cu")
	)
	(gr_line
		(start 166.312596 -12.412472)
		(end 166.312596 -9.821672)
		(stroke
			(width 0.1016)
			(type default)
		)
		(layer "In4.Cu")
	)
	(gr_line
		(start 166.312596 -9.921748)
		(end 167.455596 -9.921748)
		(stroke
			(width 0.1016)
			(type default)
		)
		(layer "In4.Cu")
	)
	(gr_line
		(start 166.312596 -9.821672)
		(end 167.455596 -9.821672)
		(stroke
			(width 0.1016)
			(type default)
		)
		(layer "In4.Cu")
	)
	(gr_line
		(start 166.312596 -8.312404)
		(end 166.312596 -5.721604)
		(stroke
			(width 0.1016)
			(type default)
		)
		(layer "In4.Cu")
	)
	(gr_line
		(start 166.312596 -8.212328)
		(end 166.312596 -5.621528)
		(stroke
			(width 0.1016)
			(type default)
		)
		(layer "In4.Cu")
	)
	(gr_line
		(start 166.312596 -5.721604)
		(end 167.455596 -5.721604)
		(stroke
			(width 0.1016)
			(type default)
		)
		(layer "In4.Cu")
	)
	(gr_line
		(start 166.312596 -5.621528)
		(end 167.455596 -5.621528)
		(stroke
			(width 0.1016)
			(type default)
		)
		(layer "In4.Cu")
	)
	(gr_line
		(start 166.312596 -4.11226)
		(end 166.312596 -1.52146)
		(stroke
			(width 0.1016)
			(type default)
		)
		(layer "In4.Cu")
	)
	(gr_line
		(start 166.312596 -4.012184)
		(end 166.312596 -1.421384)
		(stroke
			(width 0.1016)
			(type default)
		)
		(layer "In4.Cu")
	)
	(gr_line
		(start 166.312596 -1.52146)
		(end 167.455596 -1.52146)
		(stroke
			(width 0.1016)
			(type default)
		)
		(layer "In4.Cu")
	)
	(gr_line
		(start 166.312596 -1.421384)
		(end 167.455596 -1.421384)
		(stroke
			(width 0.1016)
			(type default)
		)
		(layer "In4.Cu")
	)
	(gr_line
		(start 166.337996 -12.512548)
		(end 166.337996 -9.947148)
		(stroke
			(width 0.1016)
			(type default)
		)
		(layer "In4.Cu")
	)
	(gr_line
		(start 166.337996 -12.412472)
		(end 166.337996 -9.847072)
		(stroke
			(width 0.1016)
			(type default)
		)
		(layer "In4.Cu")
	)
	(gr_line
		(start 166.337996 -9.947148)
		(end 166.591996 -9.947148)
		(stroke
			(width 0.1016)
			(type default)
		)
		(layer "In4.Cu")
	)
	(gr_line
		(start 166.337996 -9.847072)
		(end 166.591996 -9.847072)
		(stroke
			(width 0.1016)
			(type default)
		)
		(layer "In4.Cu")
	)
	(gr_line
		(start 166.337996 -8.312404)
		(end 166.337996 -5.747004)
		(stroke
			(width 0.1016)
			(type default)
		)
		(layer "In4.Cu")
	)
	(gr_line
		(start 166.337996 -8.212328)
		(end 166.337996 -5.646928)
		(stroke
			(width 0.1016)
			(type default)
		)
		(layer "In4.Cu")
	)
	(gr_line
		(start 166.337996 -5.747004)
		(end 166.591996 -5.747004)
		(stroke
			(width 0.1016)
			(type default)
		)
		(layer "In4.Cu")
	)
	(gr_line
		(start 166.337996 -5.646928)
		(end 166.591996 -5.646928)
		(stroke
			(width 0.1016)
			(type default)
		)
		(layer "In4.Cu")
	)
	(gr_line
		(start 166.337996 -4.11226)
		(end 166.337996 -1.54686)
		(stroke
			(width 0.1016)
			(type default)
		)
		(layer "In4.Cu")
	)
	(gr_line
		(start 166.337996 -4.012184)
		(end 166.337996 -1.446784)
		(stroke
			(width 0.1016)
			(type default)
		)
		(layer "In4.Cu")
	)
	(gr_line
		(start 166.337996 -1.54686)
		(end 166.591996 -1.54686)
		(stroke
			(width 0.1016)
			(type default)
		)
		(layer "In4.Cu")
	)
	(gr_line
		(start 166.337996 -1.446784)
		(end 166.591996 -1.446784)
		(stroke
			(width 0.1016)
			(type default)
		)
		(layer "In4.Cu")
	)
	(gr_line
		(start 166.363396 -12.512548)
		(end 166.363396 -9.947148)
		(stroke
			(width 0.2032)
			(type default)
		)
		(layer "In4.Cu")
	)
	(gr_line
		(start 166.363396 -12.412472)
		(end 166.363396 -9.847072)
		(stroke
			(width 0.2032)
			(type default)
		)
		(layer "In4.Cu")
	)
	(gr_line
		(start 166.363396 -9.947148)
		(end 167.379396 -9.947148)
		(stroke
			(width 0.2032)
			(type default)
		)
		(layer "In4.Cu")
	)
	(gr_line
		(start 166.363396 -9.847072)
		(end 167.379396 -9.847072)
		(stroke
			(width 0.2032)
			(type default)
		)
		(layer "In4.Cu")
	)
	(gr_line
		(start 166.363396 -8.312404)
		(end 166.363396 -5.747004)
		(stroke
			(width 0.2032)
			(type default)
		)
		(layer "In4.Cu")
	)
	(gr_line
		(start 166.363396 -8.212328)
		(end 166.363396 -5.646928)
		(stroke
			(width 0.2032)
			(type default)
		)
		(layer "In4.Cu")
	)
	(gr_line
		(start 166.363396 -5.747004)
		(end 167.379396 -5.747004)
		(stroke
			(width 0.2032)
			(type default)
		)
		(layer "In4.Cu")
	)
	(gr_line
		(start 166.363396 -5.646928)
		(end 167.379396 -5.646928)
		(stroke
			(width 0.2032)
			(type default)
		)
		(layer "In4.Cu")
	)
	(gr_line
		(start 166.363396 -4.11226)
		(end 166.363396 -1.54686)
		(stroke
			(width 0.2032)
			(type default)
		)
		(layer "In4.Cu")
	)
	(gr_line
		(start 166.363396 -4.012184)
		(end 166.363396 -1.446784)
		(stroke
			(width 0.2032)
			(type default)
		)
		(layer "In4.Cu")
	)
	(gr_line
		(start 166.363396 -1.54686)
		(end 167.379396 -1.54686)
		(stroke
			(width 0.2032)
			(type default)
		)
		(layer "In4.Cu")
	)
	(gr_line
		(start 166.363396 -1.446784)
		(end 167.379396 -1.446784)
		(stroke
			(width 0.2032)
			(type default)
		)
		(layer "In4.Cu")
	)
	(gr_line
		(start 166.414196 -12.487148)
		(end 166.414196 -9.997948)
		(stroke
			(width 0.2032)
			(type default)
		)
		(layer "In4.Cu")
	)
	(gr_line
		(start 166.414196 -12.487148)
		(end 166.414196 -9.997948)
		(stroke
			(width 0.254)
			(type default)
		)
		(layer "In4.Cu")
	)
	(gr_line
		(start 166.414196 -12.387072)
		(end 166.414196 -9.897872)
		(stroke
			(width 0.2032)
			(type default)
		)
		(layer "In4.Cu")
	)
	(gr_line
		(start 166.414196 -12.387072)
		(end 166.414196 -9.897872)
		(stroke
			(width 0.254)
			(type default)
		)
		(layer "In4.Cu")
	)
	(gr_line
		(start 166.414196 -9.997948)
		(end 166.617396 -9.997948)
		(stroke
			(width 0.2032)
			(type default)
		)
		(layer "In4.Cu")
	)
	(gr_line
		(start 166.414196 -9.997948)
		(end 167.303196 -9.997948)
		(stroke
			(width 0.254)
			(type default)
		)
		(layer "In4.Cu")
	)
	(gr_line
		(start 166.414196 -9.897872)
		(end 166.617396 -9.897872)
		(stroke
			(width 0.2032)
			(type default)
		)
		(layer "In4.Cu")
	)
	(gr_line
		(start 166.414196 -9.897872)
		(end 167.303196 -9.897872)
		(stroke
			(width 0.254)
			(type default)
		)
		(layer "In4.Cu")
	)
	(gr_line
		(start 166.414196 -8.287004)
		(end 166.414196 -5.797804)
		(stroke
			(width 0.2032)
			(type default)
		)
		(layer "In4.Cu")
	)
	(gr_line
		(start 166.414196 -8.287004)
		(end 166.414196 -5.797804)
		(stroke
			(width 0.254)
			(type default)
		)
		(layer "In4.Cu")
	)
	(gr_line
		(start 166.414196 -8.186928)
		(end 166.414196 -5.697728)
		(stroke
			(width 0.2032)
			(type default)
		)
		(layer "In4.Cu")
	)
	(gr_line
		(start 166.414196 -8.186928)
		(end 166.414196 -5.697728)
		(stroke
			(width 0.254)
			(type default)
		)
		(layer "In4.Cu")
	)
	(gr_line
		(start 166.414196 -5.797804)
		(end 166.617396 -5.797804)
		(stroke
			(width 0.2032)
			(type default)
		)
		(layer "In4.Cu")
	)
	(gr_line
		(start 166.414196 -5.797804)
		(end 167.303196 -5.797804)
		(stroke
			(width 0.254)
			(type default)
		)
		(layer "In4.Cu")
	)
	(gr_line
		(start 166.414196 -5.697728)
		(end 166.617396 -5.697728)
		(stroke
			(width 0.2032)
			(type default)
		)
		(layer "In4.Cu")
	)
	(gr_line
		(start 166.414196 -5.697728)
		(end 167.303196 -5.697728)
		(stroke
			(width 0.254)
			(type default)
		)
		(layer "In4.Cu")
	)
	(gr_line
		(start 166.414196 -4.08686)
		(end 166.414196 -1.59766)
		(stroke
			(width 0.2032)
			(type default)
		)
		(layer "In4.Cu")
	)
	(gr_line
		(start 166.414196 -4.08686)
		(end 166.414196 -1.59766)
		(stroke
			(width 0.254)
			(type default)
		)
		(layer "In4.Cu")
	)
	(gr_line
		(start 166.414196 -3.986784)
		(end 166.414196 -1.497584)
		(stroke
			(width 0.2032)
			(type default)
		)
		(layer "In4.Cu")
	)
	(gr_line
		(start 166.414196 -3.986784)
		(end 166.414196 -1.497584)
		(stroke
			(width 0.254)
			(type default)
		)
		(layer "In4.Cu")
	)
	(gr_line
		(start 166.414196 -1.59766)
		(end 166.617396 -1.59766)
		(stroke
			(width 0.2032)
			(type default)
		)
		(layer "In4.Cu")
	)
	(gr_line
		(start 166.414196 -1.59766)
		(end 167.303196 -1.59766)
		(stroke
			(width 0.254)
			(type default)
		)
		(layer "In4.Cu")
	)
	(gr_line
		(start 166.414196 -1.497584)
		(end 166.617396 -1.497584)
		(stroke
			(width 0.2032)
			(type default)
		)
		(layer "In4.Cu")
	)
	(gr_line
		(start 166.414196 -1.497584)
		(end 167.303196 -1.497584)
		(stroke
			(width 0.254)
			(type default)
		)
		(layer "In4.Cu")
	)
	(gr_line
		(start 166.439596 -12.461748)
		(end 166.439596 -10.023348)
		(stroke
			(width 0.254)
			(type default)
		)
		(layer "In4.Cu")
	)
	(gr_line
		(start 166.439596 -12.361672)
		(end 166.439596 -9.923272)
		(stroke
			(width 0.254)
			(type default)
		)
		(layer "In4.Cu")
	)
	(gr_line
		(start 166.439596 -10.023348)
		(end 167.277796 -10.023348)
		(stroke
			(width 0.254)
			(type default)
		)
		(layer "In4.Cu")
	)
	(gr_line
		(start 166.439596 -9.923272)
		(end 167.277796 -9.923272)
		(stroke
			(width 0.254)
			(type default)
		)
		(layer "In4.Cu")
	)
	(gr_line
		(start 166.439596 -8.261604)
		(end 166.439596 -5.823204)
		(stroke
			(width 0.254)
			(type default)
		)
		(layer "In4.Cu")
	)
	(gr_line
		(start 166.439596 -8.161528)
		(end 166.439596 -5.723128)
		(stroke
			(width 0.254)
			(type default)
		)
		(layer "In4.Cu")
	)
	(gr_line
		(start 166.439596 -5.823204)
		(end 167.277796 -5.823204)
		(stroke
			(width 0.254)
			(type default)
		)
		(layer "In4.Cu")
	)
	(gr_line
		(start 166.439596 -5.723128)
		(end 167.277796 -5.723128)
		(stroke
			(width 0.254)
			(type default)
		)
		(layer "In4.Cu")
	)
	(gr_line
		(start 166.439596 -4.06146)
		(end 166.439596 -1.62306)
		(stroke
			(width 0.254)
			(type default)
		)
		(layer "In4.Cu")
	)
	(gr_line
		(start 166.439596 -3.961384)
		(end 166.439596 -1.522984)
		(stroke
			(width 0.254)
			(type default)
		)
		(layer "In4.Cu")
	)
	(gr_line
		(start 166.439596 -1.62306)
		(end 167.277796 -1.62306)
		(stroke
			(width 0.254)
			(type default)
		)
		(layer "In4.Cu")
	)
	(gr_line
		(start 166.439596 -1.522984)
		(end 167.277796 -1.522984)
		(stroke
			(width 0.254)
			(type default)
		)
		(layer "In4.Cu")
	)
	(gr_line
		(start 166.464996 -12.436348)
		(end 166.464996 -10.048748)
		(stroke
			(width 0.254)
			(type default)
		)
		(layer "In4.Cu")
	)
	(gr_line
		(start 166.464996 -12.336272)
		(end 166.464996 -9.948672)
		(stroke
			(width 0.254)
			(type default)
		)
		(layer "In4.Cu")
	)
	(gr_line
		(start 166.464996 -10.048748)
		(end 167.252396 -10.048748)
		(stroke
			(width 0.254)
			(type default)
		)
		(layer "In4.Cu")
	)
	(gr_line
		(start 166.464996 -9.948672)
		(end 167.252396 -9.948672)
		(stroke
			(width 0.254)
			(type default)
		)
		(layer "In4.Cu")
	)
	(gr_line
		(start 166.464996 -8.236204)
		(end 166.464996 -5.848604)
		(stroke
			(width 0.254)
			(type default)
		)
		(layer "In4.Cu")
	)
	(gr_line
		(start 166.464996 -8.136128)
		(end 166.464996 -5.748528)
		(stroke
			(width 0.254)
			(type default)
		)
		(layer "In4.Cu")
	)
	(gr_line
		(start 166.464996 -5.848604)
		(end 167.252396 -5.848604)
		(stroke
			(width 0.254)
			(type default)
		)
		(layer "In4.Cu")
	)
	(gr_line
		(start 166.464996 -5.748528)
		(end 167.252396 -5.748528)
		(stroke
			(width 0.254)
			(type default)
		)
		(layer "In4.Cu")
	)
	(gr_line
		(start 166.464996 -4.03606)
		(end 166.464996 -1.64846)
		(stroke
			(width 0.254)
			(type default)
		)
		(layer "In4.Cu")
	)
	(gr_line
		(start 166.464996 -3.935984)
		(end 166.464996 -1.548384)
		(stroke
			(width 0.254)
			(type default)
		)
		(layer "In4.Cu")
	)
	(gr_line
		(start 166.464996 -1.64846)
		(end 167.252396 -1.64846)
		(stroke
			(width 0.254)
			(type default)
		)
		(layer "In4.Cu")
	)
	(gr_line
		(start 166.464996 -1.548384)
		(end 167.252396 -1.548384)
		(stroke
			(width 0.254)
			(type default)
		)
		(layer "In4.Cu")
	)
	(gr_line
		(start 166.490396 -12.360148)
		(end 167.125396 -12.360148)
		(stroke
			(width 0.508)
			(type default)
		)
		(layer "In4.Cu")
	)
	(gr_line
		(start 166.490396 -12.260072)
		(end 167.125396 -12.260072)
		(stroke
			(width 0.508)
			(type default)
		)
		(layer "In4.Cu")
	)
	(gr_line
		(start 166.490396 -10.175748)
		(end 167.125396 -10.175748)
		(stroke
			(width 0.508)
			(type default)
		)
		(layer "In4.Cu")
	)
	(gr_line
		(start 166.490396 -10.124948)
		(end 167.125396 -10.124948)
		(stroke
			(width 0.508)
			(type default)
		)
		(layer "In4.Cu")
	)
	(gr_line
		(start 166.490396 -10.075672)
		(end 167.125396 -10.075672)
		(stroke
			(width 0.508)
			(type default)
		)
		(layer "In4.Cu")
	)
	(gr_line
		(start 166.490396 -10.024872)
		(end 167.125396 -10.024872)
		(stroke
			(width 0.508)
			(type default)
		)
		(layer "In4.Cu")
	)
	(gr_line
		(start 166.490396 -8.160004)
		(end 167.125396 -8.160004)
		(stroke
			(width 0.508)
			(type default)
		)
		(layer "In4.Cu")
	)
	(gr_line
		(start 166.490396 -8.059928)
		(end 167.125396 -8.059928)
		(stroke
			(width 0.508)
			(type default)
		)
		(layer "In4.Cu")
	)
	(gr_line
		(start 166.490396 -5.975604)
		(end 167.125396 -5.975604)
		(stroke
			(width 0.508)
			(type default)
		)
		(layer "In4.Cu")
	)
	(gr_line
		(start 166.490396 -5.924804)
		(end 167.125396 -5.924804)
		(stroke
			(width 0.508)
			(type default)
		)
		(layer "In4.Cu")
	)
	(gr_line
		(start 166.490396 -5.875528)
		(end 167.125396 -5.875528)
		(stroke
			(width 0.508)
			(type default)
		)
		(layer "In4.Cu")
	)
	(gr_line
		(start 166.490396 -5.824728)
		(end 167.125396 -5.824728)
		(stroke
			(width 0.508)
			(type default)
		)
		(layer "In4.Cu")
	)
	(gr_line
		(start 166.490396 -3.95986)
		(end 167.125396 -3.95986)
		(stroke
			(width 0.508)
			(type default)
		)
		(layer "In4.Cu")
	)
	(gr_line
		(start 166.490396 -3.859784)
		(end 167.125396 -3.859784)
		(stroke
			(width 0.508)
			(type default)
		)
		(layer "In4.Cu")
	)
	(gr_line
		(start 166.490396 -1.77546)
		(end 167.125396 -1.77546)
		(stroke
			(width 0.508)
			(type default)
		)
		(layer "In4.Cu")
	)
	(gr_line
		(start 166.490396 -1.72466)
		(end 167.125396 -1.72466)
		(stroke
			(width 0.508)
			(type default)
		)
		(layer "In4.Cu")
	)
	(gr_line
		(start 166.490396 -1.675384)
		(end 167.125396 -1.675384)
		(stroke
			(width 0.508)
			(type default)
		)
		(layer "In4.Cu")
	)
	(gr_line
		(start 166.490396 -1.624584)
		(end 167.125396 -1.624584)
		(stroke
			(width 0.508)
			(type default)
		)
		(layer "In4.Cu")
	)
	(gr_line
		(start 166.515796 -10.429748)
		(end 167.150796 -10.429748)
		(stroke
			(width 0.508)
			(type default)
		)
		(layer "In4.Cu")
	)
	(gr_line
		(start 166.515796 -10.329672)
		(end 167.150796 -10.329672)
		(stroke
			(width 0.508)
			(type default)
		)
		(layer "In4.Cu")
	)
	(gr_line
		(start 166.515796 -6.229604)
		(end 167.150796 -6.229604)
		(stroke
			(width 0.508)
			(type default)
		)
		(layer "In4.Cu")
	)
	(gr_line
		(start 166.515796 -6.129528)
		(end 167.150796 -6.129528)
		(stroke
			(width 0.508)
			(type default)
		)
		(layer "In4.Cu")
	)
	(gr_line
		(start 166.515796 -2.02946)
		(end 167.150796 -2.02946)
		(stroke
			(width 0.508)
			(type default)
		)
		(layer "In4.Cu")
	)
	(gr_line
		(start 166.515796 -1.929384)
		(end 167.150796 -1.929384)
		(stroke
			(width 0.508)
			(type default)
		)
		(layer "In4.Cu")
	)
	(gr_line
		(start 166.541196 -12.385548)
		(end 166.541196 -10.124948)
		(stroke
			(width 0.254)
			(type default)
		)
		(layer "In4.Cu")
	)
	(gr_line
		(start 166.541196 -12.285472)
		(end 166.541196 -10.024872)
		(stroke
			(width 0.254)
			(type default)
		)
		(layer "In4.Cu")
	)
	(gr_line
		(start 166.541196 -12.233148)
		(end 167.176196 -12.233148)
		(stroke
			(width 0.508)
			(type default)
		)
		(layer "In4.Cu")
	)
	(gr_line
		(start 166.541196 -12.133072)
		(end 167.176196 -12.133072)
		(stroke
			(width 0.508)
			(type default)
		)
		(layer "In4.Cu")
	)
	(gr_line
		(start 166.541196 -10.124948)
		(end 167.176196 -10.124948)
		(stroke
			(width 0.254)
			(type default)
		)
		(layer "In4.Cu")
	)
	(gr_line
		(start 166.541196 -10.024872)
		(end 167.176196 -10.024872)
		(stroke
			(width 0.254)
			(type default)
		)
		(layer "In4.Cu")
	)
	(gr_line
		(start 166.541196 -8.185404)
		(end 166.541196 -5.924804)
		(stroke
			(width 0.254)
			(type default)
		)
		(layer "In4.Cu")
	)
	(gr_line
		(start 166.541196 -8.085328)
		(end 166.541196 -5.824728)
		(stroke
			(width 0.254)
			(type default)
		)
		(layer "In4.Cu")
	)
	(gr_line
		(start 166.541196 -8.033004)
		(end 167.176196 -8.033004)
		(stroke
			(width 0.508)
			(type default)
		)
		(layer "In4.Cu")
	)
	(gr_line
		(start 166.541196 -7.932928)
		(end 167.176196 -7.932928)
		(stroke
			(width 0.508)
			(type default)
		)
		(layer "In4.Cu")
	)
	(gr_line
		(start 166.541196 -5.924804)
		(end 167.176196 -5.924804)
		(stroke
			(width 0.254)
			(type default)
		)
		(layer "In4.Cu")
	)
	(gr_line
		(start 166.541196 -5.824728)
		(end 167.176196 -5.824728)
		(stroke
			(width 0.254)
			(type default)
		)
		(layer "In4.Cu")
	)
	(gr_line
		(start 166.541196 -3.98526)
		(end 166.541196 -1.72466)
		(stroke
			(width 0.254)
			(type default)
		)
		(layer "In4.Cu")
	)
	(gr_line
		(start 166.541196 -3.885184)
		(end 166.541196 -1.624584)
		(stroke
			(width 0.254)
			(type default)
		)
		(layer "In4.Cu")
	)
	(gr_line
		(start 166.541196 -3.83286)
		(end 167.176196 -3.83286)
		(stroke
			(width 0.508)
			(type default)
		)
		(layer "In4.Cu")
	)
	(gr_line
		(start 166.541196 -3.732784)
		(end 167.176196 -3.732784)
		(stroke
			(width 0.508)
			(type default)
		)
		(layer "In4.Cu")
	)
	(gr_line
		(start 166.541196 -1.72466)
		(end 167.176196 -1.72466)
		(stroke
			(width 0.254)
			(type default)
		)
		(layer "In4.Cu")
	)
	(gr_line
		(start 166.541196 -1.624584)
		(end 167.176196 -1.624584)
		(stroke
			(width 0.254)
			(type default)
		)
		(layer "In4.Cu")
	)
	(gr_line
		(start 166.566596 -12.080748)
		(end 167.201596 -12.080748)
		(stroke
			(width 0.508)
			(type default)
		)
		(layer "In4.Cu")
	)
	(gr_line
		(start 166.566596 -11.980672)
		(end 167.201596 -11.980672)
		(stroke
			(width 0.508)
			(type default)
		)
		(layer "In4.Cu")
	)
	(gr_line
		(start 166.566596 -7.880604)
		(end 167.201596 -7.880604)
		(stroke
			(width 0.508)
			(type default)
		)
		(layer "In4.Cu")
	)
	(gr_line
		(start 166.566596 -7.780528)
		(end 167.201596 -7.780528)
		(stroke
			(width 0.508)
			(type default)
		)
		(layer "In4.Cu")
	)
	(gr_line
		(start 166.566596 -3.68046)
		(end 167.201596 -3.68046)
		(stroke
			(width 0.508)
			(type default)
		)
		(layer "In4.Cu")
	)
	(gr_line
		(start 166.566596 -3.580384)
		(end 167.201596 -3.580384)
		(stroke
			(width 0.508)
			(type default)
		)
		(layer "In4.Cu")
	)
	(gr_line
		(start 166.591996 -12.360148)
		(end 167.226996 -12.360148)
		(stroke
			(width 0.508)
			(type default)
		)
		(layer "In4.Cu")
	)
	(gr_line
		(start 166.591996 -12.260072)
		(end 167.226996 -12.260072)
		(stroke
			(width 0.508)
			(type default)
		)
		(layer "In4.Cu")
	)
	(gr_line
		(start 166.591996 -9.947148)
		(end 167.430196 -9.947148)
		(stroke
			(width 0.2032)
			(type default)
		)
		(layer "In4.Cu")
	)
	(gr_line
		(start 166.591996 -9.847072)
		(end 167.430196 -9.847072)
		(stroke
			(width 0.2032)
			(type default)
		)
		(layer "In4.Cu")
	)
	(gr_line
		(start 166.591996 -8.160004)
		(end 167.226996 -8.160004)
		(stroke
			(width 0.508)
			(type default)
		)
		(layer "In4.Cu")
	)
	(gr_line
		(start 166.591996 -8.059928)
		(end 167.226996 -8.059928)
		(stroke
			(width 0.508)
			(type default)
		)
		(layer "In4.Cu")
	)
	(gr_line
		(start 166.591996 -5.747004)
		(end 167.430196 -5.747004)
		(stroke
			(width 0.2032)
			(type default)
		)
		(layer "In4.Cu")
	)
	(gr_line
		(start 166.591996 -5.646928)
		(end 167.430196 -5.646928)
		(stroke
			(width 0.2032)
			(type default)
		)
		(layer "In4.Cu")
	)
	(gr_line
		(start 166.591996 -3.95986)
		(end 167.226996 -3.95986)
		(stroke
			(width 0.508)
			(type default)
		)
		(layer "In4.Cu")
	)
	(gr_line
		(start 166.591996 -3.859784)
		(end 167.226996 -3.859784)
		(stroke
			(width 0.508)
			(type default)
		)
		(layer "In4.Cu")
	)
	(gr_line
		(start 166.591996 -1.54686)
		(end 167.430196 -1.54686)
		(stroke
			(width 0.2032)
			(type default)
		)
		(layer "In4.Cu")
	)
	(gr_line
		(start 166.591996 -1.446784)
		(end 167.430196 -1.446784)
		(stroke
			(width 0.2032)
			(type default)
		)
		(layer "In4.Cu")
	)
	(gr_line
		(start 166.617396 -12.360148)
		(end 166.617396 -10.175748)
		(stroke
			(width 0.254)
			(type default)
		)
		(layer "In4.Cu")
	)
	(gr_line
		(start 166.617396 -12.260072)
		(end 166.617396 -10.075672)
		(stroke
			(width 0.254)
			(type default)
		)
		(layer "In4.Cu")
	)
	(gr_line
		(start 166.617396 -10.175748)
		(end 167.099996 -10.175748)
		(stroke
			(width 0.254)
			(type default)
		)
		(layer "In4.Cu")
	)
	(gr_line
		(start 166.617396 -10.075672)
		(end 167.099996 -10.075672)
		(stroke
			(width 0.254)
			(type default)
		)
		(layer "In4.Cu")
	)
	(gr_line
		(start 166.617396 -9.997948)
		(end 167.353996 -9.997948)
		(stroke
			(width 0.254)
			(type default)
		)
		(layer "In4.Cu")
	)
	(gr_line
		(start 166.617396 -9.897872)
		(end 167.353996 -9.897872)
		(stroke
			(width 0.254)
			(type default)
		)
		(layer "In4.Cu")
	)
	(gr_line
		(start 166.617396 -8.160004)
		(end 166.617396 -5.975604)
		(stroke
			(width 0.254)
			(type default)
		)
		(layer "In4.Cu")
	)
	(gr_line
		(start 166.617396 -8.059928)
		(end 166.617396 -5.875528)
		(stroke
			(width 0.254)
			(type default)
		)
		(layer "In4.Cu")
	)
	(gr_line
		(start 166.617396 -5.975604)
		(end 167.099996 -5.975604)
		(stroke
			(width 0.254)
			(type default)
		)
		(layer "In4.Cu")
	)
	(gr_line
		(start 166.617396 -5.875528)
		(end 167.099996 -5.875528)
		(stroke
			(width 0.254)
			(type default)
		)
		(layer "In4.Cu")
	)
	(gr_line
		(start 166.617396 -5.797804)
		(end 167.353996 -5.797804)
		(stroke
			(width 0.254)
			(type default)
		)
		(layer "In4.Cu")
	)
	(gr_line
		(start 166.617396 -5.697728)
		(end 167.353996 -5.697728)
		(stroke
			(width 0.254)
			(type default)
		)
		(layer "In4.Cu")
	)
	(gr_line
		(start 166.617396 -3.95986)
		(end 166.617396 -1.77546)
		(stroke
			(width 0.254)
			(type default)
		)
		(layer "In4.Cu")
	)
	(gr_line
		(start 166.617396 -3.859784)
		(end 166.617396 -1.675384)
		(stroke
			(width 0.254)
			(type default)
		)
		(layer "In4.Cu")
	)
	(gr_line
		(start 166.617396 -1.77546)
		(end 167.099996 -1.77546)
		(stroke
			(width 0.254)
			(type default)
		)
		(layer "In4.Cu")
	)
	(gr_line
		(start 166.617396 -1.675384)
		(end 167.099996 -1.675384)
		(stroke
			(width 0.254)
			(type default)
		)
		(layer "In4.Cu")
	)
	(gr_line
		(start 166.617396 -1.59766)
		(end 167.353996 -1.59766)
		(stroke
			(width 0.254)
			(type default)
		)
		(layer "In4.Cu")
	)
	(gr_line
		(start 166.617396 -1.497584)
		(end 167.353996 -1.497584)
		(stroke
			(width 0.254)
			(type default)
		)
		(layer "In4.Cu")
	)
	(gr_line
		(start 166.635938 -10.110978)
		(end 167.270938 -10.110978)
		(stroke
			(width 0.508)
			(type default)
		)
		(layer "In4.Cu")
	)
	(gr_line
		(start 166.635938 -10.010902)
		(end 167.270938 -10.010902)
		(stroke
			(width 0.508)
			(type default)
		)
		(layer "In4.Cu")
	)
	(gr_line
		(start 166.635938 -5.910834)
		(end 167.270938 -5.910834)
		(stroke
			(width 0.508)
			(type default)
		)
		(layer "In4.Cu")
	)
	(gr_line
		(start 166.635938 -5.810758)
		(end 167.270938 -5.810758)
		(stroke
			(width 0.508)
			(type default)
		)
		(layer "In4.Cu")
	)
	(gr_line
		(start 166.635938 -1.71069)
		(end 167.270938 -1.71069)
		(stroke
			(width 0.508)
			(type default)
		)
		(layer "In4.Cu")
	)
	(gr_line
		(start 166.635938 -1.610614)
		(end 167.270938 -1.610614)
		(stroke
			(width 0.508)
			(type default)
		)
		(layer "In4.Cu")
	)
	(gr_line
		(start 166.642796 -12.360148)
		(end 167.277796 -12.360148)
		(stroke
			(width 0.508)
			(type default)
		)
		(layer "In4.Cu")
	)
	(gr_line
		(start 166.642796 -12.260072)
		(end 167.277796 -12.260072)
		(stroke
			(width 0.508)
			(type default)
		)
		(layer "In4.Cu")
	)
	(gr_line
		(start 166.642796 -12.233148)
		(end 166.642796 -10.251948)
		(stroke
			(width 0.762)
			(type default)
		)
		(layer "In4.Cu")
	)
	(gr_line
		(start 166.642796 -12.133072)
		(end 166.642796 -10.151872)
		(stroke
			(width 0.762)
			(type default)
		)
		(layer "In4.Cu")
	)
	(gr_line
		(start 166.642796 -10.251948)
		(end 167.277796 -10.251948)
		(stroke
			(width 0.508)
			(type default)
		)
		(layer "In4.Cu")
	)
	(gr_line
		(start 166.642796 -10.151872)
		(end 167.277796 -10.151872)
		(stroke
			(width 0.508)
			(type default)
		)
		(layer "In4.Cu")
	)
	(gr_line
		(start 166.642796 -8.160004)
		(end 167.277796 -8.160004)
		(stroke
			(width 0.508)
			(type default)
		)
		(layer "In4.Cu")
	)
	(gr_line
		(start 166.642796 -8.059928)
		(end 167.277796 -8.059928)
		(stroke
			(width 0.508)
			(type default)
		)
		(layer "In4.Cu")
	)
	(gr_line
		(start 166.642796 -8.033004)
		(end 166.642796 -6.051804)
		(stroke
			(width 0.762)
			(type default)
		)
		(layer "In4.Cu")
	)
	(gr_line
		(start 166.642796 -7.932928)
		(end 166.642796 -5.951728)
		(stroke
			(width 0.762)
			(type default)
		)
		(layer "In4.Cu")
	)
	(gr_line
		(start 166.642796 -6.051804)
		(end 167.277796 -6.051804)
		(stroke
			(width 0.508)
			(type default)
		)
		(layer "In4.Cu")
	)
	(gr_line
		(start 166.642796 -5.951728)
		(end 167.277796 -5.951728)
		(stroke
			(width 0.508)
			(type default)
		)
		(layer "In4.Cu")
	)
	(gr_line
		(start 166.642796 -3.95986)
		(end 167.277796 -3.95986)
		(stroke
			(width 0.508)
			(type default)
		)
		(layer "In4.Cu")
	)
	(gr_line
		(start 166.642796 -3.859784)
		(end 167.277796 -3.859784)
		(stroke
			(width 0.508)
			(type default)
		)
		(layer "In4.Cu")
	)
	(gr_line
		(start 166.642796 -3.83286)
		(end 166.642796 -1.85166)
		(stroke
			(width 0.762)
			(type default)
		)
		(layer "In4.Cu")
	)
	(gr_line
		(start 166.642796 -3.732784)
		(end 166.642796 -1.751584)
		(stroke
			(width 0.762)
			(type default)
		)
		(layer "In4.Cu")
	)
	(gr_line
		(start 166.642796 -1.85166)
		(end 167.277796 -1.85166)
		(stroke
			(width 0.508)
			(type default)
		)
		(layer "In4.Cu")
	)
	(gr_line
		(start 166.642796 -1.751584)
		(end 167.277796 -1.751584)
		(stroke
			(width 0.508)
			(type default)
		)
		(layer "In4.Cu")
	)
	(gr_line
		(start 166.693596 -12.283948)
		(end 166.693596 -10.251948)
		(stroke
			(width 0.254)
			(type default)
		)
		(layer "In4.Cu")
	)
	(gr_line
		(start 166.693596 -12.183872)
		(end 166.693596 -10.151872)
		(stroke
			(width 0.254)
			(type default)
		)
		(layer "In4.Cu")
	)
	(gr_line
		(start 166.693596 -10.251948)
		(end 167.023796 -10.251948)
		(stroke
			(width 0.254)
			(type default)
		)
		(layer "In4.Cu")
	)
	(gr_line
		(start 166.693596 -10.151872)
		(end 167.023796 -10.151872)
		(stroke
			(width 0.254)
			(type default)
		)
		(layer "In4.Cu")
	)
	(gr_line
		(start 166.693596 -8.083804)
		(end 166.693596 -6.051804)
		(stroke
			(width 0.254)
			(type default)
		)
		(layer "In4.Cu")
	)
	(gr_line
		(start 166.693596 -7.983728)
		(end 166.693596 -5.951728)
		(stroke
			(width 0.254)
			(type default)
		)
		(layer "In4.Cu")
	)
	(gr_line
		(start 166.693596 -6.051804)
		(end 167.023796 -6.051804)
		(stroke
			(width 0.254)
			(type default)
		)
		(layer "In4.Cu")
	)
	(gr_line
		(start 166.693596 -5.951728)
		(end 167.023796 -5.951728)
		(stroke
			(width 0.254)
			(type default)
		)
		(layer "In4.Cu")
	)
	(gr_line
		(start 166.693596 -3.88366)
		(end 166.693596 -1.85166)
		(stroke
			(width 0.254)
			(type default)
		)
		(layer "In4.Cu")
	)
	(gr_line
		(start 166.693596 -3.783584)
		(end 166.693596 -1.751584)
		(stroke
			(width 0.254)
			(type default)
		)
		(layer "In4.Cu")
	)
	(gr_line
		(start 166.693596 -1.85166)
		(end 167.023796 -1.85166)
		(stroke
			(width 0.254)
			(type default)
		)
		(layer "In4.Cu")
	)
	(gr_line
		(start 166.693596 -1.751584)
		(end 167.023796 -1.751584)
		(stroke
			(width 0.254)
			(type default)
		)
		(layer "In4.Cu")
	)
	(gr_line
		(start 166.795196 -12.207748)
		(end 166.795196 -10.404348)
		(stroke
			(width 0.254)
			(type default)
		)
		(layer "In4.Cu")
	)
	(gr_line
		(start 166.795196 -12.207748)
		(end 166.795196 -10.226548)
		(stroke
			(width 0.762)
			(type default)
		)
		(layer "In4.Cu")
	)
	(gr_line
		(start 166.795196 -12.107672)
		(end 166.795196 -10.304272)
		(stroke
			(width 0.254)
			(type default)
		)
		(layer "In4.Cu")
	)
	(gr_line
		(start 166.795196 -12.107672)
		(end 166.795196 -10.126472)
		(stroke
			(width 0.762)
			(type default)
		)
		(layer "In4.Cu")
	)
	(gr_line
		(start 166.795196 -10.404348)
		(end 166.896796 -10.404348)
		(stroke
			(width 0.254)
			(type default)
		)
		(layer "In4.Cu")
	)
	(gr_line
		(start 166.795196 -10.304272)
		(end 166.896796 -10.304272)
		(stroke
			(width 0.254)
			(type default)
		)
		(layer "In4.Cu")
	)
	(gr_line
		(start 166.795196 -8.007604)
		(end 166.795196 -6.204204)
		(stroke
			(width 0.254)
			(type default)
		)
		(layer "In4.Cu")
	)
	(gr_line
		(start 166.795196 -8.007604)
		(end 166.795196 -6.026404)
		(stroke
			(width 0.762)
			(type default)
		)
		(layer "In4.Cu")
	)
	(gr_line
		(start 166.795196 -7.907528)
		(end 166.795196 -6.104128)
		(stroke
			(width 0.254)
			(type default)
		)
		(layer "In4.Cu")
	)
	(gr_line
		(start 166.795196 -7.907528)
		(end 166.795196 -5.926328)
		(stroke
			(width 0.762)
			(type default)
		)
		(layer "In4.Cu")
	)
	(gr_line
		(start 166.795196 -6.204204)
		(end 166.896796 -6.204204)
		(stroke
			(width 0.254)
			(type default)
		)
		(layer "In4.Cu")
	)
	(gr_line
		(start 166.795196 -6.104128)
		(end 166.896796 -6.104128)
		(stroke
			(width 0.254)
			(type default)
		)
		(layer "In4.Cu")
	)
	(gr_line
		(start 166.795196 -3.80746)
		(end 166.795196 -2.00406)
		(stroke
			(width 0.254)
			(type default)
		)
		(layer "In4.Cu")
	)
	(gr_line
		(start 166.795196 -3.80746)
		(end 166.795196 -1.82626)
		(stroke
			(width 0.762)
			(type default)
		)
		(layer "In4.Cu")
	)
	(gr_line
		(start 166.795196 -3.707384)
		(end 166.795196 -1.903984)
		(stroke
			(width 0.254)
			(type default)
		)
		(layer "In4.Cu")
	)
	(gr_line
		(start 166.795196 -3.707384)
		(end 166.795196 -1.726184)
		(stroke
			(width 0.762)
			(type default)
		)
		(layer "In4.Cu")
	)
	(gr_line
		(start 166.795196 -2.00406)
		(end 166.896796 -2.00406)
		(stroke
			(width 0.254)
			(type default)
		)
		(layer "In4.Cu")
	)
	(gr_line
		(start 166.795196 -1.903984)
		(end 166.896796 -1.903984)
		(stroke
			(width 0.254)
			(type default)
		)
		(layer "In4.Cu")
	)
	(gr_line
		(start 166.896796 -12.309348)
		(end 166.845996 -12.309348)
		(stroke
			(width 0.254)
			(type default)
		)
		(layer "In4.Cu")
	)
	(gr_line
		(start 166.896796 -12.209272)
		(end 166.845996 -12.209272)
		(stroke
			(width 0.254)
			(type default)
		)
		(layer "In4.Cu")
	)
	(gr_line
		(start 166.896796 -10.404348)
		(end 166.896796 -12.309348)
		(stroke
			(width 0.254)
			(type default)
		)
		(layer "In4.Cu")
	)
	(gr_line
		(start 166.896796 -10.304272)
		(end 166.896796 -12.209272)
		(stroke
			(width 0.254)
			(type default)
		)
		(layer "In4.Cu")
	)
	(gr_line
		(start 166.896796 -8.109204)
		(end 166.845996 -8.109204)
		(stroke
			(width 0.254)
			(type default)
		)
		(layer "In4.Cu")
	)
	(gr_line
		(start 166.896796 -8.009128)
		(end 166.845996 -8.009128)
		(stroke
			(width 0.254)
			(type default)
		)
		(layer "In4.Cu")
	)
	(gr_line
		(start 166.896796 -6.204204)
		(end 166.896796 -8.109204)
		(stroke
			(width 0.254)
			(type default)
		)
		(layer "In4.Cu")
	)
	(gr_line
		(start 166.896796 -6.104128)
		(end 166.896796 -8.009128)
		(stroke
			(width 0.254)
			(type default)
		)
		(layer "In4.Cu")
	)
	(gr_line
		(start 166.896796 -3.90906)
		(end 166.845996 -3.90906)
		(stroke
			(width 0.254)
			(type default)
		)
		(layer "In4.Cu")
	)
	(gr_line
		(start 166.896796 -3.808984)
		(end 166.845996 -3.808984)
		(stroke
			(width 0.254)
			(type default)
		)
		(layer "In4.Cu")
	)
	(gr_line
		(start 166.896796 -2.00406)
		(end 166.896796 -3.90906)
		(stroke
			(width 0.254)
			(type default)
		)
		(layer "In4.Cu")
	)
	(gr_line
		(start 166.896796 -1.903984)
		(end 166.896796 -3.808984)
		(stroke
			(width 0.254)
			(type default)
		)
		(layer "In4.Cu")
	)
	(gr_line
		(start 166.947596 -12.233148)
		(end 166.947596 -10.251948)
		(stroke
			(width 0.762)
			(type default)
		)
		(layer "In4.Cu")
	)
	(gr_line
		(start 166.947596 -12.133072)
		(end 166.947596 -10.151872)
		(stroke
			(width 0.762)
			(type default)
		)
		(layer "In4.Cu")
	)
	(gr_line
		(start 166.947596 -8.033004)
		(end 166.947596 -6.051804)
		(stroke
			(width 0.762)
			(type default)
		)
		(layer "In4.Cu")
	)
	(gr_line
		(start 166.947596 -7.932928)
		(end 166.947596 -5.951728)
		(stroke
			(width 0.762)
			(type default)
		)
		(layer "In4.Cu")
	)
	(gr_line
		(start 166.947596 -3.83286)
		(end 166.947596 -1.85166)
		(stroke
			(width 0.762)
			(type default)
		)
		(layer "In4.Cu")
	)
	(gr_line
		(start 166.947596 -3.732784)
		(end 166.947596 -1.751584)
		(stroke
			(width 0.762)
			(type default)
		)
		(layer "In4.Cu")
	)
	(gr_line
		(start 167.023796 -12.207748)
		(end 166.795196 -12.207748)
		(stroke
			(width 0.254)
			(type default)
		)
		(layer "In4.Cu")
	)
	(gr_line
		(start 167.023796 -12.107672)
		(end 166.795196 -12.107672)
		(stroke
			(width 0.254)
			(type default)
		)
		(layer "In4.Cu")
	)
	(gr_line
		(start 167.023796 -10.251948)
		(end 167.023796 -12.207748)
		(stroke
			(width 0.254)
			(type default)
		)
		(layer "In4.Cu")
	)
	(gr_line
		(start 167.023796 -10.151872)
		(end 167.023796 -12.107672)
		(stroke
			(width 0.254)
			(type default)
		)
		(layer "In4.Cu")
	)
	(gr_line
		(start 167.023796 -8.007604)
		(end 166.795196 -8.007604)
		(stroke
			(width 0.254)
			(type default)
		)
		(layer "In4.Cu")
	)
	(gr_line
		(start 167.023796 -7.907528)
		(end 166.795196 -7.907528)
		(stroke
			(width 0.254)
			(type default)
		)
		(layer "In4.Cu")
	)
	(gr_line
		(start 167.023796 -6.051804)
		(end 167.023796 -8.007604)
		(stroke
			(width 0.254)
			(type default)
		)
		(layer "In4.Cu")
	)
	(gr_line
		(start 167.023796 -5.951728)
		(end 167.023796 -7.907528)
		(stroke
			(width 0.254)
			(type default)
		)
		(layer "In4.Cu")
	)
	(gr_line
		(start 167.023796 -3.80746)
		(end 166.795196 -3.80746)
		(stroke
			(width 0.254)
			(type default)
		)
		(layer "In4.Cu")
	)
	(gr_line
		(start 167.023796 -3.707384)
		(end 166.795196 -3.707384)
		(stroke
			(width 0.254)
			(type default)
		)
		(layer "In4.Cu")
	)
	(gr_line
		(start 167.023796 -1.85166)
		(end 167.023796 -3.80746)
		(stroke
			(width 0.254)
			(type default)
		)
		(layer "In4.Cu")
	)
	(gr_line
		(start 167.023796 -1.751584)
		(end 167.023796 -3.707384)
		(stroke
			(width 0.254)
			(type default)
		)
		(layer "In4.Cu")
	)
	(gr_line
		(start 167.074596 -12.563348)
		(end 167.074596 -12.512548)
		(stroke
			(width 0.1016)
			(type default)
		)
		(layer "In4.Cu")
	)
	(gr_line
		(start 167.074596 -12.563348)
		(end 167.480996 -12.563348)
		(stroke
			(width 0.1016)
			(type default)
		)
		(layer "In4.Cu")
	)
	(gr_line
		(start 167.074596 -12.512548)
		(end 166.312596 -12.512548)
		(stroke
			(width 0.1016)
			(type default)
		)
		(layer "In4.Cu")
	)
	(gr_line
		(start 167.074596 -12.463272)
		(end 167.074596 -12.412472)
		(stroke
			(width 0.1016)
			(type default)
		)
		(layer "In4.Cu")
	)
	(gr_line
		(start 167.074596 -12.463272)
		(end 167.480996 -12.463272)
		(stroke
			(width 0.1016)
			(type default)
		)
		(layer "In4.Cu")
	)
	(gr_line
		(start 167.074596 -12.412472)
		(end 166.312596 -12.412472)
		(stroke
			(width 0.1016)
			(type default)
		)
		(layer "In4.Cu")
	)
	(gr_line
		(start 167.074596 -12.233148)
		(end 167.074596 -10.251948)
		(stroke
			(width 0.762)
			(type default)
		)
		(layer "In4.Cu")
	)
	(gr_line
		(start 167.074596 -12.133072)
		(end 167.074596 -10.151872)
		(stroke
			(width 0.762)
			(type default)
		)
		(layer "In4.Cu")
	)
	(gr_line
		(start 167.074596 -8.363204)
		(end 167.074596 -8.312404)
		(stroke
			(width 0.1016)
			(type default)
		)
		(layer "In4.Cu")
	)
	(gr_line
		(start 167.074596 -8.363204)
		(end 167.480996 -8.363204)
		(stroke
			(width 0.1016)
			(type default)
		)
		(layer "In4.Cu")
	)
	(gr_line
		(start 167.074596 -8.312404)
		(end 166.312596 -8.312404)
		(stroke
			(width 0.1016)
			(type default)
		)
		(layer "In4.Cu")
	)
	(gr_line
		(start 167.074596 -8.263128)
		(end 167.074596 -8.212328)
		(stroke
			(width 0.1016)
			(type default)
		)
		(layer "In4.Cu")
	)
	(gr_line
		(start 167.074596 -8.263128)
		(end 167.480996 -8.263128)
		(stroke
			(width 0.1016)
			(type default)
		)
		(layer "In4.Cu")
	)
	(gr_line
		(start 167.074596 -8.212328)
		(end 166.312596 -8.212328)
		(stroke
			(width 0.1016)
			(type default)
		)
		(layer "In4.Cu")
	)
	(gr_line
		(start 167.074596 -8.033004)
		(end 167.074596 -6.051804)
		(stroke
			(width 0.762)
			(type default)
		)
		(layer "In4.Cu")
	)
	(gr_line
		(start 167.074596 -7.932928)
		(end 167.074596 -5.951728)
		(stroke
			(width 0.762)
			(type default)
		)
		(layer "In4.Cu")
	)
	(gr_line
		(start 167.074596 -4.16306)
		(end 167.074596 -4.11226)
		(stroke
			(width 0.1016)
			(type default)
		)
		(layer "In4.Cu")
	)
	(gr_line
		(start 167.074596 -4.16306)
		(end 167.480996 -4.16306)
		(stroke
			(width 0.1016)
			(type default)
		)
		(layer "In4.Cu")
	)
	(gr_line
		(start 167.074596 -4.11226)
		(end 166.312596 -4.11226)
		(stroke
			(width 0.1016)
			(type default)
		)
		(layer "In4.Cu")
	)
	(gr_line
		(start 167.074596 -4.062984)
		(end 167.074596 -4.012184)
		(stroke
			(width 0.1016)
			(type default)
		)
		(layer "In4.Cu")
	)
	(gr_line
		(start 167.074596 -4.062984)
		(end 167.480996 -4.062984)
		(stroke
			(width 0.1016)
			(type default)
		)
		(layer "In4.Cu")
	)
	(gr_line
		(start 167.074596 -4.012184)
		(end 166.312596 -4.012184)
		(stroke
			(width 0.1016)
			(type default)
		)
		(layer "In4.Cu")
	)
	(gr_line
		(start 167.074596 -3.83286)
		(end 167.074596 -1.85166)
		(stroke
			(width 0.762)
			(type default)
		)
		(layer "In4.Cu")
	)
	(gr_line
		(start 167.074596 -3.732784)
		(end 167.074596 -1.751584)
		(stroke
			(width 0.762)
			(type default)
		)
		(layer "In4.Cu")
	)
	(gr_line
		(start 167.099996 -12.283948)
		(end 166.693596 -12.283948)
		(stroke
			(width 0.254)
			(type default)
		)
		(layer "In4.Cu")
	)
	(gr_line
		(start 167.099996 -12.183872)
		(end 166.693596 -12.183872)
		(stroke
			(width 0.254)
			(type default)
		)
		(layer "In4.Cu")
	)
	(gr_line
		(start 167.099996 -10.175748)
		(end 167.099996 -12.283948)
		(stroke
			(width 0.254)
			(type default)
		)
		(layer "In4.Cu")
	)
	(gr_line
		(start 167.099996 -10.075672)
		(end 167.099996 -12.183872)
		(stroke
			(width 0.254)
			(type default)
		)
		(layer "In4.Cu")
	)
	(gr_line
		(start 167.099996 -8.083804)
		(end 166.693596 -8.083804)
		(stroke
			(width 0.254)
			(type default)
		)
		(layer "In4.Cu")
	)
	(gr_line
		(start 167.099996 -7.983728)
		(end 166.693596 -7.983728)
		(stroke
			(width 0.254)
			(type default)
		)
		(layer "In4.Cu")
	)
	(gr_line
		(start 167.099996 -5.975604)
		(end 167.099996 -8.083804)
		(stroke
			(width 0.254)
			(type default)
		)
		(layer "In4.Cu")
	)
	(gr_line
		(start 167.099996 -5.875528)
		(end 167.099996 -7.983728)
		(stroke
			(width 0.254)
			(type default)
		)
		(layer "In4.Cu")
	)
	(gr_line
		(start 167.099996 -3.88366)
		(end 166.693596 -3.88366)
		(stroke
			(width 0.254)
			(type default)
		)
		(layer "In4.Cu")
	)
	(gr_line
		(start 167.099996 -3.783584)
		(end 166.693596 -3.783584)
		(stroke
			(width 0.254)
			(type default)
		)
		(layer "In4.Cu")
	)
	(gr_line
		(start 167.099996 -1.77546)
		(end 167.099996 -3.88366)
		(stroke
			(width 0.254)
			(type default)
		)
		(layer "In4.Cu")
	)
	(gr_line
		(start 167.099996 -1.675384)
		(end 167.099996 -3.783584)
		(stroke
			(width 0.254)
			(type default)
		)
		(layer "In4.Cu")
	)
	(gr_line
		(start 167.150796 -12.233148)
		(end 167.150796 -10.251948)
		(stroke
			(width 0.762)
			(type default)
		)
		(layer "In4.Cu")
	)
	(gr_line
		(start 167.150796 -12.133072)
		(end 167.150796 -10.151872)
		(stroke
			(width 0.762)
			(type default)
		)
		(layer "In4.Cu")
	)
	(gr_line
		(start 167.150796 -8.033004)
		(end 167.150796 -6.051804)
		(stroke
			(width 0.762)
			(type default)
		)
		(layer "In4.Cu")
	)
	(gr_line
		(start 167.150796 -7.932928)
		(end 167.150796 -5.951728)
		(stroke
			(width 0.762)
			(type default)
		)
		(layer "In4.Cu")
	)
	(gr_line
		(start 167.150796 -3.83286)
		(end 167.150796 -1.85166)
		(stroke
			(width 0.762)
			(type default)
		)
		(layer "In4.Cu")
	)
	(gr_line
		(start 167.150796 -3.732784)
		(end 167.150796 -1.751584)
		(stroke
			(width 0.762)
			(type default)
		)
		(layer "In4.Cu")
	)
	(gr_line
		(start 167.176196 -12.360148)
		(end 166.617396 -12.360148)
		(stroke
			(width 0.254)
			(type default)
		)
		(layer "In4.Cu")
	)
	(gr_line
		(start 167.176196 -12.260072)
		(end 166.617396 -12.260072)
		(stroke
			(width 0.254)
			(type default)
		)
		(layer "In4.Cu")
	)
	(gr_line
		(start 167.176196 -10.124948)
		(end 167.176196 -12.360148)
		(stroke
			(width 0.254)
			(type default)
		)
		(layer "In4.Cu")
	)
	(gr_line
		(start 167.176196 -10.024872)
		(end 167.176196 -12.260072)
		(stroke
			(width 0.254)
			(type default)
		)
		(layer "In4.Cu")
	)
	(gr_line
		(start 167.176196 -8.160004)
		(end 166.617396 -8.160004)
		(stroke
			(width 0.254)
			(type default)
		)
		(layer "In4.Cu")
	)
	(gr_line
		(start 167.176196 -8.059928)
		(end 166.617396 -8.059928)
		(stroke
			(width 0.254)
			(type default)
		)
		(layer "In4.Cu")
	)
	(gr_line
		(start 167.176196 -5.924804)
		(end 167.176196 -8.160004)
		(stroke
			(width 0.254)
			(type default)
		)
		(layer "In4.Cu")
	)
	(gr_line
		(start 167.176196 -5.824728)
		(end 167.176196 -8.059928)
		(stroke
			(width 0.254)
			(type default)
		)
		(layer "In4.Cu")
	)
	(gr_line
		(start 167.176196 -3.95986)
		(end 166.617396 -3.95986)
		(stroke
			(width 0.254)
			(type default)
		)
		(layer "In4.Cu")
	)
	(gr_line
		(start 167.176196 -3.859784)
		(end 166.617396 -3.859784)
		(stroke
			(width 0.254)
			(type default)
		)
		(layer "In4.Cu")
	)
	(gr_line
		(start 167.176196 -1.72466)
		(end 167.176196 -3.95986)
		(stroke
			(width 0.254)
			(type default)
		)
		(layer "In4.Cu")
	)
	(gr_line
		(start 167.176196 -1.624584)
		(end 167.176196 -3.859784)
		(stroke
			(width 0.254)
			(type default)
		)
		(layer "In4.Cu")
	)
	(gr_line
		(start 167.252396 -12.385548)
		(end 166.541196 -12.385548)
		(stroke
			(width 0.254)
			(type default)
		)
		(layer "In4.Cu")
	)
	(gr_line
		(start 167.252396 -12.285472)
		(end 166.541196 -12.285472)
		(stroke
			(width 0.254)
			(type default)
		)
		(layer "In4.Cu")
	)
	(gr_line
		(start 167.252396 -10.048748)
		(end 167.252396 -12.385548)
		(stroke
			(width 0.254)
			(type default)
		)
		(layer "In4.Cu")
	)
	(gr_line
		(start 167.252396 -9.948672)
		(end 167.252396 -12.285472)
		(stroke
			(width 0.254)
			(type default)
		)
		(layer "In4.Cu")
	)
	(gr_line
		(start 167.252396 -8.185404)
		(end 166.541196 -8.185404)
		(stroke
			(width 0.254)
			(type default)
		)
		(layer "In4.Cu")
	)
	(gr_line
		(start 167.252396 -8.085328)
		(end 166.541196 -8.085328)
		(stroke
			(width 0.254)
			(type default)
		)
		(layer "In4.Cu")
	)
	(gr_line
		(start 167.252396 -5.848604)
		(end 167.252396 -8.185404)
		(stroke
			(width 0.254)
			(type default)
		)
		(layer "In4.Cu")
	)
	(gr_line
		(start 167.252396 -5.748528)
		(end 167.252396 -8.085328)
		(stroke
			(width 0.254)
			(type default)
		)
		(layer "In4.Cu")
	)
	(gr_line
		(start 167.252396 -3.98526)
		(end 166.541196 -3.98526)
		(stroke
			(width 0.254)
			(type default)
		)
		(layer "In4.Cu")
	)
	(gr_line
		(start 167.252396 -3.885184)
		(end 166.541196 -3.885184)
		(stroke
			(width 0.254)
			(type default)
		)
		(layer "In4.Cu")
	)
	(gr_line
		(start 167.252396 -1.64846)
		(end 167.252396 -3.98526)
		(stroke
			(width 0.254)
			(type default)
		)
		(layer "In4.Cu")
	)
	(gr_line
		(start 167.252396 -1.548384)
		(end 167.252396 -3.885184)
		(stroke
			(width 0.254)
			(type default)
		)
		(layer "In4.Cu")
	)
	(gr_line
		(start 167.277796 -12.512548)
		(end 166.287196 -12.512548)
		(stroke
			(width 0.1016)
			(type default)
		)
		(layer "In4.Cu")
	)
	(gr_line
		(start 167.277796 -12.436348)
		(end 166.464996 -12.436348)
		(stroke
			(width 0.254)
			(type default)
		)
		(layer "In4.Cu")
	)
	(gr_line
		(start 167.277796 -12.412472)
		(end 166.287196 -12.412472)
		(stroke
			(width 0.1016)
			(type default)
		)
		(layer "In4.Cu")
	)
	(gr_line
		(start 167.277796 -12.336272)
		(end 166.464996 -12.336272)
		(stroke
			(width 0.254)
			(type default)
		)
		(layer "In4.Cu")
	)
	(gr_line
		(start 167.277796 -10.023348)
		(end 167.277796 -12.436348)
		(stroke
			(width 0.254)
			(type default)
		)
		(layer "In4.Cu")
	)
	(gr_line
		(start 167.277796 -9.923272)
		(end 167.277796 -12.336272)
		(stroke
			(width 0.254)
			(type default)
		)
		(layer "In4.Cu")
	)
	(gr_line
		(start 167.277796 -8.312404)
		(end 166.287196 -8.312404)
		(stroke
			(width 0.1016)
			(type default)
		)
		(layer "In4.Cu")
	)
	(gr_line
		(start 167.277796 -8.236204)
		(end 166.464996 -8.236204)
		(stroke
			(width 0.254)
			(type default)
		)
		(layer "In4.Cu")
	)
	(gr_line
		(start 167.277796 -8.212328)
		(end 166.287196 -8.212328)
		(stroke
			(width 0.1016)
			(type default)
		)
		(layer "In4.Cu")
	)
	(gr_line
		(start 167.277796 -8.136128)
		(end 166.464996 -8.136128)
		(stroke
			(width 0.254)
			(type default)
		)
		(layer "In4.Cu")
	)
	(gr_line
		(start 167.277796 -5.823204)
		(end 167.277796 -8.236204)
		(stroke
			(width 0.254)
			(type default)
		)
		(layer "In4.Cu")
	)
	(gr_line
		(start 167.277796 -5.723128)
		(end 167.277796 -8.136128)
		(stroke
			(width 0.254)
			(type default)
		)
		(layer "In4.Cu")
	)
	(gr_line
		(start 167.277796 -4.11226)
		(end 166.287196 -4.11226)
		(stroke
			(width 0.1016)
			(type default)
		)
		(layer "In4.Cu")
	)
	(gr_line
		(start 167.277796 -4.03606)
		(end 166.464996 -4.03606)
		(stroke
			(width 0.254)
			(type default)
		)
		(layer "In4.Cu")
	)
	(gr_line
		(start 167.277796 -4.012184)
		(end 166.287196 -4.012184)
		(stroke
			(width 0.1016)
			(type default)
		)
		(layer "In4.Cu")
	)
	(gr_line
		(start 167.277796 -3.935984)
		(end 166.464996 -3.935984)
		(stroke
			(width 0.254)
			(type default)
		)
		(layer "In4.Cu")
	)
	(gr_line
		(start 167.277796 -1.62306)
		(end 167.277796 -4.03606)
		(stroke
			(width 0.254)
			(type default)
		)
		(layer "In4.Cu")
	)
	(gr_line
		(start 167.277796 -1.522984)
		(end 167.277796 -3.935984)
		(stroke
			(width 0.254)
			(type default)
		)
		(layer "In4.Cu")
	)
	(gr_line
		(start 167.303196 -12.461748)
		(end 166.439596 -12.461748)
		(stroke
			(width 0.254)
			(type default)
		)
		(layer "In4.Cu")
	)
	(gr_line
		(start 167.303196 -12.361672)
		(end 166.439596 -12.361672)
		(stroke
			(width 0.254)
			(type default)
		)
		(layer "In4.Cu")
	)
	(gr_line
		(start 167.303196 -9.997948)
		(end 167.303196 -12.461748)
		(stroke
			(width 0.254)
			(type default)
		)
		(layer "In4.Cu")
	)
	(gr_line
		(start 167.303196 -9.897872)
		(end 167.303196 -12.361672)
		(stroke
			(width 0.254)
			(type default)
		)
		(layer "In4.Cu")
	)
	(gr_line
		(start 167.303196 -8.261604)
		(end 166.439596 -8.261604)
		(stroke
			(width 0.254)
			(type default)
		)
		(layer "In4.Cu")
	)
	(gr_line
		(start 167.303196 -8.161528)
		(end 166.439596 -8.161528)
		(stroke
			(width 0.254)
			(type default)
		)
		(layer "In4.Cu")
	)
	(gr_line
		(start 167.303196 -5.797804)
		(end 167.303196 -8.261604)
		(stroke
			(width 0.254)
			(type default)
		)
		(layer "In4.Cu")
	)
	(gr_line
		(start 167.303196 -5.697728)
		(end 167.303196 -8.161528)
		(stroke
			(width 0.254)
			(type default)
		)
		(layer "In4.Cu")
	)
	(gr_line
		(start 167.303196 -4.06146)
		(end 166.439596 -4.06146)
		(stroke
			(width 0.254)
			(type default)
		)
		(layer "In4.Cu")
	)
	(gr_line
		(start 167.303196 -3.961384)
		(end 166.439596 -3.961384)
		(stroke
			(width 0.254)
			(type default)
		)
		(layer "In4.Cu")
	)
	(gr_line
		(start 167.303196 -1.59766)
		(end 167.303196 -4.06146)
		(stroke
			(width 0.254)
			(type default)
		)
		(layer "In4.Cu")
	)
	(gr_line
		(start 167.303196 -1.497584)
		(end 167.303196 -3.961384)
		(stroke
			(width 0.254)
			(type default)
		)
		(layer "In4.Cu")
	)
	(gr_line
		(start 167.353996 -12.487148)
		(end 166.414196 -12.487148)
		(stroke
			(width 0.254)
			(type default)
		)
		(layer "In4.Cu")
	)
	(gr_line
		(start 167.353996 -12.387072)
		(end 166.414196 -12.387072)
		(stroke
			(width 0.254)
			(type default)
		)
		(layer "In4.Cu")
	)
	(gr_line
		(start 167.353996 -9.997948)
		(end 167.353996 -12.487148)
		(stroke
			(width 0.254)
			(type default)
		)
		(layer "In4.Cu")
	)
	(gr_line
		(start 167.353996 -9.897872)
		(end 167.353996 -12.387072)
		(stroke
			(width 0.254)
			(type default)
		)
		(layer "In4.Cu")
	)
	(gr_line
		(start 167.353996 -8.287004)
		(end 166.414196 -8.287004)
		(stroke
			(width 0.254)
			(type default)
		)
		(layer "In4.Cu")
	)
	(gr_line
		(start 167.353996 -8.186928)
		(end 166.414196 -8.186928)
		(stroke
			(width 0.254)
			(type default)
		)
		(layer "In4.Cu")
	)
	(gr_line
		(start 167.353996 -5.797804)
		(end 167.353996 -8.287004)
		(stroke
			(width 0.254)
			(type default)
		)
		(layer "In4.Cu")
	)
	(gr_line
		(start 167.353996 -5.697728)
		(end 167.353996 -8.186928)
		(stroke
			(width 0.254)
			(type default)
		)
		(layer "In4.Cu")
	)
	(gr_line
		(start 167.353996 -4.08686)
		(end 166.414196 -4.08686)
		(stroke
			(width 0.254)
			(type default)
		)
		(layer "In4.Cu")
	)
	(gr_line
		(start 167.353996 -3.986784)
		(end 166.414196 -3.986784)
		(stroke
			(width 0.254)
			(type default)
		)
		(layer "In4.Cu")
	)
	(gr_line
		(start 167.353996 -1.59766)
		(end 167.353996 -4.08686)
		(stroke
			(width 0.254)
			(type default)
		)
		(layer "In4.Cu")
	)
	(gr_line
		(start 167.353996 -1.497584)
		(end 167.353996 -3.986784)
		(stroke
			(width 0.254)
			(type default)
		)
		(layer "In4.Cu")
	)
	(gr_line
		(start 167.379396 -12.487148)
		(end 166.414196 -12.487148)
		(stroke
			(width 0.2032)
			(type default)
		)
		(layer "In4.Cu")
	)
	(gr_line
		(start 167.379396 -12.387072)
		(end 166.414196 -12.387072)
		(stroke
			(width 0.2032)
			(type default)
		)
		(layer "In4.Cu")
	)
	(gr_line
		(start 167.379396 -9.947148)
		(end 167.379396 -12.487148)
		(stroke
			(width 0.2032)
			(type default)
		)
		(layer "In4.Cu")
	)
	(gr_line
		(start 167.379396 -9.847072)
		(end 167.379396 -12.387072)
		(stroke
			(width 0.2032)
			(type default)
		)
		(layer "In4.Cu")
	)
	(gr_line
		(start 167.379396 -8.287004)
		(end 166.414196 -8.287004)
		(stroke
			(width 0.2032)
			(type default)
		)
		(layer "In4.Cu")
	)
	(gr_line
		(start 167.379396 -8.186928)
		(end 166.414196 -8.186928)
		(stroke
			(width 0.2032)
			(type default)
		)
		(layer "In4.Cu")
	)
	(gr_line
		(start 167.379396 -5.747004)
		(end 167.379396 -8.287004)
		(stroke
			(width 0.2032)
			(type default)
		)
		(layer "In4.Cu")
	)
	(gr_line
		(start 167.379396 -5.646928)
		(end 167.379396 -8.186928)
		(stroke
			(width 0.2032)
			(type default)
		)
		(layer "In4.Cu")
	)
	(gr_line
		(start 167.379396 -4.08686)
		(end 166.414196 -4.08686)
		(stroke
			(width 0.2032)
			(type default)
		)
		(layer "In4.Cu")
	)
	(gr_line
		(start 167.379396 -3.986784)
		(end 166.414196 -3.986784)
		(stroke
			(width 0.2032)
			(type default)
		)
		(layer "In4.Cu")
	)
	(gr_line
		(start 167.379396 -1.54686)
		(end 167.379396 -4.08686)
		(stroke
			(width 0.2032)
			(type default)
		)
		(layer "In4.Cu")
	)
	(gr_line
		(start 167.379396 -1.446784)
		(end 167.379396 -3.986784)
		(stroke
			(width 0.2032)
			(type default)
		)
		(layer "In4.Cu")
	)
	(gr_line
		(start 167.430196 -12.512548)
		(end 166.363396 -12.512548)
		(stroke
			(width 0.2032)
			(type default)
		)
		(layer "In4.Cu")
	)
	(gr_line
		(start 167.430196 -12.412472)
		(end 166.363396 -12.412472)
		(stroke
			(width 0.2032)
			(type default)
		)
		(layer "In4.Cu")
	)
	(gr_line
		(start 167.430196 -9.947148)
		(end 167.430196 -12.512548)
		(stroke
			(width 0.2032)
			(type default)
		)
		(layer "In4.Cu")
	)
	(gr_line
		(start 167.430196 -9.847072)
		(end 167.430196 -12.412472)
		(stroke
			(width 0.2032)
			(type default)
		)
		(layer "In4.Cu")
	)
	(gr_line
		(start 167.430196 -8.312404)
		(end 166.363396 -8.312404)
		(stroke
			(width 0.2032)
			(type default)
		)
		(layer "In4.Cu")
	)
	(gr_line
		(start 167.430196 -8.212328)
		(end 166.363396 -8.212328)
		(stroke
			(width 0.2032)
			(type default)
		)
		(layer "In4.Cu")
	)
	(gr_line
		(start 167.430196 -5.747004)
		(end 167.430196 -8.312404)
		(stroke
			(width 0.2032)
			(type default)
		)
		(layer "In4.Cu")
	)
	(gr_line
		(start 167.430196 -5.646928)
		(end 167.430196 -8.212328)
		(stroke
			(width 0.2032)
			(type default)
		)
		(layer "In4.Cu")
	)
	(gr_line
		(start 167.430196 -4.11226)
		(end 166.363396 -4.11226)
		(stroke
			(width 0.2032)
			(type default)
		)
		(layer "In4.Cu")
	)
	(gr_line
		(start 167.430196 -4.012184)
		(end 166.363396 -4.012184)
		(stroke
			(width 0.2032)
			(type default)
		)
		(layer "In4.Cu")
	)
	(gr_line
		(start 167.430196 -1.54686)
		(end 167.430196 -4.11226)
		(stroke
			(width 0.2032)
			(type default)
		)
		(layer "In4.Cu")
	)
	(gr_line
		(start 167.430196 -1.446784)
		(end 167.430196 -4.012184)
		(stroke
			(width 0.2032)
			(type default)
		)
		(layer "In4.Cu")
	)
	(gr_line
		(start 167.455596 -12.512548)
		(end 166.337996 -12.512548)
		(stroke
			(width 0.1016)
			(type default)
		)
		(layer "In4.Cu")
	)
	(gr_line
		(start 167.455596 -12.412472)
		(end 166.337996 -12.412472)
		(stroke
			(width 0.1016)
			(type default)
		)
		(layer "In4.Cu")
	)
	(gr_line
		(start 167.455596 -9.921748)
		(end 167.455596 -12.512548)
		(stroke
			(width 0.1016)
			(type default)
		)
		(layer "In4.Cu")
	)
	(gr_line
		(start 167.455596 -9.821672)
		(end 167.455596 -12.412472)
		(stroke
			(width 0.1016)
			(type default)
		)
		(layer "In4.Cu")
	)
	(gr_line
		(start 167.455596 -8.312404)
		(end 166.337996 -8.312404)
		(stroke
			(width 0.1016)
			(type default)
		)
		(layer "In4.Cu")
	)
	(gr_line
		(start 167.455596 -8.212328)
		(end 166.337996 -8.212328)
		(stroke
			(width 0.1016)
			(type default)
		)
		(layer "In4.Cu")
	)
	(gr_line
		(start 167.455596 -5.721604)
		(end 167.455596 -8.312404)
		(stroke
			(width 0.1016)
			(type default)
		)
		(layer "In4.Cu")
	)
	(gr_line
		(start 167.455596 -5.621528)
		(end 167.455596 -8.212328)
		(stroke
			(width 0.1016)
			(type default)
		)
		(layer "In4.Cu")
	)
	(gr_line
		(start 167.455596 -4.11226)
		(end 166.337996 -4.11226)
		(stroke
			(width 0.1016)
			(type default)
		)
		(layer "In4.Cu")
	)
	(gr_line
		(start 167.455596 -4.012184)
		(end 166.337996 -4.012184)
		(stroke
			(width 0.1016)
			(type default)
		)
		(layer "In4.Cu")
	)
	(gr_line
		(start 167.455596 -1.52146)
		(end 167.455596 -4.11226)
		(stroke
			(width 0.1016)
			(type default)
		)
		(layer "In4.Cu")
	)
	(gr_line
		(start 167.455596 -1.421384)
		(end 167.455596 -4.012184)
		(stroke
			(width 0.1016)
			(type default)
		)
		(layer "In4.Cu")
	)
	(gr_line
		(start 167.480996 -12.563348)
		(end 167.074596 -12.563348)
		(stroke
			(width 0.1016)
			(type default)
		)
		(layer "In4.Cu")
	)
	(gr_line
		(start 167.480996 -12.563348)
		(end 167.480996 -9.896348)
		(stroke
			(width 0.1016)
			(type default)
		)
		(layer "In4.Cu")
	)
	(gr_line
		(start 167.480996 -12.463272)
		(end 167.074596 -12.463272)
		(stroke
			(width 0.1016)
			(type default)
		)
		(layer "In4.Cu")
	)
	(gr_line
		(start 167.480996 -12.463272)
		(end 167.480996 -9.796272)
		(stroke
			(width 0.1016)
			(type default)
		)
		(layer "In4.Cu")
	)
	(gr_line
		(start 167.480996 -9.896348)
		(end 166.287196 -9.896348)
		(stroke
			(width 0.1016)
			(type default)
		)
		(layer "In4.Cu")
	)
	(gr_line
		(start 167.480996 -9.896348)
		(end 167.480996 -12.563348)
		(stroke
			(width 0.1016)
			(type default)
		)
		(layer "In4.Cu")
	)
	(gr_line
		(start 167.480996 -9.796272)
		(end 166.287196 -9.796272)
		(stroke
			(width 0.1016)
			(type default)
		)
		(layer "In4.Cu")
	)
	(gr_line
		(start 167.480996 -9.796272)
		(end 167.480996 -12.463272)
		(stroke
			(width 0.1016)
			(type default)
		)
		(layer "In4.Cu")
	)
	(gr_line
		(start 167.480996 -8.363204)
		(end 167.074596 -8.363204)
		(stroke
			(width 0.1016)
			(type default)
		)
		(layer "In4.Cu")
	)
	(gr_line
		(start 167.480996 -8.363204)
		(end 167.480996 -5.696204)
		(stroke
			(width 0.1016)
			(type default)
		)
		(layer "In4.Cu")
	)
	(gr_line
		(start 167.480996 -8.263128)
		(end 167.074596 -8.263128)
		(stroke
			(width 0.1016)
			(type default)
		)
		(layer "In4.Cu")
	)
	(gr_line
		(start 167.480996 -8.263128)
		(end 167.480996 -5.596128)
		(stroke
			(width 0.1016)
			(type default)
		)
		(layer "In4.Cu")
	)
	(gr_line
		(start 167.480996 -5.696204)
		(end 166.287196 -5.696204)
		(stroke
			(width 0.1016)
			(type default)
		)
		(layer "In4.Cu")
	)
	(gr_line
		(start 167.480996 -5.696204)
		(end 167.480996 -8.363204)
		(stroke
			(width 0.1016)
			(type default)
		)
		(layer "In4.Cu")
	)
	(gr_line
		(start 167.480996 -5.596128)
		(end 166.287196 -5.596128)
		(stroke
			(width 0.1016)
			(type default)
		)
		(layer "In4.Cu")
	)
	(gr_line
		(start 167.480996 -5.596128)
		(end 167.480996 -8.263128)
		(stroke
			(width 0.1016)
			(type default)
		)
		(layer "In4.Cu")
	)
	(gr_line
		(start 167.480996 -4.16306)
		(end 167.074596 -4.16306)
		(stroke
			(width 0.1016)
			(type default)
		)
		(layer "In4.Cu")
	)
	(gr_line
		(start 167.480996 -4.16306)
		(end 167.480996 -1.49606)
		(stroke
			(width 0.1016)
			(type default)
		)
		(layer "In4.Cu")
	)
	(gr_line
		(start 167.480996 -4.062984)
		(end 167.074596 -4.062984)
		(stroke
			(width 0.1016)
			(type default)
		)
		(layer "In4.Cu")
	)
	(gr_line
		(start 167.480996 -4.062984)
		(end 167.480996 -1.395984)
		(stroke
			(width 0.1016)
			(type default)
		)
		(layer "In4.Cu")
	)
	(gr_line
		(start 167.480996 -1.49606)
		(end 166.287196 -1.49606)
		(stroke
			(width 0.1016)
			(type default)
		)
		(layer "In4.Cu")
	)
	(gr_line
		(start 167.480996 -1.49606)
		(end 167.480996 -4.16306)
		(stroke
			(width 0.1016)
			(type default)
		)
		(layer "In4.Cu")
	)
	(gr_line
		(start 167.480996 -1.494028)
		(end 166.261796 -1.494028)
		(stroke
			(width 0.1016)
			(type default)
		)
		(layer "In4.Cu")
	)
	(gr_line
		(start 167.480996 -1.494028)
		(end 166.287196 -1.494028)
		(stroke
			(width 0.1016)
			(type default)
		)
		(layer "In4.Cu")
	)
	(gr_line
		(start 167.480996 -1.395984)
		(end 166.287196 -1.395984)
		(stroke
			(width 0.1016)
			(type default)
		)
		(layer "In4.Cu")
	)
	(gr_line
		(start 167.480996 -1.395984)
		(end 167.480996 -4.062984)
		(stroke
			(width 0.1016)
			(type default)
		)
		(layer "In4.Cu")
	)
	(gr_line
		(start 167.506396 -1.468628)
		(end 166.261796 -1.468628)
		(stroke
			(width 0.1016)
			(type default)
		)
		(layer "In4.Cu")
	)
	(gr_line
		(start 168.287192 -13.8176)
		(end 169.074592 -13.8176)
		(stroke
			(width 0.1016)
			(type default)
		)
		(layer "In4.Cu")
	)
	(gr_line
		(start 168.287192 -13.7668)
		(end 168.287192 -11.1506)
		(stroke
			(width 0.1016)
			(type default)
		)
		(layer "In4.Cu")
	)
	(gr_line
		(start 168.287192 -11.1506)
		(end 168.287192 -13.8176)
		(stroke
			(width 0.1016)
			(type default)
		)
		(layer "In4.Cu")
	)
	(gr_line
		(start 168.287192 -11.1506)
		(end 169.480992 -11.1506)
		(stroke
			(width 0.1016)
			(type default)
		)
		(layer "In4.Cu")
	)
	(gr_line
		(start 168.287192 -9.617456)
		(end 169.074592 -9.617456)
		(stroke
			(width 0.1016)
			(type default)
		)
		(layer "In4.Cu")
	)
	(gr_line
		(start 168.287192 -9.566656)
		(end 168.287192 -6.950456)
		(stroke
			(width 0.1016)
			(type default)
		)
		(layer "In4.Cu")
	)
	(gr_line
		(start 168.287192 -6.950456)
		(end 168.287192 -9.617456)
		(stroke
			(width 0.1016)
			(type default)
		)
		(layer "In4.Cu")
	)
	(gr_line
		(start 168.287192 -6.950456)
		(end 169.480992 -6.950456)
		(stroke
			(width 0.1016)
			(type default)
		)
		(layer "In4.Cu")
	)
	(gr_line
		(start 168.312592 -13.7668)
		(end 168.312592 -11.176)
		(stroke
			(width 0.1016)
			(type default)
		)
		(layer "In4.Cu")
	)
	(gr_line
		(start 168.312592 -11.176)
		(end 169.455592 -11.176)
		(stroke
			(width 0.1016)
			(type default)
		)
		(layer "In4.Cu")
	)
	(gr_line
		(start 168.312592 -9.566656)
		(end 168.312592 -6.975856)
		(stroke
			(width 0.1016)
			(type default)
		)
		(layer "In4.Cu")
	)
	(gr_line
		(start 168.312592 -6.975856)
		(end 169.455592 -6.975856)
		(stroke
			(width 0.1016)
			(type default)
		)
		(layer "In4.Cu")
	)
	(gr_line
		(start 168.337992 -13.7668)
		(end 168.337992 -11.2014)
		(stroke
			(width 0.1016)
			(type default)
		)
		(layer "In4.Cu")
	)
	(gr_line
		(start 168.337992 -11.2014)
		(end 168.591992 -11.2014)
		(stroke
			(width 0.1016)
			(type default)
		)
		(layer "In4.Cu")
	)
	(gr_line
		(start 168.337992 -9.566656)
		(end 168.337992 -7.001256)
		(stroke
			(width 0.1016)
			(type default)
		)
		(layer "In4.Cu")
	)
	(gr_line
		(start 168.337992 -7.001256)
		(end 168.591992 -7.001256)
		(stroke
			(width 0.1016)
			(type default)
		)
		(layer "In4.Cu")
	)
	(gr_line
		(start 168.363392 -13.7668)
		(end 168.363392 -11.2014)
		(stroke
			(width 0.2032)
			(type default)
		)
		(layer "In4.Cu")
	)
	(gr_line
		(start 168.363392 -11.2014)
		(end 169.379392 -11.2014)
		(stroke
			(width 0.2032)
			(type default)
		)
		(layer "In4.Cu")
	)
	(gr_line
		(start 168.363392 -9.566656)
		(end 168.363392 -7.001256)
		(stroke
			(width 0.2032)
			(type default)
		)
		(layer "In4.Cu")
	)
	(gr_line
		(start 168.363392 -7.001256)
		(end 169.379392 -7.001256)
		(stroke
			(width 0.2032)
			(type default)
		)
		(layer "In4.Cu")
	)
	(gr_line
		(start 168.414192 -13.7414)
		(end 168.414192 -11.2522)
		(stroke
			(width 0.2032)
			(type default)
		)
		(layer "In4.Cu")
	)
	(gr_line
		(start 168.414192 -13.7414)
		(end 168.414192 -11.2522)
		(stroke
			(width 0.254)
			(type default)
		)
		(layer "In4.Cu")
	)
	(gr_line
		(start 168.414192 -11.2522)
		(end 168.617392 -11.2522)
		(stroke
			(width 0.2032)
			(type default)
		)
		(layer "In4.Cu")
	)
	(gr_line
		(start 168.414192 -11.2522)
		(end 169.303192 -11.2522)
		(stroke
			(width 0.254)
			(type default)
		)
		(layer "In4.Cu")
	)
	(gr_line
		(start 168.414192 -9.541256)
		(end 168.414192 -7.052056)
		(stroke
			(width 0.2032)
			(type default)
		)
		(layer "In4.Cu")
	)
	(gr_line
		(start 168.414192 -9.541256)
		(end 168.414192 -7.052056)
		(stroke
			(width 0.254)
			(type default)
		)
		(layer "In4.Cu")
	)
	(gr_line
		(start 168.414192 -7.052056)
		(end 168.617392 -7.052056)
		(stroke
			(width 0.2032)
			(type default)
		)
		(layer "In4.Cu")
	)
	(gr_line
		(start 168.414192 -7.052056)
		(end 169.303192 -7.052056)
		(stroke
			(width 0.254)
			(type default)
		)
		(layer "In4.Cu")
	)
	(gr_line
		(start 168.439592 -13.716)
		(end 168.439592 -11.2776)
		(stroke
			(width 0.254)
			(type default)
		)
		(layer "In4.Cu")
	)
	(gr_line
		(start 168.439592 -11.2776)
		(end 169.277792 -11.2776)
		(stroke
			(width 0.254)
			(type default)
		)
		(layer "In4.Cu")
	)
	(gr_line
		(start 168.439592 -9.515856)
		(end 168.439592 -7.077456)
		(stroke
			(width 0.254)
			(type default)
		)
		(layer "In4.Cu")
	)
	(gr_line
		(start 168.439592 -7.077456)
		(end 169.277792 -7.077456)
		(stroke
			(width 0.254)
			(type default)
		)
		(layer "In4.Cu")
	)
	(gr_line
		(start 168.464992 -13.6906)
		(end 168.464992 -11.303)
		(stroke
			(width 0.254)
			(type default)
		)
		(layer "In4.Cu")
	)
	(gr_line
		(start 168.464992 -11.303)
		(end 169.252392 -11.303)
		(stroke
			(width 0.254)
			(type default)
		)
		(layer "In4.Cu")
	)
	(gr_line
		(start 168.464992 -9.490456)
		(end 168.464992 -7.102856)
		(stroke
			(width 0.254)
			(type default)
		)
		(layer "In4.Cu")
	)
	(gr_line
		(start 168.464992 -7.102856)
		(end 169.252392 -7.102856)
		(stroke
			(width 0.254)
			(type default)
		)
		(layer "In4.Cu")
	)
	(gr_line
		(start 168.490392 -13.6144)
		(end 169.125392 -13.6144)
		(stroke
			(width 0.508)
			(type default)
		)
		(layer "In4.Cu")
	)
	(gr_line
		(start 168.490392 -11.43)
		(end 169.125392 -11.43)
		(stroke
			(width 0.508)
			(type default)
		)
		(layer "In4.Cu")
	)
	(gr_line
		(start 168.490392 -11.3792)
		(end 169.125392 -11.3792)
		(stroke
			(width 0.508)
			(type default)
		)
		(layer "In4.Cu")
	)
	(gr_line
		(start 168.490392 -9.414256)
		(end 169.125392 -9.414256)
		(stroke
			(width 0.508)
			(type default)
		)
		(layer "In4.Cu")
	)
	(gr_line
		(start 168.490392 -7.229856)
		(end 169.125392 -7.229856)
		(stroke
			(width 0.508)
			(type default)
		)
		(layer "In4.Cu")
	)
	(gr_line
		(start 168.490392 -7.179056)
		(end 169.125392 -7.179056)
		(stroke
			(width 0.508)
			(type default)
		)
		(layer "In4.Cu")
	)
	(gr_line
		(start 168.515792 -11.684)
		(end 169.150792 -11.684)
		(stroke
			(width 0.508)
			(type default)
		)
		(layer "In4.Cu")
	)
	(gr_line
		(start 168.515792 -7.483856)
		(end 169.150792 -7.483856)
		(stroke
			(width 0.508)
			(type default)
		)
		(layer "In4.Cu")
	)
	(gr_line
		(start 168.541192 -13.6398)
		(end 168.541192 -11.3792)
		(stroke
			(width 0.254)
			(type default)
		)
		(layer "In4.Cu")
	)
	(gr_line
		(start 168.541192 -13.4874)
		(end 169.176192 -13.4874)
		(stroke
			(width 0.508)
			(type default)
		)
		(layer "In4.Cu")
	)
	(gr_line
		(start 168.541192 -11.3792)
		(end 169.176192 -11.3792)
		(stroke
			(width 0.254)
			(type default)
		)
		(layer "In4.Cu")
	)
	(gr_line
		(start 168.541192 -9.439656)
		(end 168.541192 -7.179056)
		(stroke
			(width 0.254)
			(type default)
		)
		(layer "In4.Cu")
	)
	(gr_line
		(start 168.541192 -9.287256)
		(end 169.176192 -9.287256)
		(stroke
			(width 0.508)
			(type default)
		)
		(layer "In4.Cu")
	)
	(gr_line
		(start 168.541192 -7.179056)
		(end 169.176192 -7.179056)
		(stroke
			(width 0.254)
			(type default)
		)
		(layer "In4.Cu")
	)
	(gr_line
		(start 168.566592 -13.335)
		(end 169.201592 -13.335)
		(stroke
			(width 0.508)
			(type default)
		)
		(layer "In4.Cu")
	)
	(gr_line
		(start 168.566592 -9.134856)
		(end 169.201592 -9.134856)
		(stroke
			(width 0.508)
			(type default)
		)
		(layer "In4.Cu")
	)
	(gr_line
		(start 168.591992 -13.6144)
		(end 169.226992 -13.6144)
		(stroke
			(width 0.508)
			(type default)
		)
		(layer "In4.Cu")
	)
	(gr_line
		(start 168.591992 -11.2014)
		(end 169.430192 -11.2014)
		(stroke
			(width 0.2032)
			(type default)
		)
		(layer "In4.Cu")
	)
	(gr_line
		(start 168.591992 -9.414256)
		(end 169.226992 -9.414256)
		(stroke
			(width 0.508)
			(type default)
		)
		(layer "In4.Cu")
	)
	(gr_line
		(start 168.591992 -7.001256)
		(end 169.430192 -7.001256)
		(stroke
			(width 0.2032)
			(type default)
		)
		(layer "In4.Cu")
	)
	(gr_line
		(start 168.617392 -13.6144)
		(end 168.617392 -11.43)
		(stroke
			(width 0.254)
			(type default)
		)
		(layer "In4.Cu")
	)
	(gr_line
		(start 168.617392 -11.43)
		(end 169.099992 -11.43)
		(stroke
			(width 0.254)
			(type default)
		)
		(layer "In4.Cu")
	)
	(gr_line
		(start 168.617392 -11.2522)
		(end 169.353992 -11.2522)
		(stroke
			(width 0.254)
			(type default)
		)
		(layer "In4.Cu")
	)
	(gr_line
		(start 168.617392 -9.414256)
		(end 168.617392 -7.229856)
		(stroke
			(width 0.254)
			(type default)
		)
		(layer "In4.Cu")
	)
	(gr_line
		(start 168.617392 -7.229856)
		(end 169.099992 -7.229856)
		(stroke
			(width 0.254)
			(type default)
		)
		(layer "In4.Cu")
	)
	(gr_line
		(start 168.617392 -7.052056)
		(end 169.353992 -7.052056)
		(stroke
			(width 0.254)
			(type default)
		)
		(layer "In4.Cu")
	)
	(gr_line
		(start 168.635934 -11.36523)
		(end 169.270934 -11.36523)
		(stroke
			(width 0.508)
			(type default)
		)
		(layer "In4.Cu")
	)
	(gr_line
		(start 168.635934 -7.165086)
		(end 169.270934 -7.165086)
		(stroke
			(width 0.508)
			(type default)
		)
		(layer "In4.Cu")
	)
	(gr_line
		(start 168.642792 -13.6144)
		(end 169.277792 -13.6144)
		(stroke
			(width 0.508)
			(type default)
		)
		(layer "In4.Cu")
	)
	(gr_line
		(start 168.642792 -13.4874)
		(end 168.642792 -11.5062)
		(stroke
			(width 0.762)
			(type default)
		)
		(layer "In4.Cu")
	)
	(gr_line
		(start 168.642792 -11.5062)
		(end 169.277792 -11.5062)
		(stroke
			(width 0.508)
			(type default)
		)
		(layer "In4.Cu")
	)
	(gr_line
		(start 168.642792 -9.414256)
		(end 169.277792 -9.414256)
		(stroke
			(width 0.508)
			(type default)
		)
		(layer "In4.Cu")
	)
	(gr_line
		(start 168.642792 -9.287256)
		(end 168.642792 -7.306056)
		(stroke
			(width 0.762)
			(type default)
		)
		(layer "In4.Cu")
	)
	(gr_line
		(start 168.642792 -7.306056)
		(end 169.277792 -7.306056)
		(stroke
			(width 0.508)
			(type default)
		)
		(layer "In4.Cu")
	)
	(gr_line
		(start 168.693592 -13.5382)
		(end 168.693592 -11.5062)
		(stroke
			(width 0.254)
			(type default)
		)
		(layer "In4.Cu")
	)
	(gr_line
		(start 168.693592 -11.5062)
		(end 169.023792 -11.5062)
		(stroke
			(width 0.254)
			(type default)
		)
		(layer "In4.Cu")
	)
	(gr_line
		(start 168.693592 -9.338056)
		(end 168.693592 -7.306056)
		(stroke
			(width 0.254)
			(type default)
		)
		(layer "In4.Cu")
	)
	(gr_line
		(start 168.693592 -7.306056)
		(end 169.023792 -7.306056)
		(stroke
			(width 0.254)
			(type default)
		)
		(layer "In4.Cu")
	)
	(gr_line
		(start 168.73474 -18.5166)
		(end 167.46474 -18.5166)
		(stroke
			(width 0.7874)
			(type default)
		)
		(layer "In4.Cu")
	)
	(gr_line
		(start 168.795192 -13.462)
		(end 168.795192 -11.6586)
		(stroke
			(width 0.254)
			(type default)
		)
		(layer "In4.Cu")
	)
	(gr_line
		(start 168.795192 -13.462)
		(end 168.795192 -11.4808)
		(stroke
			(width 0.762)
			(type default)
		)
		(layer "In4.Cu")
	)
	(gr_line
		(start 168.795192 -11.6586)
		(end 168.896792 -11.6586)
		(stroke
			(width 0.254)
			(type default)
		)
		(layer "In4.Cu")
	)
	(gr_line
		(start 168.795192 -9.261856)
		(end 168.795192 -7.458456)
		(stroke
			(width 0.254)
			(type default)
		)
		(layer "In4.Cu")
	)
	(gr_line
		(start 168.795192 -9.261856)
		(end 168.795192 -7.280656)
		(stroke
			(width 0.762)
			(type default)
		)
		(layer "In4.Cu")
	)
	(gr_line
		(start 168.795192 -7.458456)
		(end 168.896792 -7.458456)
		(stroke
			(width 0.254)
			(type default)
		)
		(layer "In4.Cu")
	)
	(gr_line
		(start 168.896792 -13.5636)
		(end 168.845992 -13.5636)
		(stroke
			(width 0.254)
			(type default)
		)
		(layer "In4.Cu")
	)
	(gr_line
		(start 168.896792 -11.6586)
		(end 168.896792 -13.5636)
		(stroke
			(width 0.254)
			(type default)
		)
		(layer "In4.Cu")
	)
	(gr_line
		(start 168.896792 -9.363456)
		(end 168.845992 -9.363456)
		(stroke
			(width 0.254)
			(type default)
		)
		(layer "In4.Cu")
	)
	(gr_line
		(start 168.896792 -7.458456)
		(end 168.896792 -9.363456)
		(stroke
			(width 0.254)
			(type default)
		)
		(layer "In4.Cu")
	)
	(gr_line
		(start 168.947592 -13.4874)
		(end 168.947592 -11.5062)
		(stroke
			(width 0.762)
			(type default)
		)
		(layer "In4.Cu")
	)
	(gr_line
		(start 168.947592 -9.287256)
		(end 168.947592 -7.306056)
		(stroke
			(width 0.762)
			(type default)
		)
		(layer "In4.Cu")
	)
	(gr_line
		(start 169.023792 -13.462)
		(end 168.795192 -13.462)
		(stroke
			(width 0.254)
			(type default)
		)
		(layer "In4.Cu")
	)
	(gr_line
		(start 169.023792 -11.5062)
		(end 169.023792 -13.462)
		(stroke
			(width 0.254)
			(type default)
		)
		(layer "In4.Cu")
	)
	(gr_line
		(start 169.023792 -9.261856)
		(end 168.795192 -9.261856)
		(stroke
			(width 0.254)
			(type default)
		)
		(layer "In4.Cu")
	)
	(gr_line
		(start 169.023792 -7.306056)
		(end 169.023792 -9.261856)
		(stroke
			(width 0.254)
			(type default)
		)
		(layer "In4.Cu")
	)
	(gr_line
		(start 169.074592 -13.8176)
		(end 169.074592 -13.7668)
		(stroke
			(width 0.1016)
			(type default)
		)
		(layer "In4.Cu")
	)
	(gr_line
		(start 169.074592 -13.8176)
		(end 169.480992 -13.8176)
		(stroke
			(width 0.1016)
			(type default)
		)
		(layer "In4.Cu")
	)
	(gr_line
		(start 169.074592 -13.7668)
		(end 168.312592 -13.7668)
		(stroke
			(width 0.1016)
			(type default)
		)
		(layer "In4.Cu")
	)
	(gr_line
		(start 169.074592 -13.4874)
		(end 169.074592 -11.5062)
		(stroke
			(width 0.762)
			(type default)
		)
		(layer "In4.Cu")
	)
	(gr_line
		(start 169.074592 -9.617456)
		(end 169.074592 -9.566656)
		(stroke
			(width 0.1016)
			(type default)
		)
		(layer "In4.Cu")
	)
	(gr_line
		(start 169.074592 -9.617456)
		(end 169.480992 -9.617456)
		(stroke
			(width 0.1016)
			(type default)
		)
		(layer "In4.Cu")
	)
	(gr_line
		(start 169.074592 -9.566656)
		(end 168.312592 -9.566656)
		(stroke
			(width 0.1016)
			(type default)
		)
		(layer "In4.Cu")
	)
	(gr_line
		(start 169.074592 -9.287256)
		(end 169.074592 -7.306056)
		(stroke
			(width 0.762)
			(type default)
		)
		(layer "In4.Cu")
	)
	(gr_line
		(start 169.099992 -13.5382)
		(end 168.693592 -13.5382)
		(stroke
			(width 0.254)
			(type default)
		)
		(layer "In4.Cu")
	)
	(gr_line
		(start 169.099992 -11.43)
		(end 169.099992 -13.5382)
		(stroke
			(width 0.254)
			(type default)
		)
		(layer "In4.Cu")
	)
	(gr_line
		(start 169.099992 -9.338056)
		(end 168.693592 -9.338056)
		(stroke
			(width 0.254)
			(type default)
		)
		(layer "In4.Cu")
	)
	(gr_line
		(start 169.099992 -7.229856)
		(end 169.099992 -9.338056)
		(stroke
			(width 0.254)
			(type default)
		)
		(layer "In4.Cu")
	)
	(gr_line
		(start 169.150792 -13.4874)
		(end 169.150792 -11.5062)
		(stroke
			(width 0.762)
			(type default)
		)
		(layer "In4.Cu")
	)
	(gr_line
		(start 169.150792 -9.287256)
		(end 169.150792 -7.306056)
		(stroke
			(width 0.762)
			(type default)
		)
		(layer "In4.Cu")
	)
	(gr_line
		(start 169.176192 -13.6144)
		(end 168.617392 -13.6144)
		(stroke
			(width 0.254)
			(type default)
		)
		(layer "In4.Cu")
	)
	(gr_line
		(start 169.176192 -11.3792)
		(end 169.176192 -13.6144)
		(stroke
			(width 0.254)
			(type default)
		)
		(layer "In4.Cu")
	)
	(gr_line
		(start 169.176192 -9.414256)
		(end 168.617392 -9.414256)
		(stroke
			(width 0.254)
			(type default)
		)
		(layer "In4.Cu")
	)
	(gr_line
		(start 169.176192 -7.179056)
		(end 169.176192 -9.414256)
		(stroke
			(width 0.254)
			(type default)
		)
		(layer "In4.Cu")
	)
	(gr_line
		(start 169.252392 -13.6398)
		(end 168.541192 -13.6398)
		(stroke
			(width 0.254)
			(type default)
		)
		(layer "In4.Cu")
	)
	(gr_line
		(start 169.252392 -11.303)
		(end 169.252392 -13.6398)
		(stroke
			(width 0.254)
			(type default)
		)
		(layer "In4.Cu")
	)
	(gr_line
		(start 169.252392 -9.439656)
		(end 168.541192 -9.439656)
		(stroke
			(width 0.254)
			(type default)
		)
		(layer "In4.Cu")
	)
	(gr_line
		(start 169.252392 -7.102856)
		(end 169.252392 -9.439656)
		(stroke
			(width 0.254)
			(type default)
		)
		(layer "In4.Cu")
	)
	(gr_line
		(start 169.277792 -13.7668)
		(end 168.287192 -13.7668)
		(stroke
			(width 0.1016)
			(type default)
		)
		(layer "In4.Cu")
	)
	(gr_line
		(start 169.277792 -13.6906)
		(end 168.464992 -13.6906)
		(stroke
			(width 0.254)
			(type default)
		)
		(layer "In4.Cu")
	)
	(gr_line
		(start 169.277792 -11.2776)
		(end 169.277792 -13.6906)
		(stroke
			(width 0.254)
			(type default)
		)
		(layer "In4.Cu")
	)
	(gr_line
		(start 169.277792 -9.566656)
		(end 168.287192 -9.566656)
		(stroke
			(width 0.1016)
			(type default)
		)
		(layer "In4.Cu")
	)
	(gr_line
		(start 169.277792 -9.490456)
		(end 168.464992 -9.490456)
		(stroke
			(width 0.254)
			(type default)
		)
		(layer "In4.Cu")
	)
	(gr_line
		(start 169.277792 -7.077456)
		(end 169.277792 -9.490456)
		(stroke
			(width 0.254)
			(type default)
		)
		(layer "In4.Cu")
	)
	(gr_line
		(start 169.303192 -13.716)
		(end 168.439592 -13.716)
		(stroke
			(width 0.254)
			(type default)
		)
		(layer "In4.Cu")
	)
	(gr_line
		(start 169.303192 -11.2522)
		(end 169.303192 -13.716)
		(stroke
			(width 0.254)
			(type default)
		)
		(layer "In4.Cu")
	)
	(gr_line
		(start 169.303192 -9.515856)
		(end 168.439592 -9.515856)
		(stroke
			(width 0.254)
			(type default)
		)
		(layer "In4.Cu")
	)
	(gr_line
		(start 169.303192 -7.052056)
		(end 169.303192 -9.515856)
		(stroke
			(width 0.254)
			(type default)
		)
		(layer "In4.Cu")
	)
	(gr_line
		(start 169.319956 -30.734)
		(end 168.049956 -30.734)
		(stroke
			(width 0.7874)
			(type default)
		)
		(layer "In4.Cu")
	)
	(gr_line
		(start 169.353992 -13.7414)
		(end 168.414192 -13.7414)
		(stroke
			(width 0.254)
			(type default)
		)
		(layer "In4.Cu")
	)
	(gr_line
		(start 169.353992 -11.2522)
		(end 169.353992 -13.7414)
		(stroke
			(width 0.254)
			(type default)
		)
		(layer "In4.Cu")
	)
	(gr_line
		(start 169.353992 -9.541256)
		(end 168.414192 -9.541256)
		(stroke
			(width 0.254)
			(type default)
		)
		(layer "In4.Cu")
	)
	(gr_line
		(start 169.353992 -7.052056)
		(end 169.353992 -9.541256)
		(stroke
			(width 0.254)
			(type default)
		)
		(layer "In4.Cu")
	)
	(gr_line
		(start 169.379392 -13.7414)
		(end 168.414192 -13.7414)
		(stroke
			(width 0.2032)
			(type default)
		)
		(layer "In4.Cu")
	)
	(gr_line
		(start 169.379392 -11.2014)
		(end 169.379392 -13.7414)
		(stroke
			(width 0.2032)
			(type default)
		)
		(layer "In4.Cu")
	)
	(gr_line
		(start 169.379392 -9.541256)
		(end 168.414192 -9.541256)
		(stroke
			(width 0.2032)
			(type default)
		)
		(layer "In4.Cu")
	)
	(gr_line
		(start 169.379392 -7.001256)
		(end 169.379392 -9.541256)
		(stroke
			(width 0.2032)
			(type default)
		)
		(layer "In4.Cu")
	)
	(gr_line
		(start 169.430192 -13.7668)
		(end 168.363392 -13.7668)
		(stroke
			(width 0.2032)
			(type default)
		)
		(layer "In4.Cu")
	)
	(gr_line
		(start 169.430192 -11.2014)
		(end 169.430192 -13.7668)
		(stroke
			(width 0.2032)
			(type default)
		)
		(layer "In4.Cu")
	)
	(gr_line
		(start 169.430192 -9.566656)
		(end 168.363392 -9.566656)
		(stroke
			(width 0.2032)
			(type default)
		)
		(layer "In4.Cu")
	)
	(gr_line
		(start 169.430192 -7.001256)
		(end 169.430192 -9.566656)
		(stroke
			(width 0.2032)
			(type default)
		)
		(layer "In4.Cu")
	)
	(gr_line
		(start 169.455592 -13.7668)
		(end 168.337992 -13.7668)
		(stroke
			(width 0.1016)
			(type default)
		)
		(layer "In4.Cu")
	)
	(gr_line
		(start 169.455592 -11.176)
		(end 169.455592 -13.7668)
		(stroke
			(width 0.1016)
			(type default)
		)
		(layer "In4.Cu")
	)
	(gr_line
		(start 169.455592 -9.566656)
		(end 168.337992 -9.566656)
		(stroke
			(width 0.1016)
			(type default)
		)
		(layer "In4.Cu")
	)
	(gr_line
		(start 169.455592 -6.975856)
		(end 169.455592 -9.566656)
		(stroke
			(width 0.1016)
			(type default)
		)
		(layer "In4.Cu")
	)
	(gr_line
		(start 169.480992 -13.8176)
		(end 169.074592 -13.8176)
		(stroke
			(width 0.1016)
			(type default)
		)
		(layer "In4.Cu")
	)
	(gr_line
		(start 169.480992 -13.8176)
		(end 169.480992 -11.1506)
		(stroke
			(width 0.1016)
			(type default)
		)
		(layer "In4.Cu")
	)
	(gr_line
		(start 169.480992 -11.1506)
		(end 168.287192 -11.1506)
		(stroke
			(width 0.1016)
			(type default)
		)
		(layer "In4.Cu")
	)
	(gr_line
		(start 169.480992 -11.1506)
		(end 169.480992 -13.8176)
		(stroke
			(width 0.1016)
			(type default)
		)
		(layer "In4.Cu")
	)
	(gr_line
		(start 169.480992 -9.617456)
		(end 169.074592 -9.617456)
		(stroke
			(width 0.1016)
			(type default)
		)
		(layer "In4.Cu")
	)
	(gr_line
		(start 169.480992 -9.617456)
		(end 169.480992 -6.950456)
		(stroke
			(width 0.1016)
			(type default)
		)
		(layer "In4.Cu")
	)
	(gr_line
		(start 169.480992 -6.950456)
		(end 168.287192 -6.950456)
		(stroke
			(width 0.1016)
			(type default)
		)
		(layer "In4.Cu")
	)
	(gr_line
		(start 169.480992 -6.950456)
		(end 169.480992 -9.617456)
		(stroke
			(width 0.1016)
			(type default)
		)
		(layer "In4.Cu")
	)
	(gr_line
		(start 170.287188 -12.563348)
		(end 171.074588 -12.563348)
		(stroke
			(width 0.1016)
			(type default)
		)
		(layer "In4.Cu")
	)
	(gr_line
		(start 170.287188 -12.512548)
		(end 170.287188 -9.896348)
		(stroke
			(width 0.1016)
			(type default)
		)
		(layer "In4.Cu")
	)
	(gr_line
		(start 170.287188 -12.463272)
		(end 171.074588 -12.463272)
		(stroke
			(width 0.1016)
			(type default)
		)
		(layer "In4.Cu")
	)
	(gr_line
		(start 170.287188 -12.412472)
		(end 170.287188 -9.796272)
		(stroke
			(width 0.1016)
			(type default)
		)
		(layer "In4.Cu")
	)
	(gr_line
		(start 170.287188 -9.896348)
		(end 170.287188 -12.563348)
		(stroke
			(width 0.1016)
			(type default)
		)
		(layer "In4.Cu")
	)
	(gr_line
		(start 170.287188 -9.896348)
		(end 171.480988 -9.896348)
		(stroke
			(width 0.1016)
			(type default)
		)
		(layer "In4.Cu")
	)
	(gr_line
		(start 170.287188 -9.796272)
		(end 170.287188 -12.463272)
		(stroke
			(width 0.1016)
			(type default)
		)
		(layer "In4.Cu")
	)
	(gr_line
		(start 170.287188 -9.796272)
		(end 171.480988 -9.796272)
		(stroke
			(width 0.1016)
			(type default)
		)
		(layer "In4.Cu")
	)
	(gr_line
		(start 170.287188 -8.363204)
		(end 171.074588 -8.363204)
		(stroke
			(width 0.1016)
			(type default)
		)
		(layer "In4.Cu")
	)
	(gr_line
		(start 170.287188 -8.312404)
		(end 170.287188 -5.696204)
		(stroke
			(width 0.1016)
			(type default)
		)
		(layer "In4.Cu")
	)
	(gr_line
		(start 170.287188 -8.263128)
		(end 171.074588 -8.263128)
		(stroke
			(width 0.1016)
			(type default)
		)
		(layer "In4.Cu")
	)
	(gr_line
		(start 170.287188 -8.212328)
		(end 170.287188 -5.596128)
		(stroke
			(width 0.1016)
			(type default)
		)
		(layer "In4.Cu")
	)
	(gr_line
		(start 170.287188 -5.696204)
		(end 170.287188 -8.363204)
		(stroke
			(width 0.1016)
			(type default)
		)
		(layer "In4.Cu")
	)
	(gr_line
		(start 170.287188 -5.696204)
		(end 171.480988 -5.696204)
		(stroke
			(width 0.1016)
			(type default)
		)
		(layer "In4.Cu")
	)
	(gr_line
		(start 170.287188 -5.596128)
		(end 170.287188 -8.263128)
		(stroke
			(width 0.1016)
			(type default)
		)
		(layer "In4.Cu")
	)
	(gr_line
		(start 170.287188 -5.596128)
		(end 171.480988 -5.596128)
		(stroke
			(width 0.1016)
			(type default)
		)
		(layer "In4.Cu")
	)
	(gr_line
		(start 170.312588 -12.512548)
		(end 170.312588 -9.921748)
		(stroke
			(width 0.1016)
			(type default)
		)
		(layer "In4.Cu")
	)
	(gr_line
		(start 170.312588 -12.412472)
		(end 170.312588 -9.821672)
		(stroke
			(width 0.1016)
			(type default)
		)
		(layer "In4.Cu")
	)
	(gr_line
		(start 170.312588 -9.921748)
		(end 171.455588 -9.921748)
		(stroke
			(width 0.1016)
			(type default)
		)
		(layer "In4.Cu")
	)
	(gr_line
		(start 170.312588 -9.821672)
		(end 171.455588 -9.821672)
		(stroke
			(width 0.1016)
			(type default)
		)
		(layer "In4.Cu")
	)
	(gr_line
		(start 170.312588 -8.312404)
		(end 170.312588 -5.721604)
		(stroke
			(width 0.1016)
			(type default)
		)
		(layer "In4.Cu")
	)
	(gr_line
		(start 170.312588 -8.212328)
		(end 170.312588 -5.621528)
		(stroke
			(width 0.1016)
			(type default)
		)
		(layer "In4.Cu")
	)
	(gr_line
		(start 170.312588 -5.721604)
		(end 171.455588 -5.721604)
		(stroke
			(width 0.1016)
			(type default)
		)
		(layer "In4.Cu")
	)
	(gr_line
		(start 170.312588 -5.621528)
		(end 171.455588 -5.621528)
		(stroke
			(width 0.1016)
			(type default)
		)
		(layer "In4.Cu")
	)
	(gr_line
		(start 170.337988 -12.512548)
		(end 170.337988 -9.947148)
		(stroke
			(width 0.1016)
			(type default)
		)
		(layer "In4.Cu")
	)
	(gr_line
		(start 170.337988 -12.412472)
		(end 170.337988 -9.847072)
		(stroke
			(width 0.1016)
			(type default)
		)
		(layer "In4.Cu")
	)
	(gr_line
		(start 170.337988 -9.947148)
		(end 170.591988 -9.947148)
		(stroke
			(width 0.1016)
			(type default)
		)
		(layer "In4.Cu")
	)
	(gr_line
		(start 170.337988 -9.847072)
		(end 170.591988 -9.847072)
		(stroke
			(width 0.1016)
			(type default)
		)
		(layer "In4.Cu")
	)
	(gr_line
		(start 170.337988 -8.312404)
		(end 170.337988 -5.747004)
		(stroke
			(width 0.1016)
			(type default)
		)
		(layer "In4.Cu")
	)
	(gr_line
		(start 170.337988 -8.212328)
		(end 170.337988 -5.646928)
		(stroke
			(width 0.1016)
			(type default)
		)
		(layer "In4.Cu")
	)
	(gr_line
		(start 170.337988 -5.747004)
		(end 170.591988 -5.747004)
		(stroke
			(width 0.1016)
			(type default)
		)
		(layer "In4.Cu")
	)
	(gr_line
		(start 170.337988 -5.646928)
		(end 170.591988 -5.646928)
		(stroke
			(width 0.1016)
			(type default)
		)
		(layer "In4.Cu")
	)
	(gr_line
		(start 170.363388 -12.512548)
		(end 170.363388 -9.947148)
		(stroke
			(width 0.2032)
			(type default)
		)
		(layer "In4.Cu")
	)
	(gr_line
		(start 170.363388 -12.412472)
		(end 170.363388 -9.847072)
		(stroke
			(width 0.2032)
			(type default)
		)
		(layer "In4.Cu")
	)
	(gr_line
		(start 170.363388 -9.947148)
		(end 171.379388 -9.947148)
		(stroke
			(width 0.2032)
			(type default)
		)
		(layer "In4.Cu")
	)
	(gr_line
		(start 170.363388 -9.847072)
		(end 171.379388 -9.847072)
		(stroke
			(width 0.2032)
			(type default)
		)
		(layer "In4.Cu")
	)
	(gr_line
		(start 170.363388 -8.312404)
		(end 170.363388 -5.747004)
		(stroke
			(width 0.2032)
			(type default)
		)
		(layer "In4.Cu")
	)
	(gr_line
		(start 170.363388 -8.212328)
		(end 170.363388 -5.646928)
		(stroke
			(width 0.2032)
			(type default)
		)
		(layer "In4.Cu")
	)
	(gr_line
		(start 170.363388 -5.747004)
		(end 171.379388 -5.747004)
		(stroke
			(width 0.2032)
			(type default)
		)
		(layer "In4.Cu")
	)
	(gr_line
		(start 170.363388 -5.646928)
		(end 171.379388 -5.646928)
		(stroke
			(width 0.2032)
			(type default)
		)
		(layer "In4.Cu")
	)
	(gr_line
		(start 170.414188 -12.487148)
		(end 170.414188 -9.997948)
		(stroke
			(width 0.2032)
			(type default)
		)
		(layer "In4.Cu")
	)
	(gr_line
		(start 170.414188 -12.487148)
		(end 170.414188 -9.997948)
		(stroke
			(width 0.254)
			(type default)
		)
		(layer "In4.Cu")
	)
	(gr_line
		(start 170.414188 -12.387072)
		(end 170.414188 -9.897872)
		(stroke
			(width 0.2032)
			(type default)
		)
		(layer "In4.Cu")
	)
	(gr_line
		(start 170.414188 -12.387072)
		(end 170.414188 -9.897872)
		(stroke
			(width 0.254)
			(type default)
		)
		(layer "In4.Cu")
	)
	(gr_line
		(start 170.414188 -9.997948)
		(end 170.617388 -9.997948)
		(stroke
			(width 0.2032)
			(type default)
		)
		(layer "In4.Cu")
	)
	(gr_line
		(start 170.414188 -9.997948)
		(end 171.303188 -9.997948)
		(stroke
			(width 0.254)
			(type default)
		)
		(layer "In4.Cu")
	)
	(gr_line
		(start 170.414188 -9.897872)
		(end 170.617388 -9.897872)
		(stroke
			(width 0.2032)
			(type default)
		)
		(layer "In4.Cu")
	)
	(gr_line
		(start 170.414188 -9.897872)
		(end 171.303188 -9.897872)
		(stroke
			(width 0.254)
			(type default)
		)
		(layer "In4.Cu")
	)
	(gr_line
		(start 170.414188 -8.287004)
		(end 170.414188 -5.797804)
		(stroke
			(width 0.2032)
			(type default)
		)
		(layer "In4.Cu")
	)
	(gr_line
		(start 170.414188 -8.287004)
		(end 170.414188 -5.797804)
		(stroke
			(width 0.254)
			(type default)
		)
		(layer "In4.Cu")
	)
	(gr_line
		(start 170.414188 -8.186928)
		(end 170.414188 -5.697728)
		(stroke
			(width 0.2032)
			(type default)
		)
		(layer "In4.Cu")
	)
	(gr_line
		(start 170.414188 -8.186928)
		(end 170.414188 -5.697728)
		(stroke
			(width 0.254)
			(type default)
		)
		(layer "In4.Cu")
	)
	(gr_line
		(start 170.414188 -5.797804)
		(end 170.617388 -5.797804)
		(stroke
			(width 0.2032)
			(type default)
		)
		(layer "In4.Cu")
	)
	(gr_line
		(start 170.414188 -5.797804)
		(end 171.303188 -5.797804)
		(stroke
			(width 0.254)
			(type default)
		)
		(layer "In4.Cu")
	)
	(gr_line
		(start 170.414188 -5.697728)
		(end 170.617388 -5.697728)
		(stroke
			(width 0.2032)
			(type default)
		)
		(layer "In4.Cu")
	)
	(gr_line
		(start 170.414188 -5.697728)
		(end 171.303188 -5.697728)
		(stroke
			(width 0.254)
			(type default)
		)
		(layer "In4.Cu")
	)
	(gr_line
		(start 170.439588 -12.461748)
		(end 170.439588 -10.023348)
		(stroke
			(width 0.254)
			(type default)
		)
		(layer "In4.Cu")
	)
	(gr_line
		(start 170.439588 -12.361672)
		(end 170.439588 -9.923272)
		(stroke
			(width 0.254)
			(type default)
		)
		(layer "In4.Cu")
	)
	(gr_line
		(start 170.439588 -10.023348)
		(end 171.277788 -10.023348)
		(stroke
			(width 0.254)
			(type default)
		)
		(layer "In4.Cu")
	)
	(gr_line
		(start 170.439588 -9.923272)
		(end 171.277788 -9.923272)
		(stroke
			(width 0.254)
			(type default)
		)
		(layer "In4.Cu")
	)
	(gr_line
		(start 170.439588 -8.261604)
		(end 170.439588 -5.823204)
		(stroke
			(width 0.254)
			(type default)
		)
		(layer "In4.Cu")
	)
	(gr_line
		(start 170.439588 -8.161528)
		(end 170.439588 -5.723128)
		(stroke
			(width 0.254)
			(type default)
		)
		(layer "In4.Cu")
	)
	(gr_line
		(start 170.439588 -5.823204)
		(end 171.277788 -5.823204)
		(stroke
			(width 0.254)
			(type default)
		)
		(layer "In4.Cu")
	)
	(gr_line
		(start 170.439588 -5.723128)
		(end 171.277788 -5.723128)
		(stroke
			(width 0.254)
			(type default)
		)
		(layer "In4.Cu")
	)
	(gr_line
		(start 170.464988 -12.436348)
		(end 170.464988 -10.048748)
		(stroke
			(width 0.254)
			(type default)
		)
		(layer "In4.Cu")
	)
	(gr_line
		(start 170.464988 -12.336272)
		(end 170.464988 -9.948672)
		(stroke
			(width 0.254)
			(type default)
		)
		(layer "In4.Cu")
	)
	(gr_line
		(start 170.464988 -10.048748)
		(end 171.252388 -10.048748)
		(stroke
			(width 0.254)
			(type default)
		)
		(layer "In4.Cu")
	)
	(gr_line
		(start 170.464988 -9.948672)
		(end 171.252388 -9.948672)
		(stroke
			(width 0.254)
			(type default)
		)
		(layer "In4.Cu")
	)
	(gr_line
		(start 170.464988 -8.236204)
		(end 170.464988 -5.848604)
		(stroke
			(width 0.254)
			(type default)
		)
		(layer "In4.Cu")
	)
	(gr_line
		(start 170.464988 -8.136128)
		(end 170.464988 -5.748528)
		(stroke
			(width 0.254)
			(type default)
		)
		(layer "In4.Cu")
	)
	(gr_line
		(start 170.464988 -5.848604)
		(end 171.252388 -5.848604)
		(stroke
			(width 0.254)
			(type default)
		)
		(layer "In4.Cu")
	)
	(gr_line
		(start 170.464988 -5.748528)
		(end 171.252388 -5.748528)
		(stroke
			(width 0.254)
			(type default)
		)
		(layer "In4.Cu")
	)
	(gr_line
		(start 170.490388 -12.360148)
		(end 171.125388 -12.360148)
		(stroke
			(width 0.508)
			(type default)
		)
		(layer "In4.Cu")
	)
	(gr_line
		(start 170.490388 -12.260072)
		(end 171.125388 -12.260072)
		(stroke
			(width 0.508)
			(type default)
		)
		(layer "In4.Cu")
	)
	(gr_line
		(start 170.490388 -10.175748)
		(end 171.125388 -10.175748)
		(stroke
			(width 0.508)
			(type default)
		)
		(layer "In4.Cu")
	)
	(gr_line
		(start 170.490388 -10.124948)
		(end 171.125388 -10.124948)
		(stroke
			(width 0.508)
			(type default)
		)
		(layer "In4.Cu")
	)
	(gr_line
		(start 170.490388 -10.075672)
		(end 171.125388 -10.075672)
		(stroke
			(width 0.508)
			(type default)
		)
		(layer "In4.Cu")
	)
	(gr_line
		(start 170.490388 -10.024872)
		(end 171.125388 -10.024872)
		(stroke
			(width 0.508)
			(type default)
		)
		(layer "In4.Cu")
	)
	(gr_line
		(start 170.490388 -8.160004)
		(end 171.125388 -8.160004)
		(stroke
			(width 0.508)
			(type default)
		)
		(layer "In4.Cu")
	)
	(gr_line
		(start 170.490388 -8.059928)
		(end 171.125388 -8.059928)
		(stroke
			(width 0.508)
			(type default)
		)
		(layer "In4.Cu")
	)
	(gr_line
		(start 170.490388 -5.975604)
		(end 171.125388 -5.975604)
		(stroke
			(width 0.508)
			(type default)
		)
		(layer "In4.Cu")
	)
	(gr_line
		(start 170.490388 -5.924804)
		(end 171.125388 -5.924804)
		(stroke
			(width 0.508)
			(type default)
		)
		(layer "In4.Cu")
	)
	(gr_line
		(start 170.490388 -5.875528)
		(end 171.125388 -5.875528)
		(stroke
			(width 0.508)
			(type default)
		)
		(layer "In4.Cu")
	)
	(gr_line
		(start 170.490388 -5.824728)
		(end 171.125388 -5.824728)
		(stroke
			(width 0.508)
			(type default)
		)
		(layer "In4.Cu")
	)
	(gr_line
		(start 170.515788 -10.429748)
		(end 171.150788 -10.429748)
		(stroke
			(width 0.508)
			(type default)
		)
		(layer "In4.Cu")
	)
	(gr_line
		(start 170.515788 -10.329672)
		(end 171.150788 -10.329672)
		(stroke
			(width 0.508)
			(type default)
		)
		(layer "In4.Cu")
	)
	(gr_line
		(start 170.515788 -6.229604)
		(end 171.150788 -6.229604)
		(stroke
			(width 0.508)
			(type default)
		)
		(layer "In4.Cu")
	)
	(gr_line
		(start 170.515788 -6.129528)
		(end 171.150788 -6.129528)
		(stroke
			(width 0.508)
			(type default)
		)
		(layer "In4.Cu")
	)
	(gr_line
		(start 170.541188 -12.385548)
		(end 170.541188 -10.124948)
		(stroke
			(width 0.254)
			(type default)
		)
		(layer "In4.Cu")
	)
	(gr_line
		(start 170.541188 -12.285472)
		(end 170.541188 -10.024872)
		(stroke
			(width 0.254)
			(type default)
		)
		(layer "In4.Cu")
	)
	(gr_line
		(start 170.541188 -12.233148)
		(end 171.176188 -12.233148)
		(stroke
			(width 0.508)
			(type default)
		)
		(layer "In4.Cu")
	)
	(gr_line
		(start 170.541188 -12.133072)
		(end 171.176188 -12.133072)
		(stroke
			(width 0.508)
			(type default)
		)
		(layer "In4.Cu")
	)
	(gr_line
		(start 170.541188 -10.124948)
		(end 171.176188 -10.124948)
		(stroke
			(width 0.254)
			(type default)
		)
		(layer "In4.Cu")
	)
	(gr_line
		(start 170.541188 -10.024872)
		(end 171.176188 -10.024872)
		(stroke
			(width 0.254)
			(type default)
		)
		(layer "In4.Cu")
	)
	(gr_line
		(start 170.541188 -8.185404)
		(end 170.541188 -5.924804)
		(stroke
			(width 0.254)
			(type default)
		)
		(layer "In4.Cu")
	)
	(gr_line
		(start 170.541188 -8.085328)
		(end 170.541188 -5.824728)
		(stroke
			(width 0.254)
			(type default)
		)
		(layer "In4.Cu")
	)
	(gr_line
		(start 170.541188 -8.033004)
		(end 171.176188 -8.033004)
		(stroke
			(width 0.508)
			(type default)
		)
		(layer "In4.Cu")
	)
	(gr_line
		(start 170.541188 -7.932928)
		(end 171.176188 -7.932928)
		(stroke
			(width 0.508)
			(type default)
		)
		(layer "In4.Cu")
	)
	(gr_line
		(start 170.541188 -5.924804)
		(end 171.176188 -5.924804)
		(stroke
			(width 0.254)
			(type default)
		)
		(layer "In4.Cu")
	)
	(gr_line
		(start 170.541188 -5.824728)
		(end 171.176188 -5.824728)
		(stroke
			(width 0.254)
			(type default)
		)
		(layer "In4.Cu")
	)
	(gr_line
		(start 170.566588 -12.080748)
		(end 171.201588 -12.080748)
		(stroke
			(width 0.508)
			(type default)
		)
		(layer "In4.Cu")
	)
	(gr_line
		(start 170.566588 -11.980672)
		(end 171.201588 -11.980672)
		(stroke
			(width 0.508)
			(type default)
		)
		(layer "In4.Cu")
	)
	(gr_line
		(start 170.566588 -7.880604)
		(end 171.201588 -7.880604)
		(stroke
			(width 0.508)
			(type default)
		)
		(layer "In4.Cu")
	)
	(gr_line
		(start 170.566588 -7.780528)
		(end 171.201588 -7.780528)
		(stroke
			(width 0.508)
			(type default)
		)
		(layer "In4.Cu")
	)
	(gr_line
		(start 170.591988 -12.360148)
		(end 171.226988 -12.360148)
		(stroke
			(width 0.508)
			(type default)
		)
		(layer "In4.Cu")
	)
	(gr_line
		(start 170.591988 -12.260072)
		(end 171.226988 -12.260072)
		(stroke
			(width 0.508)
			(type default)
		)
		(layer "In4.Cu")
	)
	(gr_line
		(start 170.591988 -9.947148)
		(end 171.430188 -9.947148)
		(stroke
			(width 0.2032)
			(type default)
		)
		(layer "In4.Cu")
	)
	(gr_line
		(start 170.591988 -9.847072)
		(end 171.430188 -9.847072)
		(stroke
			(width 0.2032)
			(type default)
		)
		(layer "In4.Cu")
	)
	(gr_line
		(start 170.591988 -8.160004)
		(end 171.226988 -8.160004)
		(stroke
			(width 0.508)
			(type default)
		)
		(layer "In4.Cu")
	)
	(gr_line
		(start 170.591988 -8.059928)
		(end 171.226988 -8.059928)
		(stroke
			(width 0.508)
			(type default)
		)
		(layer "In4.Cu")
	)
	(gr_line
		(start 170.591988 -5.747004)
		(end 171.430188 -5.747004)
		(stroke
			(width 0.2032)
			(type default)
		)
		(layer "In4.Cu")
	)
	(gr_line
		(start 170.591988 -5.646928)
		(end 171.430188 -5.646928)
		(stroke
			(width 0.2032)
			(type default)
		)
		(layer "In4.Cu")
	)
	(gr_line
		(start 170.617388 -12.360148)
		(end 170.617388 -10.175748)
		(stroke
			(width 0.254)
			(type default)
		)
		(layer "In4.Cu")
	)
	(gr_line
		(start 170.617388 -12.260072)
		(end 170.617388 -10.075672)
		(stroke
			(width 0.254)
			(type default)
		)
		(layer "In4.Cu")
	)
	(gr_line
		(start 170.617388 -10.175748)
		(end 171.099988 -10.175748)
		(stroke
			(width 0.254)
			(type default)
		)
		(layer "In4.Cu")
	)
	(gr_line
		(start 170.617388 -10.075672)
		(end 171.099988 -10.075672)
		(stroke
			(width 0.254)
			(type default)
		)
		(layer "In4.Cu")
	)
	(gr_line
		(start 170.617388 -9.997948)
		(end 171.353988 -9.997948)
		(stroke
			(width 0.254)
			(type default)
		)
		(layer "In4.Cu")
	)
	(gr_line
		(start 170.617388 -9.897872)
		(end 171.353988 -9.897872)
		(stroke
			(width 0.254)
			(type default)
		)
		(layer "In4.Cu")
	)
	(gr_line
		(start 170.617388 -8.160004)
		(end 170.617388 -5.975604)
		(stroke
			(width 0.254)
			(type default)
		)
		(layer "In4.Cu")
	)
	(gr_line
		(start 170.617388 -8.059928)
		(end 170.617388 -5.875528)
		(stroke
			(width 0.254)
			(type default)
		)
		(layer "In4.Cu")
	)
	(gr_line
		(start 170.617388 -5.975604)
		(end 171.099988 -5.975604)
		(stroke
			(width 0.254)
			(type default)
		)
		(layer "In4.Cu")
	)
	(gr_line
		(start 170.617388 -5.875528)
		(end 171.099988 -5.875528)
		(stroke
			(width 0.254)
			(type default)
		)
		(layer "In4.Cu")
	)
	(gr_line
		(start 170.617388 -5.797804)
		(end 171.353988 -5.797804)
		(stroke
			(width 0.254)
			(type default)
		)
		(layer "In4.Cu")
	)
	(gr_line
		(start 170.617388 -5.697728)
		(end 171.353988 -5.697728)
		(stroke
			(width 0.254)
			(type default)
		)
		(layer "In4.Cu")
	)
	(gr_line
		(start 170.63593 -10.110978)
		(end 171.27093 -10.110978)
		(stroke
			(width 0.508)
			(type default)
		)
		(layer "In4.Cu")
	)
	(gr_line
		(start 170.63593 -10.010902)
		(end 171.27093 -10.010902)
		(stroke
			(width 0.508)
			(type default)
		)
		(layer "In4.Cu")
	)
	(gr_line
		(start 170.63593 -5.910834)
		(end 171.27093 -5.910834)
		(stroke
			(width 0.508)
			(type default)
		)
		(layer "In4.Cu")
	)
	(gr_line
		(start 170.63593 -5.810758)
		(end 171.27093 -5.810758)
		(stroke
			(width 0.508)
			(type default)
		)
		(layer "In4.Cu")
	)
	(gr_line
		(start 170.642788 -12.360148)
		(end 171.277788 -12.360148)
		(stroke
			(width 0.508)
			(type default)
		)
		(layer "In4.Cu")
	)
	(gr_line
		(start 170.642788 -12.260072)
		(end 171.277788 -12.260072)
		(stroke
			(width 0.508)
			(type default)
		)
		(layer "In4.Cu")
	)
	(gr_line
		(start 170.642788 -12.233148)
		(end 170.642788 -10.251948)
		(stroke
			(width 0.762)
			(type default)
		)
		(layer "In4.Cu")
	)
	(gr_line
		(start 170.642788 -12.133072)
		(end 170.642788 -10.151872)
		(stroke
			(width 0.762)
			(type default)
		)
		(layer "In4.Cu")
	)
	(gr_line
		(start 170.642788 -10.251948)
		(end 171.277788 -10.251948)
		(stroke
			(width 0.508)
			(type default)
		)
		(layer "In4.Cu")
	)
	(gr_line
		(start 170.642788 -10.151872)
		(end 171.277788 -10.151872)
		(stroke
			(width 0.508)
			(type default)
		)
		(layer "In4.Cu")
	)
	(gr_line
		(start 170.642788 -8.160004)
		(end 171.277788 -8.160004)
		(stroke
			(width 0.508)
			(type default)
		)
		(layer "In4.Cu")
	)
	(gr_line
		(start 170.642788 -8.059928)
		(end 171.277788 -8.059928)
		(stroke
			(width 0.508)
			(type default)
		)
		(layer "In4.Cu")
	)
	(gr_line
		(start 170.642788 -8.033004)
		(end 170.642788 -6.051804)
		(stroke
			(width 0.762)
			(type default)
		)
		(layer "In4.Cu")
	)
	(gr_line
		(start 170.642788 -7.932928)
		(end 170.642788 -5.951728)
		(stroke
			(width 0.762)
			(type default)
		)
		(layer "In4.Cu")
	)
	(gr_line
		(start 170.642788 -6.051804)
		(end 171.277788 -6.051804)
		(stroke
			(width 0.508)
			(type default)
		)
		(layer "In4.Cu")
	)
	(gr_line
		(start 170.642788 -5.951728)
		(end 171.277788 -5.951728)
		(stroke
			(width 0.508)
			(type default)
		)
		(layer "In4.Cu")
	)
	(gr_line
		(start 170.693588 -12.283948)
		(end 170.693588 -10.251948)
		(stroke
			(width 0.254)
			(type default)
		)
		(layer "In4.Cu")
	)
	(gr_line
		(start 170.693588 -12.183872)
		(end 170.693588 -10.151872)
		(stroke
			(width 0.254)
			(type default)
		)
		(layer "In4.Cu")
	)
	(gr_line
		(start 170.693588 -10.251948)
		(end 171.023788 -10.251948)
		(stroke
			(width 0.254)
			(type default)
		)
		(layer "In4.Cu")
	)
	(gr_line
		(start 170.693588 -10.151872)
		(end 171.023788 -10.151872)
		(stroke
			(width 0.254)
			(type default)
		)
		(layer "In4.Cu")
	)
	(gr_line
		(start 170.693588 -8.083804)
		(end 170.693588 -6.051804)
		(stroke
			(width 0.254)
			(type default)
		)
		(layer "In4.Cu")
	)
	(gr_line
		(start 170.693588 -7.983728)
		(end 170.693588 -5.951728)
		(stroke
			(width 0.254)
			(type default)
		)
		(layer "In4.Cu")
	)
	(gr_line
		(start 170.693588 -6.051804)
		(end 171.023788 -6.051804)
		(stroke
			(width 0.254)
			(type default)
		)
		(layer "In4.Cu")
	)
	(gr_line
		(start 170.693588 -5.951728)
		(end 171.023788 -5.951728)
		(stroke
			(width 0.254)
			(type default)
		)
		(layer "In4.Cu")
	)
	(gr_line
		(start 170.795188 -12.207748)
		(end 170.795188 -10.404348)
		(stroke
			(width 0.254)
			(type default)
		)
		(layer "In4.Cu")
	)
	(gr_line
		(start 170.795188 -12.207748)
		(end 170.795188 -10.226548)
		(stroke
			(width 0.762)
			(type default)
		)
		(layer "In4.Cu")
	)
	(gr_line
		(start 170.795188 -12.107672)
		(end 170.795188 -10.304272)
		(stroke
			(width 0.254)
			(type default)
		)
		(layer "In4.Cu")
	)
	(gr_line
		(start 170.795188 -12.107672)
		(end 170.795188 -10.126472)
		(stroke
			(width 0.762)
			(type default)
		)
		(layer "In4.Cu")
	)
	(gr_line
		(start 170.795188 -10.404348)
		(end 170.896788 -10.404348)
		(stroke
			(width 0.254)
			(type default)
		)
		(layer "In4.Cu")
	)
	(gr_line
		(start 170.795188 -10.304272)
		(end 170.896788 -10.304272)
		(stroke
			(width 0.254)
			(type default)
		)
		(layer "In4.Cu")
	)
	(gr_line
		(start 170.795188 -8.007604)
		(end 170.795188 -6.204204)
		(stroke
			(width 0.254)
			(type default)
		)
		(layer "In4.Cu")
	)
	(gr_line
		(start 170.795188 -8.007604)
		(end 170.795188 -6.026404)
		(stroke
			(width 0.762)
			(type default)
		)
		(layer "In4.Cu")
	)
	(gr_line
		(start 170.795188 -7.907528)
		(end 170.795188 -6.104128)
		(stroke
			(width 0.254)
			(type default)
		)
		(layer "In4.Cu")
	)
	(gr_line
		(start 170.795188 -7.907528)
		(end 170.795188 -5.926328)
		(stroke
			(width 0.762)
			(type default)
		)
		(layer "In4.Cu")
	)
	(gr_line
		(start 170.795188 -6.204204)
		(end 170.896788 -6.204204)
		(stroke
			(width 0.254)
			(type default)
		)
		(layer "In4.Cu")
	)
	(gr_line
		(start 170.795188 -6.104128)
		(end 170.896788 -6.104128)
		(stroke
			(width 0.254)
			(type default)
		)
		(layer "In4.Cu")
	)
	(gr_line
		(start 170.896788 -12.309348)
		(end 170.845988 -12.309348)
		(stroke
			(width 0.254)
			(type default)
		)
		(layer "In4.Cu")
	)
	(gr_line
		(start 170.896788 -12.209272)
		(end 170.845988 -12.209272)
		(stroke
			(width 0.254)
			(type default)
		)
		(layer "In4.Cu")
	)
	(gr_line
		(start 170.896788 -10.404348)
		(end 170.896788 -12.309348)
		(stroke
			(width 0.254)
			(type default)
		)
		(layer "In4.Cu")
	)
	(gr_line
		(start 170.896788 -10.304272)
		(end 170.896788 -12.209272)
		(stroke
			(width 0.254)
			(type default)
		)
		(layer "In4.Cu")
	)
	(gr_line
		(start 170.896788 -8.109204)
		(end 170.845988 -8.109204)
		(stroke
			(width 0.254)
			(type default)
		)
		(layer "In4.Cu")
	)
	(gr_line
		(start 170.896788 -8.009128)
		(end 170.845988 -8.009128)
		(stroke
			(width 0.254)
			(type default)
		)
		(layer "In4.Cu")
	)
	(gr_line
		(start 170.896788 -6.204204)
		(end 170.896788 -8.109204)
		(stroke
			(width 0.254)
			(type default)
		)
		(layer "In4.Cu")
	)
	(gr_line
		(start 170.896788 -6.104128)
		(end 170.896788 -8.009128)
		(stroke
			(width 0.254)
			(type default)
		)
		(layer "In4.Cu")
	)
	(gr_line
		(start 170.947588 -12.233148)
		(end 170.947588 -10.251948)
		(stroke
			(width 0.762)
			(type default)
		)
		(layer "In4.Cu")
	)
	(gr_line
		(start 170.947588 -12.133072)
		(end 170.947588 -10.151872)
		(stroke
			(width 0.762)
			(type default)
		)
		(layer "In4.Cu")
	)
	(gr_line
		(start 170.947588 -8.033004)
		(end 170.947588 -6.051804)
		(stroke
			(width 0.762)
			(type default)
		)
		(layer "In4.Cu")
	)
	(gr_line
		(start 170.947588 -7.932928)
		(end 170.947588 -5.951728)
		(stroke
			(width 0.762)
			(type default)
		)
		(layer "In4.Cu")
	)
	(gr_line
		(start 171.023788 -12.207748)
		(end 170.795188 -12.207748)
		(stroke
			(width 0.254)
			(type default)
		)
		(layer "In4.Cu")
	)
	(gr_line
		(start 171.023788 -12.107672)
		(end 170.795188 -12.107672)
		(stroke
			(width 0.254)
			(type default)
		)
		(layer "In4.Cu")
	)
	(gr_line
		(start 171.023788 -10.251948)
		(end 171.023788 -12.207748)
		(stroke
			(width 0.254)
			(type default)
		)
		(layer "In4.Cu")
	)
	(gr_line
		(start 171.023788 -10.151872)
		(end 171.023788 -12.107672)
		(stroke
			(width 0.254)
			(type default)
		)
		(layer "In4.Cu")
	)
	(gr_line
		(start 171.023788 -8.007604)
		(end 170.795188 -8.007604)
		(stroke
			(width 0.254)
			(type default)
		)
		(layer "In4.Cu")
	)
	(gr_line
		(start 171.023788 -7.907528)
		(end 170.795188 -7.907528)
		(stroke
			(width 0.254)
			(type default)
		)
		(layer "In4.Cu")
	)
	(gr_line
		(start 171.023788 -6.051804)
		(end 171.023788 -8.007604)
		(stroke
			(width 0.254)
			(type default)
		)
		(layer "In4.Cu")
	)
	(gr_line
		(start 171.023788 -5.951728)
		(end 171.023788 -7.907528)
		(stroke
			(width 0.254)
			(type default)
		)
		(layer "In4.Cu")
	)
	(gr_line
		(start 171.074588 -12.563348)
		(end 171.074588 -12.512548)
		(stroke
			(width 0.1016)
			(type default)
		)
		(layer "In4.Cu")
	)
	(gr_line
		(start 171.074588 -12.563348)
		(end 171.480988 -12.563348)
		(stroke
			(width 0.1016)
			(type default)
		)
		(layer "In4.Cu")
	)
	(gr_line
		(start 171.074588 -12.512548)
		(end 170.312588 -12.512548)
		(stroke
			(width 0.1016)
			(type default)
		)
		(layer "In4.Cu")
	)
	(gr_line
		(start 171.074588 -12.463272)
		(end 171.074588 -12.412472)
		(stroke
			(width 0.1016)
			(type default)
		)
		(layer "In4.Cu")
	)
	(gr_line
		(start 171.074588 -12.463272)
		(end 171.480988 -12.463272)
		(stroke
			(width 0.1016)
			(type default)
		)
		(layer "In4.Cu")
	)
	(gr_line
		(start 171.074588 -12.412472)
		(end 170.312588 -12.412472)
		(stroke
			(width 0.1016)
			(type default)
		)
		(layer "In4.Cu")
	)
	(gr_line
		(start 171.074588 -12.233148)
		(end 171.074588 -10.251948)
		(stroke
			(width 0.762)
			(type default)
		)
		(layer "In4.Cu")
	)
	(gr_line
		(start 171.074588 -12.133072)
		(end 171.074588 -10.151872)
		(stroke
			(width 0.762)
			(type default)
		)
		(layer "In4.Cu")
	)
	(gr_line
		(start 171.074588 -8.363204)
		(end 171.074588 -8.312404)
		(stroke
			(width 0.1016)
			(type default)
		)
		(layer "In4.Cu")
	)
	(gr_line
		(start 171.074588 -8.363204)
		(end 171.480988 -8.363204)
		(stroke
			(width 0.1016)
			(type default)
		)
		(layer "In4.Cu")
	)
	(gr_line
		(start 171.074588 -8.312404)
		(end 170.312588 -8.312404)
		(stroke
			(width 0.1016)
			(type default)
		)
		(layer "In4.Cu")
	)
	(gr_line
		(start 171.074588 -8.263128)
		(end 171.074588 -8.212328)
		(stroke
			(width 0.1016)
			(type default)
		)
		(layer "In4.Cu")
	)
	(gr_line
		(start 171.074588 -8.263128)
		(end 171.480988 -8.263128)
		(stroke
			(width 0.1016)
			(type default)
		)
		(layer "In4.Cu")
	)
	(gr_line
		(start 171.074588 -8.212328)
		(end 170.312588 -8.212328)
		(stroke
			(width 0.1016)
			(type default)
		)
		(layer "In4.Cu")
	)
	(gr_line
		(start 171.074588 -8.033004)
		(end 171.074588 -6.051804)
		(stroke
			(width 0.762)
			(type default)
		)
		(layer "In4.Cu")
	)
	(gr_line
		(start 171.074588 -7.932928)
		(end 171.074588 -5.951728)
		(stroke
			(width 0.762)
			(type default)
		)
		(layer "In4.Cu")
	)
	(gr_line
		(start 171.099988 -12.283948)
		(end 170.693588 -12.283948)
		(stroke
			(width 0.254)
			(type default)
		)
		(layer "In4.Cu")
	)
	(gr_line
		(start 171.099988 -12.183872)
		(end 170.693588 -12.183872)
		(stroke
			(width 0.254)
			(type default)
		)
		(layer "In4.Cu")
	)
	(gr_line
		(start 171.099988 -10.175748)
		(end 171.099988 -12.283948)
		(stroke
			(width 0.254)
			(type default)
		)
		(layer "In4.Cu")
	)
	(gr_line
		(start 171.099988 -10.075672)
		(end 171.099988 -12.183872)
		(stroke
			(width 0.254)
			(type default)
		)
		(layer "In4.Cu")
	)
	(gr_line
		(start 171.099988 -8.083804)
		(end 170.693588 -8.083804)
		(stroke
			(width 0.254)
			(type default)
		)
		(layer "In4.Cu")
	)
	(gr_line
		(start 171.099988 -7.983728)
		(end 170.693588 -7.983728)
		(stroke
			(width 0.254)
			(type default)
		)
		(layer "In4.Cu")
	)
	(gr_line
		(start 171.099988 -5.975604)
		(end 171.099988 -8.083804)
		(stroke
			(width 0.254)
			(type default)
		)
		(layer "In4.Cu")
	)
	(gr_line
		(start 171.099988 -5.875528)
		(end 171.099988 -7.983728)
		(stroke
			(width 0.254)
			(type default)
		)
		(layer "In4.Cu")
	)
	(gr_line
		(start 171.150788 -12.233148)
		(end 171.150788 -10.251948)
		(stroke
			(width 0.762)
			(type default)
		)
		(layer "In4.Cu")
	)
	(gr_line
		(start 171.150788 -12.133072)
		(end 171.150788 -10.151872)
		(stroke
			(width 0.762)
			(type default)
		)
		(layer "In4.Cu")
	)
	(gr_line
		(start 171.150788 -8.033004)
		(end 171.150788 -6.051804)
		(stroke
			(width 0.762)
			(type default)
		)
		(layer "In4.Cu")
	)
	(gr_line
		(start 171.150788 -7.932928)
		(end 171.150788 -5.951728)
		(stroke
			(width 0.762)
			(type default)
		)
		(layer "In4.Cu")
	)
	(gr_line
		(start 171.176188 -12.360148)
		(end 170.617388 -12.360148)
		(stroke
			(width 0.254)
			(type default)
		)
		(layer "In4.Cu")
	)
	(gr_line
		(start 171.176188 -12.260072)
		(end 170.617388 -12.260072)
		(stroke
			(width 0.254)
			(type default)
		)
		(layer "In4.Cu")
	)
	(gr_line
		(start 171.176188 -10.124948)
		(end 171.176188 -12.360148)
		(stroke
			(width 0.254)
			(type default)
		)
		(layer "In4.Cu")
	)
	(gr_line
		(start 171.176188 -10.024872)
		(end 171.176188 -12.260072)
		(stroke
			(width 0.254)
			(type default)
		)
		(layer "In4.Cu")
	)
	(gr_line
		(start 171.176188 -8.160004)
		(end 170.617388 -8.160004)
		(stroke
			(width 0.254)
			(type default)
		)
		(layer "In4.Cu")
	)
	(gr_line
		(start 171.176188 -8.059928)
		(end 170.617388 -8.059928)
		(stroke
			(width 0.254)
			(type default)
		)
		(layer "In4.Cu")
	)
	(gr_line
		(start 171.176188 -5.924804)
		(end 171.176188 -8.160004)
		(stroke
			(width 0.254)
			(type default)
		)
		(layer "In4.Cu")
	)
	(gr_line
		(start 171.176188 -5.824728)
		(end 171.176188 -8.059928)
		(stroke
			(width 0.254)
			(type default)
		)
		(layer "In4.Cu")
	)
	(gr_line
		(start 171.252388 -12.385548)
		(end 170.541188 -12.385548)
		(stroke
			(width 0.254)
			(type default)
		)
		(layer "In4.Cu")
	)
	(gr_line
		(start 171.252388 -12.285472)
		(end 170.541188 -12.285472)
		(stroke
			(width 0.254)
			(type default)
		)
		(layer "In4.Cu")
	)
	(gr_line
		(start 171.252388 -10.048748)
		(end 171.252388 -12.385548)
		(stroke
			(width 0.254)
			(type default)
		)
		(layer "In4.Cu")
	)
	(gr_line
		(start 171.252388 -9.948672)
		(end 171.252388 -12.285472)
		(stroke
			(width 0.254)
			(type default)
		)
		(layer "In4.Cu")
	)
	(gr_line
		(start 171.252388 -8.185404)
		(end 170.541188 -8.185404)
		(stroke
			(width 0.254)
			(type default)
		)
		(layer "In4.Cu")
	)
	(gr_line
		(start 171.252388 -8.085328)
		(end 170.541188 -8.085328)
		(stroke
			(width 0.254)
			(type default)
		)
		(layer "In4.Cu")
	)
	(gr_line
		(start 171.252388 -5.848604)
		(end 171.252388 -8.185404)
		(stroke
			(width 0.254)
			(type default)
		)
		(layer "In4.Cu")
	)
	(gr_line
		(start 171.252388 -5.748528)
		(end 171.252388 -8.085328)
		(stroke
			(width 0.254)
			(type default)
		)
		(layer "In4.Cu")
	)
	(gr_line
		(start 171.277788 -12.512548)
		(end 170.287188 -12.512548)
		(stroke
			(width 0.1016)
			(type default)
		)
		(layer "In4.Cu")
	)
	(gr_line
		(start 171.277788 -12.436348)
		(end 170.464988 -12.436348)
		(stroke
			(width 0.254)
			(type default)
		)
		(layer "In4.Cu")
	)
	(gr_line
		(start 171.277788 -12.412472)
		(end 170.287188 -12.412472)
		(stroke
			(width 0.1016)
			(type default)
		)
		(layer "In4.Cu")
	)
	(gr_line
		(start 171.277788 -12.336272)
		(end 170.464988 -12.336272)
		(stroke
			(width 0.254)
			(type default)
		)
		(layer "In4.Cu")
	)
	(gr_line
		(start 171.277788 -10.023348)
		(end 171.277788 -12.436348)
		(stroke
			(width 0.254)
			(type default)
		)
		(layer "In4.Cu")
	)
	(gr_line
		(start 171.277788 -9.923272)
		(end 171.277788 -12.336272)
		(stroke
			(width 0.254)
			(type default)
		)
		(layer "In4.Cu")
	)
	(gr_line
		(start 171.277788 -8.312404)
		(end 170.287188 -8.312404)
		(stroke
			(width 0.1016)
			(type default)
		)
		(layer "In4.Cu")
	)
	(gr_line
		(start 171.277788 -8.236204)
		(end 170.464988 -8.236204)
		(stroke
			(width 0.254)
			(type default)
		)
		(layer "In4.Cu")
	)
	(gr_line
		(start 171.277788 -8.212328)
		(end 170.287188 -8.212328)
		(stroke
			(width 0.1016)
			(type default)
		)
		(layer "In4.Cu")
	)
	(gr_line
		(start 171.277788 -8.136128)
		(end 170.464988 -8.136128)
		(stroke
			(width 0.254)
			(type default)
		)
		(layer "In4.Cu")
	)
	(gr_line
		(start 171.277788 -5.823204)
		(end 171.277788 -8.236204)
		(stroke
			(width 0.254)
			(type default)
		)
		(layer "In4.Cu")
	)
	(gr_line
		(start 171.277788 -5.723128)
		(end 171.277788 -8.136128)
		(stroke
			(width 0.254)
			(type default)
		)
		(layer "In4.Cu")
	)
	(gr_line
		(start 171.303188 -12.461748)
		(end 170.439588 -12.461748)
		(stroke
			(width 0.254)
			(type default)
		)
		(layer "In4.Cu")
	)
	(gr_line
		(start 171.303188 -12.361672)
		(end 170.439588 -12.361672)
		(stroke
			(width 0.254)
			(type default)
		)
		(layer "In4.Cu")
	)
	(gr_line
		(start 171.303188 -9.997948)
		(end 171.303188 -12.461748)
		(stroke
			(width 0.254)
			(type default)
		)
		(layer "In4.Cu")
	)
	(gr_line
		(start 171.303188 -9.897872)
		(end 171.303188 -12.361672)
		(stroke
			(width 0.254)
			(type default)
		)
		(layer "In4.Cu")
	)
	(gr_line
		(start 171.303188 -8.261604)
		(end 170.439588 -8.261604)
		(stroke
			(width 0.254)
			(type default)
		)
		(layer "In4.Cu")
	)
	(gr_line
		(start 171.303188 -8.161528)
		(end 170.439588 -8.161528)
		(stroke
			(width 0.254)
			(type default)
		)
		(layer "In4.Cu")
	)
	(gr_line
		(start 171.303188 -5.797804)
		(end 171.303188 -8.261604)
		(stroke
			(width 0.254)
			(type default)
		)
		(layer "In4.Cu")
	)
	(gr_line
		(start 171.303188 -5.697728)
		(end 171.303188 -8.161528)
		(stroke
			(width 0.254)
			(type default)
		)
		(layer "In4.Cu")
	)
	(gr_line
		(start 171.353988 -12.487148)
		(end 170.414188 -12.487148)
		(stroke
			(width 0.254)
			(type default)
		)
		(layer "In4.Cu")
	)
	(gr_line
		(start 171.353988 -12.387072)
		(end 170.414188 -12.387072)
		(stroke
			(width 0.254)
			(type default)
		)
		(layer "In4.Cu")
	)
	(gr_line
		(start 171.353988 -9.997948)
		(end 171.353988 -12.487148)
		(stroke
			(width 0.254)
			(type default)
		)
		(layer "In4.Cu")
	)
	(gr_line
		(start 171.353988 -9.897872)
		(end 171.353988 -12.387072)
		(stroke
			(width 0.254)
			(type default)
		)
		(layer "In4.Cu")
	)
	(gr_line
		(start 171.353988 -8.287004)
		(end 170.414188 -8.287004)
		(stroke
			(width 0.254)
			(type default)
		)
		(layer "In4.Cu")
	)
	(gr_line
		(start 171.353988 -8.186928)
		(end 170.414188 -8.186928)
		(stroke
			(width 0.254)
			(type default)
		)
		(layer "In4.Cu")
	)
	(gr_line
		(start 171.353988 -5.797804)
		(end 171.353988 -8.287004)
		(stroke
			(width 0.254)
			(type default)
		)
		(layer "In4.Cu")
	)
	(gr_line
		(start 171.353988 -5.697728)
		(end 171.353988 -8.186928)
		(stroke
			(width 0.254)
			(type default)
		)
		(layer "In4.Cu")
	)
	(gr_line
		(start 171.379388 -12.487148)
		(end 170.414188 -12.487148)
		(stroke
			(width 0.2032)
			(type default)
		)
		(layer "In4.Cu")
	)
	(gr_line
		(start 171.379388 -12.387072)
		(end 170.414188 -12.387072)
		(stroke
			(width 0.2032)
			(type default)
		)
		(layer "In4.Cu")
	)
	(gr_line
		(start 171.379388 -9.947148)
		(end 171.379388 -12.487148)
		(stroke
			(width 0.2032)
			(type default)
		)
		(layer "In4.Cu")
	)
	(gr_line
		(start 171.379388 -9.847072)
		(end 171.379388 -12.387072)
		(stroke
			(width 0.2032)
			(type default)
		)
		(layer "In4.Cu")
	)
	(gr_line
		(start 171.379388 -8.287004)
		(end 170.414188 -8.287004)
		(stroke
			(width 0.2032)
			(type default)
		)
		(layer "In4.Cu")
	)
	(gr_line
		(start 171.379388 -8.186928)
		(end 170.414188 -8.186928)
		(stroke
			(width 0.2032)
			(type default)
		)
		(layer "In4.Cu")
	)
	(gr_line
		(start 171.379388 -5.747004)
		(end 171.379388 -8.287004)
		(stroke
			(width 0.2032)
			(type default)
		)
		(layer "In4.Cu")
	)
	(gr_line
		(start 171.379388 -5.646928)
		(end 171.379388 -8.186928)
		(stroke
			(width 0.2032)
			(type default)
		)
		(layer "In4.Cu")
	)
	(gr_line
		(start 171.430188 -12.512548)
		(end 170.363388 -12.512548)
		(stroke
			(width 0.2032)
			(type default)
		)
		(layer "In4.Cu")
	)
	(gr_line
		(start 171.430188 -12.412472)
		(end 170.363388 -12.412472)
		(stroke
			(width 0.2032)
			(type default)
		)
		(layer "In4.Cu")
	)
	(gr_line
		(start 171.430188 -9.947148)
		(end 171.430188 -12.512548)
		(stroke
			(width 0.2032)
			(type default)
		)
		(layer "In4.Cu")
	)
	(gr_line
		(start 171.430188 -9.847072)
		(end 171.430188 -12.412472)
		(stroke
			(width 0.2032)
			(type default)
		)
		(layer "In4.Cu")
	)
	(gr_line
		(start 171.430188 -8.312404)
		(end 170.363388 -8.312404)
		(stroke
			(width 0.2032)
			(type default)
		)
		(layer "In4.Cu")
	)
	(gr_line
		(start 171.430188 -8.212328)
		(end 170.363388 -8.212328)
		(stroke
			(width 0.2032)
			(type default)
		)
		(layer "In4.Cu")
	)
	(gr_line
		(start 171.430188 -5.747004)
		(end 171.430188 -8.312404)
		(stroke
			(width 0.2032)
			(type default)
		)
		(layer "In4.Cu")
	)
	(gr_line
		(start 171.430188 -5.646928)
		(end 171.430188 -8.212328)
		(stroke
			(width 0.2032)
			(type default)
		)
		(layer "In4.Cu")
	)
	(gr_line
		(start 171.455588 -12.512548)
		(end 170.337988 -12.512548)
		(stroke
			(width 0.1016)
			(type default)
		)
		(layer "In4.Cu")
	)
	(gr_line
		(start 171.455588 -12.412472)
		(end 170.337988 -12.412472)
		(stroke
			(width 0.1016)
			(type default)
		)
		(layer "In4.Cu")
	)
	(gr_line
		(start 171.455588 -9.921748)
		(end 171.455588 -12.512548)
		(stroke
			(width 0.1016)
			(type default)
		)
		(layer "In4.Cu")
	)
	(gr_line
		(start 171.455588 -9.821672)
		(end 171.455588 -12.412472)
		(stroke
			(width 0.1016)
			(type default)
		)
		(layer "In4.Cu")
	)
	(gr_line
		(start 171.455588 -8.312404)
		(end 170.337988 -8.312404)
		(stroke
			(width 0.1016)
			(type default)
		)
		(layer "In4.Cu")
	)
	(gr_line
		(start 171.455588 -8.212328)
		(end 170.337988 -8.212328)
		(stroke
			(width 0.1016)
			(type default)
		)
		(layer "In4.Cu")
	)
	(gr_line
		(start 171.455588 -5.721604)
		(end 171.455588 -8.312404)
		(stroke
			(width 0.1016)
			(type default)
		)
		(layer "In4.Cu")
	)
	(gr_line
		(start 171.455588 -5.621528)
		(end 171.455588 -8.212328)
		(stroke
			(width 0.1016)
			(type default)
		)
		(layer "In4.Cu")
	)
	(gr_line
		(start 171.480988 -12.563348)
		(end 171.074588 -12.563348)
		(stroke
			(width 0.1016)
			(type default)
		)
		(layer "In4.Cu")
	)
	(gr_line
		(start 171.480988 -12.563348)
		(end 171.480988 -9.896348)
		(stroke
			(width 0.1016)
			(type default)
		)
		(layer "In4.Cu")
	)
	(gr_line
		(start 171.480988 -12.463272)
		(end 171.074588 -12.463272)
		(stroke
			(width 0.1016)
			(type default)
		)
		(layer "In4.Cu")
	)
	(gr_line
		(start 171.480988 -12.463272)
		(end 171.480988 -9.796272)
		(stroke
			(width 0.1016)
			(type default)
		)
		(layer "In4.Cu")
	)
	(gr_line
		(start 171.480988 -9.896348)
		(end 170.287188 -9.896348)
		(stroke
			(width 0.1016)
			(type default)
		)
		(layer "In4.Cu")
	)
	(gr_line
		(start 171.480988 -9.896348)
		(end 171.480988 -12.563348)
		(stroke
			(width 0.1016)
			(type default)
		)
		(layer "In4.Cu")
	)
	(gr_line
		(start 171.480988 -9.796272)
		(end 170.287188 -9.796272)
		(stroke
			(width 0.1016)
			(type default)
		)
		(layer "In4.Cu")
	)
	(gr_line
		(start 171.480988 -9.796272)
		(end 171.480988 -12.463272)
		(stroke
			(width 0.1016)
			(type default)
		)
		(layer "In4.Cu")
	)
	(gr_line
		(start 171.480988 -8.363204)
		(end 171.074588 -8.363204)
		(stroke
			(width 0.1016)
			(type default)
		)
		(layer "In4.Cu")
	)
	(gr_line
		(start 171.480988 -8.363204)
		(end 171.480988 -5.696204)
		(stroke
			(width 0.1016)
			(type default)
		)
		(layer "In4.Cu")
	)
	(gr_line
		(start 171.480988 -8.263128)
		(end 171.074588 -8.263128)
		(stroke
			(width 0.1016)
			(type default)
		)
		(layer "In4.Cu")
	)
	(gr_line
		(start 171.480988 -8.263128)
		(end 171.480988 -5.596128)
		(stroke
			(width 0.1016)
			(type default)
		)
		(layer "In4.Cu")
	)
	(gr_line
		(start 171.480988 -5.696204)
		(end 170.287188 -5.696204)
		(stroke
			(width 0.1016)
			(type default)
		)
		(layer "In4.Cu")
	)
	(gr_line
		(start 171.480988 -5.696204)
		(end 171.480988 -8.363204)
		(stroke
			(width 0.1016)
			(type default)
		)
		(layer "In4.Cu")
	)
	(gr_line
		(start 171.480988 -5.596128)
		(end 170.287188 -5.596128)
		(stroke
			(width 0.1016)
			(type default)
		)
		(layer "In4.Cu")
	)
	(gr_line
		(start 171.480988 -5.596128)
		(end 171.480988 -8.263128)
		(stroke
			(width 0.1016)
			(type default)
		)
		(layer "In4.Cu")
	)
	(gr_line
		(start 171.720002 -31.98622)
		(end 170.450002 -31.98622)
		(stroke
			(width 0.7874)
			(type default)
		)
		(layer "In4.Cu")
	)
	(gr_line
		(start 172.120052 -23.69566)
		(end 170.850052 -23.69566)
		(stroke
			(width 0.7874)
			(type default)
		)
		(layer "In4.Cu")
	)
	(gr_line
		(start 172.287184 -13.8176)
		(end 173.074584 -13.8176)
		(stroke
			(width 0.1016)
			(type default)
		)
		(layer "In4.Cu")
	)
	(gr_line
		(start 172.287184 -13.7668)
		(end 172.287184 -11.1506)
		(stroke
			(width 0.1016)
			(type default)
		)
		(layer "In4.Cu")
	)
	(gr_line
		(start 172.287184 -11.1506)
		(end 172.287184 -13.8176)
		(stroke
			(width 0.1016)
			(type default)
		)
		(layer "In4.Cu")
	)
	(gr_line
		(start 172.287184 -11.1506)
		(end 173.480984 -11.1506)
		(stroke
			(width 0.1016)
			(type default)
		)
		(layer "In4.Cu")
	)
	(gr_line
		(start 172.287184 -9.617456)
		(end 173.074584 -9.617456)
		(stroke
			(width 0.1016)
			(type default)
		)
		(layer "In4.Cu")
	)
	(gr_line
		(start 172.287184 -9.566656)
		(end 172.287184 -6.950456)
		(stroke
			(width 0.1016)
			(type default)
		)
		(layer "In4.Cu")
	)
	(gr_line
		(start 172.287184 -6.950456)
		(end 172.287184 -9.617456)
		(stroke
			(width 0.1016)
			(type default)
		)
		(layer "In4.Cu")
	)
	(gr_line
		(start 172.287184 -6.950456)
		(end 173.480984 -6.950456)
		(stroke
			(width 0.1016)
			(type default)
		)
		(layer "In4.Cu")
	)
	(gr_line
		(start 172.287184 -5.417312)
		(end 173.074584 -5.417312)
		(stroke
			(width 0.1016)
			(type default)
		)
		(layer "In4.Cu")
	)
	(gr_line
		(start 172.287184 -5.366512)
		(end 172.287184 -2.750312)
		(stroke
			(width 0.1016)
			(type default)
		)
		(layer "In4.Cu")
	)
	(gr_line
		(start 172.287184 -2.750312)
		(end 172.287184 -5.417312)
		(stroke
			(width 0.1016)
			(type default)
		)
		(layer "In4.Cu")
	)
	(gr_line
		(start 172.287184 -2.750312)
		(end 173.480984 -2.750312)
		(stroke
			(width 0.1016)
			(type default)
		)
		(layer "In4.Cu")
	)
	(gr_line
		(start 172.312584 -13.7668)
		(end 172.312584 -11.176)
		(stroke
			(width 0.1016)
			(type default)
		)
		(layer "In4.Cu")
	)
	(gr_line
		(start 172.312584 -11.176)
		(end 173.455584 -11.176)
		(stroke
			(width 0.1016)
			(type default)
		)
		(layer "In4.Cu")
	)
	(gr_line
		(start 172.312584 -9.566656)
		(end 172.312584 -6.975856)
		(stroke
			(width 0.1016)
			(type default)
		)
		(layer "In4.Cu")
	)
	(gr_line
		(start 172.312584 -6.975856)
		(end 173.455584 -6.975856)
		(stroke
			(width 0.1016)
			(type default)
		)
		(layer "In4.Cu")
	)
	(gr_line
		(start 172.312584 -5.366512)
		(end 172.312584 -2.775712)
		(stroke
			(width 0.1016)
			(type default)
		)
		(layer "In4.Cu")
	)
	(gr_line
		(start 172.312584 -2.775712)
		(end 173.455584 -2.775712)
		(stroke
			(width 0.1016)
			(type default)
		)
		(layer "In4.Cu")
	)
	(gr_line
		(start 172.337984 -13.7668)
		(end 172.337984 -11.2014)
		(stroke
			(width 0.1016)
			(type default)
		)
		(layer "In4.Cu")
	)
	(gr_line
		(start 172.337984 -11.2014)
		(end 172.591984 -11.2014)
		(stroke
			(width 0.1016)
			(type default)
		)
		(layer "In4.Cu")
	)
	(gr_line
		(start 172.337984 -9.566656)
		(end 172.337984 -7.001256)
		(stroke
			(width 0.1016)
			(type default)
		)
		(layer "In4.Cu")
	)
	(gr_line
		(start 172.337984 -7.001256)
		(end 172.591984 -7.001256)
		(stroke
			(width 0.1016)
			(type default)
		)
		(layer "In4.Cu")
	)
	(gr_line
		(start 172.337984 -5.366512)
		(end 172.337984 -2.801112)
		(stroke
			(width 0.1016)
			(type default)
		)
		(layer "In4.Cu")
	)
	(gr_line
		(start 172.337984 -2.801112)
		(end 172.591984 -2.801112)
		(stroke
			(width 0.1016)
			(type default)
		)
		(layer "In4.Cu")
	)
	(gr_line
		(start 172.363384 -13.7668)
		(end 172.363384 -11.2014)
		(stroke
			(width 0.2032)
			(type default)
		)
		(layer "In4.Cu")
	)
	(gr_line
		(start 172.363384 -11.2014)
		(end 173.379384 -11.2014)
		(stroke
			(width 0.2032)
			(type default)
		)
		(layer "In4.Cu")
	)
	(gr_line
		(start 172.363384 -9.566656)
		(end 172.363384 -7.001256)
		(stroke
			(width 0.2032)
			(type default)
		)
		(layer "In4.Cu")
	)
	(gr_line
		(start 172.363384 -7.001256)
		(end 173.379384 -7.001256)
		(stroke
			(width 0.2032)
			(type default)
		)
		(layer "In4.Cu")
	)
	(gr_line
		(start 172.363384 -5.366512)
		(end 172.363384 -2.801112)
		(stroke
			(width 0.2032)
			(type default)
		)
		(layer "In4.Cu")
	)
	(gr_line
		(start 172.363384 -2.801112)
		(end 173.379384 -2.801112)
		(stroke
			(width 0.2032)
			(type default)
		)
		(layer "In4.Cu")
	)
	(gr_line
		(start 172.414184 -13.7414)
		(end 172.414184 -11.2522)
		(stroke
			(width 0.2032)
			(type default)
		)
		(layer "In4.Cu")
	)
	(gr_line
		(start 172.414184 -13.7414)
		(end 172.414184 -11.2522)
		(stroke
			(width 0.254)
			(type default)
		)
		(layer "In4.Cu")
	)
	(gr_line
		(start 172.414184 -11.2522)
		(end 172.617384 -11.2522)
		(stroke
			(width 0.2032)
			(type default)
		)
		(layer "In4.Cu")
	)
	(gr_line
		(start 172.414184 -11.2522)
		(end 173.303184 -11.2522)
		(stroke
			(width 0.254)
			(type default)
		)
		(layer "In4.Cu")
	)
	(gr_line
		(start 172.414184 -9.541256)
		(end 172.414184 -7.052056)
		(stroke
			(width 0.2032)
			(type default)
		)
		(layer "In4.Cu")
	)
	(gr_line
		(start 172.414184 -9.541256)
		(end 172.414184 -7.052056)
		(stroke
			(width 0.254)
			(type default)
		)
		(layer "In4.Cu")
	)
	(gr_line
		(start 172.414184 -7.052056)
		(end 172.617384 -7.052056)
		(stroke
			(width 0.2032)
			(type default)
		)
		(layer "In4.Cu")
	)
	(gr_line
		(start 172.414184 -7.052056)
		(end 173.303184 -7.052056)
		(stroke
			(width 0.254)
			(type default)
		)
		(layer "In4.Cu")
	)
	(gr_line
		(start 172.414184 -5.341112)
		(end 172.414184 -2.851912)
		(stroke
			(width 0.2032)
			(type default)
		)
		(layer "In4.Cu")
	)
	(gr_line
		(start 172.414184 -5.341112)
		(end 172.414184 -2.851912)
		(stroke
			(width 0.254)
			(type default)
		)
		(layer "In4.Cu")
	)
	(gr_line
		(start 172.414184 -2.851912)
		(end 172.617384 -2.851912)
		(stroke
			(width 0.2032)
			(type default)
		)
		(layer "In4.Cu")
	)
	(gr_line
		(start 172.414184 -2.851912)
		(end 173.303184 -2.851912)
		(stroke
			(width 0.254)
			(type default)
		)
		(layer "In4.Cu")
	)
	(gr_line
		(start 172.439584 -13.716)
		(end 172.439584 -11.2776)
		(stroke
			(width 0.254)
			(type default)
		)
		(layer "In4.Cu")
	)
	(gr_line
		(start 172.439584 -11.2776)
		(end 173.277784 -11.2776)
		(stroke
			(width 0.254)
			(type default)
		)
		(layer "In4.Cu")
	)
	(gr_line
		(start 172.439584 -9.515856)
		(end 172.439584 -7.077456)
		(stroke
			(width 0.254)
			(type default)
		)
		(layer "In4.Cu")
	)
	(gr_line
		(start 172.439584 -7.077456)
		(end 173.277784 -7.077456)
		(stroke
			(width 0.254)
			(type default)
		)
		(layer "In4.Cu")
	)
	(gr_line
		(start 172.439584 -5.315712)
		(end 172.439584 -2.877312)
		(stroke
			(width 0.254)
			(type default)
		)
		(layer "In4.Cu")
	)
	(gr_line
		(start 172.439584 -2.877312)
		(end 173.277784 -2.877312)
		(stroke
			(width 0.254)
			(type default)
		)
		(layer "In4.Cu")
	)
	(gr_line
		(start 172.464984 -13.6906)
		(end 172.464984 -11.303)
		(stroke
			(width 0.254)
			(type default)
		)
		(layer "In4.Cu")
	)
	(gr_line
		(start 172.464984 -11.303)
		(end 173.252384 -11.303)
		(stroke
			(width 0.254)
			(type default)
		)
		(layer "In4.Cu")
	)
	(gr_line
		(start 172.464984 -9.490456)
		(end 172.464984 -7.102856)
		(stroke
			(width 0.254)
			(type default)
		)
		(layer "In4.Cu")
	)
	(gr_line
		(start 172.464984 -7.102856)
		(end 173.252384 -7.102856)
		(stroke
			(width 0.254)
			(type default)
		)
		(layer "In4.Cu")
	)
	(gr_line
		(start 172.464984 -5.290312)
		(end 172.464984 -2.902712)
		(stroke
			(width 0.254)
			(type default)
		)
		(layer "In4.Cu")
	)
	(gr_line
		(start 172.464984 -2.902712)
		(end 173.252384 -2.902712)
		(stroke
			(width 0.254)
			(type default)
		)
		(layer "In4.Cu")
	)
	(gr_line
		(start 172.490384 -13.6144)
		(end 173.125384 -13.6144)
		(stroke
			(width 0.508)
			(type default)
		)
		(layer "In4.Cu")
	)
	(gr_line
		(start 172.490384 -11.43)
		(end 173.125384 -11.43)
		(stroke
			(width 0.508)
			(type default)
		)
		(layer "In4.Cu")
	)
	(gr_line
		(start 172.490384 -11.3792)
		(end 173.125384 -11.3792)
		(stroke
			(width 0.508)
			(type default)
		)
		(layer "In4.Cu")
	)
	(gr_line
		(start 172.490384 -9.414256)
		(end 173.125384 -9.414256)
		(stroke
			(width 0.508)
			(type default)
		)
		(layer "In4.Cu")
	)
	(gr_line
		(start 172.490384 -7.229856)
		(end 173.125384 -7.229856)
		(stroke
			(width 0.508)
			(type default)
		)
		(layer "In4.Cu")
	)
	(gr_line
		(start 172.490384 -7.179056)
		(end 173.125384 -7.179056)
		(stroke
			(width 0.508)
			(type default)
		)
		(layer "In4.Cu")
	)
	(gr_line
		(start 172.490384 -5.214112)
		(end 173.125384 -5.214112)
		(stroke
			(width 0.508)
			(type default)
		)
		(layer "In4.Cu")
	)
	(gr_line
		(start 172.490384 -3.029712)
		(end 173.125384 -3.029712)
		(stroke
			(width 0.508)
			(type default)
		)
		(layer "In4.Cu")
	)
	(gr_line
		(start 172.490384 -2.978912)
		(end 173.125384 -2.978912)
		(stroke
			(width 0.508)
			(type default)
		)
		(layer "In4.Cu")
	)
	(gr_line
		(start 172.515784 -11.684)
		(end 173.150784 -11.684)
		(stroke
			(width 0.508)
			(type default)
		)
		(layer "In4.Cu")
	)
	(gr_line
		(start 172.515784 -7.483856)
		(end 173.150784 -7.483856)
		(stroke
			(width 0.508)
			(type default)
		)
		(layer "In4.Cu")
	)
	(gr_line
		(start 172.515784 -3.283712)
		(end 173.150784 -3.283712)
		(stroke
			(width 0.508)
			(type default)
		)
		(layer "In4.Cu")
	)
	(gr_line
		(start 172.541184 -13.6398)
		(end 172.541184 -11.3792)
		(stroke
			(width 0.254)
			(type default)
		)
		(layer "In4.Cu")
	)
	(gr_line
		(start 172.541184 -13.4874)
		(end 173.176184 -13.4874)
		(stroke
			(width 0.508)
			(type default)
		)
		(layer "In4.Cu")
	)
	(gr_line
		(start 172.541184 -11.3792)
		(end 173.176184 -11.3792)
		(stroke
			(width 0.254)
			(type default)
		)
		(layer "In4.Cu")
	)
	(gr_line
		(start 172.541184 -9.439656)
		(end 172.541184 -7.179056)
		(stroke
			(width 0.254)
			(type default)
		)
		(layer "In4.Cu")
	)
	(gr_line
		(start 172.541184 -9.287256)
		(end 173.176184 -9.287256)
		(stroke
			(width 0.508)
			(type default)
		)
		(layer "In4.Cu")
	)
	(gr_line
		(start 172.541184 -7.179056)
		(end 173.176184 -7.179056)
		(stroke
			(width 0.254)
			(type default)
		)
		(layer "In4.Cu")
	)
	(gr_line
		(start 172.541184 -5.239512)
		(end 172.541184 -2.978912)
		(stroke
			(width 0.254)
			(type default)
		)
		(layer "In4.Cu")
	)
	(gr_line
		(start 172.541184 -5.087112)
		(end 173.176184 -5.087112)
		(stroke
			(width 0.508)
			(type default)
		)
		(layer "In4.Cu")
	)
	(gr_line
		(start 172.541184 -2.978912)
		(end 173.176184 -2.978912)
		(stroke
			(width 0.254)
			(type default)
		)
		(layer "In4.Cu")
	)
	(gr_line
		(start 172.566584 -13.335)
		(end 173.201584 -13.335)
		(stroke
			(width 0.508)
			(type default)
		)
		(layer "In4.Cu")
	)
	(gr_line
		(start 172.566584 -9.134856)
		(end 173.201584 -9.134856)
		(stroke
			(width 0.508)
			(type default)
		)
		(layer "In4.Cu")
	)
	(gr_line
		(start 172.566584 -4.934712)
		(end 173.201584 -4.934712)
		(stroke
			(width 0.508)
			(type default)
		)
		(layer "In4.Cu")
	)
	(gr_line
		(start 172.591984 -13.6144)
		(end 173.226984 -13.6144)
		(stroke
			(width 0.508)
			(type default)
		)
		(layer "In4.Cu")
	)
	(gr_line
		(start 172.591984 -11.2014)
		(end 173.430184 -11.2014)
		(stroke
			(width 0.2032)
			(type default)
		)
		(layer "In4.Cu")
	)
	(gr_line
		(start 172.591984 -9.414256)
		(end 173.226984 -9.414256)
		(stroke
			(width 0.508)
			(type default)
		)
		(layer "In4.Cu")
	)
	(gr_line
		(start 172.591984 -7.001256)
		(end 173.430184 -7.001256)
		(stroke
			(width 0.2032)
			(type default)
		)
		(layer "In4.Cu")
	)
	(gr_line
		(start 172.591984 -5.214112)
		(end 173.226984 -5.214112)
		(stroke
			(width 0.508)
			(type default)
		)
		(layer "In4.Cu")
	)
	(gr_line
		(start 172.591984 -2.801112)
		(end 173.430184 -2.801112)
		(stroke
			(width 0.2032)
			(type default)
		)
		(layer "In4.Cu")
	)
	(gr_line
		(start 172.617384 -13.6144)
		(end 172.617384 -11.43)
		(stroke
			(width 0.254)
			(type default)
		)
		(layer "In4.Cu")
	)
	(gr_line
		(start 172.617384 -11.43)
		(end 173.099984 -11.43)
		(stroke
			(width 0.254)
			(type default)
		)
		(layer "In4.Cu")
	)
	(gr_line
		(start 172.617384 -11.2522)
		(end 173.353984 -11.2522)
		(stroke
			(width 0.254)
			(type default)
		)
		(layer "In4.Cu")
	)
	(gr_line
		(start 172.617384 -9.414256)
		(end 172.617384 -7.229856)
		(stroke
			(width 0.254)
			(type default)
		)
		(layer "In4.Cu")
	)
	(gr_line
		(start 172.617384 -7.229856)
		(end 173.099984 -7.229856)
		(stroke
			(width 0.254)
			(type default)
		)
		(layer "In4.Cu")
	)
	(gr_line
		(start 172.617384 -7.052056)
		(end 173.353984 -7.052056)
		(stroke
			(width 0.254)
			(type default)
		)
		(layer "In4.Cu")
	)
	(gr_line
		(start 172.617384 -5.214112)
		(end 172.617384 -3.029712)
		(stroke
			(width 0.254)
			(type default)
		)
		(layer "In4.Cu")
	)
	(gr_line
		(start 172.617384 -3.029712)
		(end 173.099984 -3.029712)
		(stroke
			(width 0.254)
			(type default)
		)
		(layer "In4.Cu")
	)
	(gr_line
		(start 172.617384 -2.851912)
		(end 173.353984 -2.851912)
		(stroke
			(width 0.254)
			(type default)
		)
		(layer "In4.Cu")
	)
	(gr_line
		(start 172.635926 -11.36523)
		(end 173.270926 -11.36523)
		(stroke
			(width 0.508)
			(type default)
		)
		(layer "In4.Cu")
	)
	(gr_line
		(start 172.635926 -7.165086)
		(end 173.270926 -7.165086)
		(stroke
			(width 0.508)
			(type default)
		)
		(layer "In4.Cu")
	)
	(gr_line
		(start 172.635926 -2.964942)
		(end 173.270926 -2.964942)
		(stroke
			(width 0.508)
			(type default)
		)
		(layer "In4.Cu")
	)
	(gr_line
		(start 172.642784 -13.6144)
		(end 173.277784 -13.6144)
		(stroke
			(width 0.508)
			(type default)
		)
		(layer "In4.Cu")
	)
	(gr_line
		(start 172.642784 -13.4874)
		(end 172.642784 -11.5062)
		(stroke
			(width 0.762)
			(type default)
		)
		(layer "In4.Cu")
	)
	(gr_line
		(start 172.642784 -11.5062)
		(end 173.277784 -11.5062)
		(stroke
			(width 0.508)
			(type default)
		)
		(layer "In4.Cu")
	)
	(gr_line
		(start 172.642784 -9.414256)
		(end 173.277784 -9.414256)
		(stroke
			(width 0.508)
			(type default)
		)
		(layer "In4.Cu")
	)
	(gr_line
		(start 172.642784 -9.287256)
		(end 172.642784 -7.306056)
		(stroke
			(width 0.762)
			(type default)
		)
		(layer "In4.Cu")
	)
	(gr_line
		(start 172.642784 -7.306056)
		(end 173.277784 -7.306056)
		(stroke
			(width 0.508)
			(type default)
		)
		(layer "In4.Cu")
	)
	(gr_line
		(start 172.642784 -5.214112)
		(end 173.277784 -5.214112)
		(stroke
			(width 0.508)
			(type default)
		)
		(layer "In4.Cu")
	)
	(gr_line
		(start 172.642784 -5.087112)
		(end 172.642784 -3.105912)
		(stroke
			(width 0.762)
			(type default)
		)
		(layer "In4.Cu")
	)
	(gr_line
		(start 172.642784 -3.105912)
		(end 173.277784 -3.105912)
		(stroke
			(width 0.508)
			(type default)
		)
		(layer "In4.Cu")
	)
	(gr_line
		(start 172.693584 -13.5382)
		(end 172.693584 -11.5062)
		(stroke
			(width 0.254)
			(type default)
		)
		(layer "In4.Cu")
	)
	(gr_line
		(start 172.693584 -11.5062)
		(end 173.023784 -11.5062)
		(stroke
			(width 0.254)
			(type default)
		)
		(layer "In4.Cu")
	)
	(gr_line
		(start 172.693584 -9.338056)
		(end 172.693584 -7.306056)
		(stroke
			(width 0.254)
			(type default)
		)
		(layer "In4.Cu")
	)
	(gr_line
		(start 172.693584 -7.306056)
		(end 173.023784 -7.306056)
		(stroke
			(width 0.254)
			(type default)
		)
		(layer "In4.Cu")
	)
	(gr_line
		(start 172.693584 -5.137912)
		(end 172.693584 -3.105912)
		(stroke
			(width 0.254)
			(type default)
		)
		(layer "In4.Cu")
	)
	(gr_line
		(start 172.693584 -3.105912)
		(end 173.023784 -3.105912)
		(stroke
			(width 0.254)
			(type default)
		)
		(layer "In4.Cu")
	)
	(gr_line
		(start 172.795184 -13.462)
		(end 172.795184 -11.6586)
		(stroke
			(width 0.254)
			(type default)
		)
		(layer "In4.Cu")
	)
	(gr_line
		(start 172.795184 -13.462)
		(end 172.795184 -11.4808)
		(stroke
			(width 0.762)
			(type default)
		)
		(layer "In4.Cu")
	)
	(gr_line
		(start 172.795184 -11.6586)
		(end 172.896784 -11.6586)
		(stroke
			(width 0.254)
			(type default)
		)
		(layer "In4.Cu")
	)
	(gr_line
		(start 172.795184 -9.261856)
		(end 172.795184 -7.458456)
		(stroke
			(width 0.254)
			(type default)
		)
		(layer "In4.Cu")
	)
	(gr_line
		(start 172.795184 -9.261856)
		(end 172.795184 -7.280656)
		(stroke
			(width 0.762)
			(type default)
		)
		(layer "In4.Cu")
	)
	(gr_line
		(start 172.795184 -7.458456)
		(end 172.896784 -7.458456)
		(stroke
			(width 0.254)
			(type default)
		)
		(layer "In4.Cu")
	)
	(gr_line
		(start 172.795184 -5.061712)
		(end 172.795184 -3.258312)
		(stroke
			(width 0.254)
			(type default)
		)
		(layer "In4.Cu")
	)
	(gr_line
		(start 172.795184 -5.061712)
		(end 172.795184 -3.080512)
		(stroke
			(width 0.762)
			(type default)
		)
		(layer "In4.Cu")
	)
	(gr_line
		(start 172.795184 -3.258312)
		(end 172.896784 -3.258312)
		(stroke
			(width 0.254)
			(type default)
		)
		(layer "In4.Cu")
	)
	(gr_line
		(start 172.896784 -13.5636)
		(end 172.845984 -13.5636)
		(stroke
			(width 0.254)
			(type default)
		)
		(layer "In4.Cu")
	)
	(gr_line
		(start 172.896784 -11.6586)
		(end 172.896784 -13.5636)
		(stroke
			(width 0.254)
			(type default)
		)
		(layer "In4.Cu")
	)
	(gr_line
		(start 172.896784 -9.363456)
		(end 172.845984 -9.363456)
		(stroke
			(width 0.254)
			(type default)
		)
		(layer "In4.Cu")
	)
	(gr_line
		(start 172.896784 -7.458456)
		(end 172.896784 -9.363456)
		(stroke
			(width 0.254)
			(type default)
		)
		(layer "In4.Cu")
	)
	(gr_line
		(start 172.896784 -5.163312)
		(end 172.845984 -5.163312)
		(stroke
			(width 0.254)
			(type default)
		)
		(layer "In4.Cu")
	)
	(gr_line
		(start 172.896784 -3.258312)
		(end 172.896784 -5.163312)
		(stroke
			(width 0.254)
			(type default)
		)
		(layer "In4.Cu")
	)
	(gr_line
		(start 172.947584 -13.4874)
		(end 172.947584 -11.5062)
		(stroke
			(width 0.762)
			(type default)
		)
		(layer "In4.Cu")
	)
	(gr_line
		(start 172.947584 -9.287256)
		(end 172.947584 -7.306056)
		(stroke
			(width 0.762)
			(type default)
		)
		(layer "In4.Cu")
	)
	(gr_line
		(start 172.947584 -5.087112)
		(end 172.947584 -3.105912)
		(stroke
			(width 0.762)
			(type default)
		)
		(layer "In4.Cu")
	)
	(gr_line
		(start 173.023784 -13.462)
		(end 172.795184 -13.462)
		(stroke
			(width 0.254)
			(type default)
		)
		(layer "In4.Cu")
	)
	(gr_line
		(start 173.023784 -11.5062)
		(end 173.023784 -13.462)
		(stroke
			(width 0.254)
			(type default)
		)
		(layer "In4.Cu")
	)
	(gr_line
		(start 173.023784 -9.261856)
		(end 172.795184 -9.261856)
		(stroke
			(width 0.254)
			(type default)
		)
		(layer "In4.Cu")
	)
	(gr_line
		(start 173.023784 -7.306056)
		(end 173.023784 -9.261856)
		(stroke
			(width 0.254)
			(type default)
		)
		(layer "In4.Cu")
	)
	(gr_line
		(start 173.023784 -5.061712)
		(end 172.795184 -5.061712)
		(stroke
			(width 0.254)
			(type default)
		)
		(layer "In4.Cu")
	)
	(gr_line
		(start 173.023784 -3.105912)
		(end 173.023784 -5.061712)
		(stroke
			(width 0.254)
			(type default)
		)
		(layer "In4.Cu")
	)
	(gr_line
		(start 173.074584 -13.8176)
		(end 173.074584 -13.7668)
		(stroke
			(width 0.1016)
			(type default)
		)
		(layer "In4.Cu")
	)
	(gr_line
		(start 173.074584 -13.8176)
		(end 173.480984 -13.8176)
		(stroke
			(width 0.1016)
			(type default)
		)
		(layer "In4.Cu")
	)
	(gr_line
		(start 173.074584 -13.7668)
		(end 172.312584 -13.7668)
		(stroke
			(width 0.1016)
			(type default)
		)
		(layer "In4.Cu")
	)
	(gr_line
		(start 173.074584 -13.4874)
		(end 173.074584 -11.5062)
		(stroke
			(width 0.762)
			(type default)
		)
		(layer "In4.Cu")
	)
	(gr_line
		(start 173.074584 -9.617456)
		(end 173.074584 -9.566656)
		(stroke
			(width 0.1016)
			(type default)
		)
		(layer "In4.Cu")
	)
	(gr_line
		(start 173.074584 -9.617456)
		(end 173.480984 -9.617456)
		(stroke
			(width 0.1016)
			(type default)
		)
		(layer "In4.Cu")
	)
	(gr_line
		(start 173.074584 -9.566656)
		(end 172.312584 -9.566656)
		(stroke
			(width 0.1016)
			(type default)
		)
		(layer "In4.Cu")
	)
	(gr_line
		(start 173.074584 -9.287256)
		(end 173.074584 -7.306056)
		(stroke
			(width 0.762)
			(type default)
		)
		(layer "In4.Cu")
	)
	(gr_line
		(start 173.074584 -5.417312)
		(end 173.074584 -5.366512)
		(stroke
			(width 0.1016)
			(type default)
		)
		(layer "In4.Cu")
	)
	(gr_line
		(start 173.074584 -5.417312)
		(end 173.480984 -5.417312)
		(stroke
			(width 0.1016)
			(type default)
		)
		(layer "In4.Cu")
	)
	(gr_line
		(start 173.074584 -5.366512)
		(end 172.312584 -5.366512)
		(stroke
			(width 0.1016)
			(type default)
		)
		(layer "In4.Cu")
	)
	(gr_line
		(start 173.074584 -5.087112)
		(end 173.074584 -3.105912)
		(stroke
			(width 0.762)
			(type default)
		)
		(layer "In4.Cu")
	)
	(gr_line
		(start 173.099984 -13.5382)
		(end 172.693584 -13.5382)
		(stroke
			(width 0.254)
			(type default)
		)
		(layer "In4.Cu")
	)
	(gr_line
		(start 173.099984 -11.43)
		(end 173.099984 -13.5382)
		(stroke
			(width 0.254)
			(type default)
		)
		(layer "In4.Cu")
	)
	(gr_line
		(start 173.099984 -9.338056)
		(end 172.693584 -9.338056)
		(stroke
			(width 0.254)
			(type default)
		)
		(layer "In4.Cu")
	)
	(gr_line
		(start 173.099984 -7.229856)
		(end 173.099984 -9.338056)
		(stroke
			(width 0.254)
			(type default)
		)
		(layer "In4.Cu")
	)
	(gr_line
		(start 173.099984 -5.137912)
		(end 172.693584 -5.137912)
		(stroke
			(width 0.254)
			(type default)
		)
		(layer "In4.Cu")
	)
	(gr_line
		(start 173.099984 -3.029712)
		(end 173.099984 -5.137912)
		(stroke
			(width 0.254)
			(type default)
		)
		(layer "In4.Cu")
	)
	(gr_line
		(start 173.150784 -13.4874)
		(end 173.150784 -11.5062)
		(stroke
			(width 0.762)
			(type default)
		)
		(layer "In4.Cu")
	)
	(gr_line
		(start 173.150784 -9.287256)
		(end 173.150784 -7.306056)
		(stroke
			(width 0.762)
			(type default)
		)
		(layer "In4.Cu")
	)
	(gr_line
		(start 173.150784 -5.087112)
		(end 173.150784 -3.105912)
		(stroke
			(width 0.762)
			(type default)
		)
		(layer "In4.Cu")
	)
	(gr_line
		(start 173.176184 -13.6144)
		(end 172.617384 -13.6144)
		(stroke
			(width 0.254)
			(type default)
		)
		(layer "In4.Cu")
	)
	(gr_line
		(start 173.176184 -11.3792)
		(end 173.176184 -13.6144)
		(stroke
			(width 0.254)
			(type default)
		)
		(layer "In4.Cu")
	)
	(gr_line
		(start 173.176184 -9.414256)
		(end 172.617384 -9.414256)
		(stroke
			(width 0.254)
			(type default)
		)
		(layer "In4.Cu")
	)
	(gr_line
		(start 173.176184 -7.179056)
		(end 173.176184 -9.414256)
		(stroke
			(width 0.254)
			(type default)
		)
		(layer "In4.Cu")
	)
	(gr_line
		(start 173.176184 -5.214112)
		(end 172.617384 -5.214112)
		(stroke
			(width 0.254)
			(type default)
		)
		(layer "In4.Cu")
	)
	(gr_line
		(start 173.176184 -2.978912)
		(end 173.176184 -5.214112)
		(stroke
			(width 0.254)
			(type default)
		)
		(layer "In4.Cu")
	)
	(gr_line
		(start 173.252384 -13.6398)
		(end 172.541184 -13.6398)
		(stroke
			(width 0.254)
			(type default)
		)
		(layer "In4.Cu")
	)
	(gr_line
		(start 173.252384 -11.303)
		(end 173.252384 -13.6398)
		(stroke
			(width 0.254)
			(type default)
		)
		(layer "In4.Cu")
	)
	(gr_line
		(start 173.252384 -9.439656)
		(end 172.541184 -9.439656)
		(stroke
			(width 0.254)
			(type default)
		)
		(layer "In4.Cu")
	)
	(gr_line
		(start 173.252384 -7.102856)
		(end 173.252384 -9.439656)
		(stroke
			(width 0.254)
			(type default)
		)
		(layer "In4.Cu")
	)
	(gr_line
		(start 173.252384 -5.239512)
		(end 172.541184 -5.239512)
		(stroke
			(width 0.254)
			(type default)
		)
		(layer "In4.Cu")
	)
	(gr_line
		(start 173.252384 -2.902712)
		(end 173.252384 -5.239512)
		(stroke
			(width 0.254)
			(type default)
		)
		(layer "In4.Cu")
	)
	(gr_line
		(start 173.277784 -13.7668)
		(end 172.287184 -13.7668)
		(stroke
			(width 0.1016)
			(type default)
		)
		(layer "In4.Cu")
	)
	(gr_line
		(start 173.277784 -13.6906)
		(end 172.464984 -13.6906)
		(stroke
			(width 0.254)
			(type default)
		)
		(layer "In4.Cu")
	)
	(gr_line
		(start 173.277784 -11.2776)
		(end 173.277784 -13.6906)
		(stroke
			(width 0.254)
			(type default)
		)
		(layer "In4.Cu")
	)
	(gr_line
		(start 173.277784 -9.566656)
		(end 172.287184 -9.566656)
		(stroke
			(width 0.1016)
			(type default)
		)
		(layer "In4.Cu")
	)
	(gr_line
		(start 173.277784 -9.490456)
		(end 172.464984 -9.490456)
		(stroke
			(width 0.254)
			(type default)
		)
		(layer "In4.Cu")
	)
	(gr_line
		(start 173.277784 -7.077456)
		(end 173.277784 -9.490456)
		(stroke
			(width 0.254)
			(type default)
		)
		(layer "In4.Cu")
	)
	(gr_line
		(start 173.277784 -5.366512)
		(end 172.287184 -5.366512)
		(stroke
			(width 0.1016)
			(type default)
		)
		(layer "In4.Cu")
	)
	(gr_line
		(start 173.277784 -5.290312)
		(end 172.464984 -5.290312)
		(stroke
			(width 0.254)
			(type default)
		)
		(layer "In4.Cu")
	)
	(gr_line
		(start 173.277784 -2.877312)
		(end 173.277784 -5.290312)
		(stroke
			(width 0.254)
			(type default)
		)
		(layer "In4.Cu")
	)
	(gr_line
		(start 173.303184 -13.716)
		(end 172.439584 -13.716)
		(stroke
			(width 0.254)
			(type default)
		)
		(layer "In4.Cu")
	)
	(gr_line
		(start 173.303184 -11.2522)
		(end 173.303184 -13.716)
		(stroke
			(width 0.254)
			(type default)
		)
		(layer "In4.Cu")
	)
	(gr_line
		(start 173.303184 -9.515856)
		(end 172.439584 -9.515856)
		(stroke
			(width 0.254)
			(type default)
		)
		(layer "In4.Cu")
	)
	(gr_line
		(start 173.303184 -7.052056)
		(end 173.303184 -9.515856)
		(stroke
			(width 0.254)
			(type default)
		)
		(layer "In4.Cu")
	)
	(gr_line
		(start 173.303184 -5.315712)
		(end 172.439584 -5.315712)
		(stroke
			(width 0.254)
			(type default)
		)
		(layer "In4.Cu")
	)
	(gr_line
		(start 173.303184 -2.851912)
		(end 173.303184 -5.315712)
		(stroke
			(width 0.254)
			(type default)
		)
		(layer "In4.Cu")
	)
	(gr_line
		(start 173.353984 -13.7414)
		(end 172.414184 -13.7414)
		(stroke
			(width 0.254)
			(type default)
		)
		(layer "In4.Cu")
	)
	(gr_line
		(start 173.353984 -11.2522)
		(end 173.353984 -13.7414)
		(stroke
			(width 0.254)
			(type default)
		)
		(layer "In4.Cu")
	)
	(gr_line
		(start 173.353984 -9.541256)
		(end 172.414184 -9.541256)
		(stroke
			(width 0.254)
			(type default)
		)
		(layer "In4.Cu")
	)
	(gr_line
		(start 173.353984 -7.052056)
		(end 173.353984 -9.541256)
		(stroke
			(width 0.254)
			(type default)
		)
		(layer "In4.Cu")
	)
	(gr_line
		(start 173.353984 -5.341112)
		(end 172.414184 -5.341112)
		(stroke
			(width 0.254)
			(type default)
		)
		(layer "In4.Cu")
	)
	(gr_line
		(start 173.353984 -2.851912)
		(end 173.353984 -5.341112)
		(stroke
			(width 0.254)
			(type default)
		)
		(layer "In4.Cu")
	)
	(gr_line
		(start 173.379384 -13.7414)
		(end 172.414184 -13.7414)
		(stroke
			(width 0.2032)
			(type default)
		)
		(layer "In4.Cu")
	)
	(gr_line
		(start 173.379384 -11.2014)
		(end 173.379384 -13.7414)
		(stroke
			(width 0.2032)
			(type default)
		)
		(layer "In4.Cu")
	)
	(gr_line
		(start 173.379384 -9.541256)
		(end 172.414184 -9.541256)
		(stroke
			(width 0.2032)
			(type default)
		)
		(layer "In4.Cu")
	)
	(gr_line
		(start 173.379384 -7.001256)
		(end 173.379384 -9.541256)
		(stroke
			(width 0.2032)
			(type default)
		)
		(layer "In4.Cu")
	)
	(gr_line
		(start 173.379384 -5.341112)
		(end 172.414184 -5.341112)
		(stroke
			(width 0.2032)
			(type default)
		)
		(layer "In4.Cu")
	)
	(gr_line
		(start 173.379384 -2.801112)
		(end 173.379384 -5.341112)
		(stroke
			(width 0.2032)
			(type default)
		)
		(layer "In4.Cu")
	)
	(gr_line
		(start 173.430184 -13.7668)
		(end 172.363384 -13.7668)
		(stroke
			(width 0.2032)
			(type default)
		)
		(layer "In4.Cu")
	)
	(gr_line
		(start 173.430184 -11.2014)
		(end 173.430184 -13.7668)
		(stroke
			(width 0.2032)
			(type default)
		)
		(layer "In4.Cu")
	)
	(gr_line
		(start 173.430184 -9.566656)
		(end 172.363384 -9.566656)
		(stroke
			(width 0.2032)
			(type default)
		)
		(layer "In4.Cu")
	)
	(gr_line
		(start 173.430184 -7.001256)
		(end 173.430184 -9.566656)
		(stroke
			(width 0.2032)
			(type default)
		)
		(layer "In4.Cu")
	)
	(gr_line
		(start 173.430184 -5.366512)
		(end 172.363384 -5.366512)
		(stroke
			(width 0.2032)
			(type default)
		)
		(layer "In4.Cu")
	)
	(gr_line
		(start 173.430184 -2.801112)
		(end 173.430184 -5.366512)
		(stroke
			(width 0.2032)
			(type default)
		)
		(layer "In4.Cu")
	)
	(gr_line
		(start 173.455584 -13.7668)
		(end 172.337984 -13.7668)
		(stroke
			(width 0.1016)
			(type default)
		)
		(layer "In4.Cu")
	)
	(gr_line
		(start 173.455584 -11.176)
		(end 173.455584 -13.7668)
		(stroke
			(width 0.1016)
			(type default)
		)
		(layer "In4.Cu")
	)
	(gr_line
		(start 173.455584 -9.566656)
		(end 172.337984 -9.566656)
		(stroke
			(width 0.1016)
			(type default)
		)
		(layer "In4.Cu")
	)
	(gr_line
		(start 173.455584 -6.975856)
		(end 173.455584 -9.566656)
		(stroke
			(width 0.1016)
			(type default)
		)
		(layer "In4.Cu")
	)
	(gr_line
		(start 173.455584 -5.366512)
		(end 172.337984 -5.366512)
		(stroke
			(width 0.1016)
			(type default)
		)
		(layer "In4.Cu")
	)
	(gr_line
		(start 173.455584 -2.775712)
		(end 173.455584 -5.366512)
		(stroke
			(width 0.1016)
			(type default)
		)
		(layer "In4.Cu")
	)
	(gr_line
		(start 173.480984 -13.8176)
		(end 173.074584 -13.8176)
		(stroke
			(width 0.1016)
			(type default)
		)
		(layer "In4.Cu")
	)
	(gr_line
		(start 173.480984 -13.8176)
		(end 173.480984 -11.1506)
		(stroke
			(width 0.1016)
			(type default)
		)
		(layer "In4.Cu")
	)
	(gr_line
		(start 173.480984 -11.1506)
		(end 172.287184 -11.1506)
		(stroke
			(width 0.1016)
			(type default)
		)
		(layer "In4.Cu")
	)
	(gr_line
		(start 173.480984 -11.1506)
		(end 173.480984 -13.8176)
		(stroke
			(width 0.1016)
			(type default)
		)
		(layer "In4.Cu")
	)
	(gr_line
		(start 173.480984 -9.617456)
		(end 173.074584 -9.617456)
		(stroke
			(width 0.1016)
			(type default)
		)
		(layer "In4.Cu")
	)
	(gr_line
		(start 173.480984 -9.617456)
		(end 173.480984 -6.950456)
		(stroke
			(width 0.1016)
			(type default)
		)
		(layer "In4.Cu")
	)
	(gr_line
		(start 173.480984 -6.950456)
		(end 172.287184 -6.950456)
		(stroke
			(width 0.1016)
			(type default)
		)
		(layer "In4.Cu")
	)
	(gr_line
		(start 173.480984 -6.950456)
		(end 173.480984 -9.617456)
		(stroke
			(width 0.1016)
			(type default)
		)
		(layer "In4.Cu")
	)
	(gr_line
		(start 173.480984 -5.417312)
		(end 173.074584 -5.417312)
		(stroke
			(width 0.1016)
			(type default)
		)
		(layer "In4.Cu")
	)
	(gr_line
		(start 173.480984 -5.417312)
		(end 173.480984 -2.750312)
		(stroke
			(width 0.1016)
			(type default)
		)
		(layer "In4.Cu")
	)
	(gr_line
		(start 173.480984 -2.750312)
		(end 172.287184 -2.750312)
		(stroke
			(width 0.1016)
			(type default)
		)
		(layer "In4.Cu")
	)
	(gr_line
		(start 173.480984 -2.750312)
		(end 173.480984 -5.417312)
		(stroke
			(width 0.1016)
			(type default)
		)
		(layer "In4.Cu")
	)
	(gr_line
		(start 174.145448 -32.9184)
		(end 172.875448 -32.9184)
		(stroke
			(width 0.7874)
			(type default)
		)
		(layer "In4.Cu")
	)
	(gr_line
		(start 174.28718 -12.563348)
		(end 175.07458 -12.563348)
		(stroke
			(width 0.1016)
			(type default)
		)
		(layer "In4.Cu")
	)
	(gr_line
		(start 174.28718 -12.512548)
		(end 174.28718 -9.896348)
		(stroke
			(width 0.1016)
			(type default)
		)
		(layer "In4.Cu")
	)
	(gr_line
		(start 174.28718 -12.463272)
		(end 175.07458 -12.463272)
		(stroke
			(width 0.1016)
			(type default)
		)
		(layer "In4.Cu")
	)
	(gr_line
		(start 174.28718 -12.412472)
		(end 174.28718 -9.796272)
		(stroke
			(width 0.1016)
			(type default)
		)
		(layer "In4.Cu")
	)
	(gr_line
		(start 174.28718 -9.896348)
		(end 174.28718 -12.563348)
		(stroke
			(width 0.1016)
			(type default)
		)
		(layer "In4.Cu")
	)
	(gr_line
		(start 174.28718 -9.896348)
		(end 175.48098 -9.896348)
		(stroke
			(width 0.1016)
			(type default)
		)
		(layer "In4.Cu")
	)
	(gr_line
		(start 174.28718 -9.796272)
		(end 174.28718 -12.463272)
		(stroke
			(width 0.1016)
			(type default)
		)
		(layer "In4.Cu")
	)
	(gr_line
		(start 174.28718 -9.796272)
		(end 175.48098 -9.796272)
		(stroke
			(width 0.1016)
			(type default)
		)
		(layer "In4.Cu")
	)
	(gr_line
		(start 174.28718 -8.363204)
		(end 175.07458 -8.363204)
		(stroke
			(width 0.1016)
			(type default)
		)
		(layer "In4.Cu")
	)
	(gr_line
		(start 174.28718 -8.312404)
		(end 174.28718 -5.696204)
		(stroke
			(width 0.1016)
			(type default)
		)
		(layer "In4.Cu")
	)
	(gr_line
		(start 174.28718 -8.263128)
		(end 175.07458 -8.263128)
		(stroke
			(width 0.1016)
			(type default)
		)
		(layer "In4.Cu")
	)
	(gr_line
		(start 174.28718 -8.212328)
		(end 174.28718 -5.596128)
		(stroke
			(width 0.1016)
			(type default)
		)
		(layer "In4.Cu")
	)
	(gr_line
		(start 174.28718 -5.696204)
		(end 174.28718 -8.363204)
		(stroke
			(width 0.1016)
			(type default)
		)
		(layer "In4.Cu")
	)
	(gr_line
		(start 174.28718 -5.696204)
		(end 175.48098 -5.696204)
		(stroke
			(width 0.1016)
			(type default)
		)
		(layer "In4.Cu")
	)
	(gr_line
		(start 174.28718 -5.596128)
		(end 174.28718 -8.263128)
		(stroke
			(width 0.1016)
			(type default)
		)
		(layer "In4.Cu")
	)
	(gr_line
		(start 174.28718 -5.596128)
		(end 175.48098 -5.596128)
		(stroke
			(width 0.1016)
			(type default)
		)
		(layer "In4.Cu")
	)
	(gr_line
		(start 174.28718 -4.16306)
		(end 175.07458 -4.16306)
		(stroke
			(width 0.1016)
			(type default)
		)
		(layer "In4.Cu")
	)
	(gr_line
		(start 174.28718 -4.11226)
		(end 174.28718 -1.49606)
		(stroke
			(width 0.1016)
			(type default)
		)
		(layer "In4.Cu")
	)
	(gr_line
		(start 174.28718 -4.062984)
		(end 175.07458 -4.062984)
		(stroke
			(width 0.1016)
			(type default)
		)
		(layer "In4.Cu")
	)
	(gr_line
		(start 174.28718 -4.012184)
		(end 174.28718 -1.395984)
		(stroke
			(width 0.1016)
			(type default)
		)
		(layer "In4.Cu")
	)
	(gr_line
		(start 174.28718 -1.49606)
		(end 174.28718 -4.16306)
		(stroke
			(width 0.1016)
			(type default)
		)
		(layer "In4.Cu")
	)
	(gr_line
		(start 174.28718 -1.49606)
		(end 175.48098 -1.49606)
		(stroke
			(width 0.1016)
			(type default)
		)
		(layer "In4.Cu")
	)
	(gr_line
		(start 174.28718 -1.395984)
		(end 174.28718 -4.062984)
		(stroke
			(width 0.1016)
			(type default)
		)
		(layer "In4.Cu")
	)
	(gr_line
		(start 174.28718 -1.395984)
		(end 175.48098 -1.395984)
		(stroke
			(width 0.1016)
			(type default)
		)
		(layer "In4.Cu")
	)
	(gr_line
		(start 174.31258 -12.512548)
		(end 174.31258 -9.921748)
		(stroke
			(width 0.1016)
			(type default)
		)
		(layer "In4.Cu")
	)
	(gr_line
		(start 174.31258 -12.412472)
		(end 174.31258 -9.821672)
		(stroke
			(width 0.1016)
			(type default)
		)
		(layer "In4.Cu")
	)
	(gr_line
		(start 174.31258 -9.921748)
		(end 175.45558 -9.921748)
		(stroke
			(width 0.1016)
			(type default)
		)
		(layer "In4.Cu")
	)
	(gr_line
		(start 174.31258 -9.821672)
		(end 175.45558 -9.821672)
		(stroke
			(width 0.1016)
			(type default)
		)
		(layer "In4.Cu")
	)
	(gr_line
		(start 174.31258 -8.312404)
		(end 174.31258 -5.721604)
		(stroke
			(width 0.1016)
			(type default)
		)
		(layer "In4.Cu")
	)
	(gr_line
		(start 174.31258 -8.212328)
		(end 174.31258 -5.621528)
		(stroke
			(width 0.1016)
			(type default)
		)
		(layer "In4.Cu")
	)
	(gr_line
		(start 174.31258 -5.721604)
		(end 175.45558 -5.721604)
		(stroke
			(width 0.1016)
			(type default)
		)
		(layer "In4.Cu")
	)
	(gr_line
		(start 174.31258 -5.621528)
		(end 175.45558 -5.621528)
		(stroke
			(width 0.1016)
			(type default)
		)
		(layer "In4.Cu")
	)
	(gr_line
		(start 174.31258 -4.11226)
		(end 174.31258 -1.52146)
		(stroke
			(width 0.1016)
			(type default)
		)
		(layer "In4.Cu")
	)
	(gr_line
		(start 174.31258 -4.012184)
		(end 174.31258 -1.421384)
		(stroke
			(width 0.1016)
			(type default)
		)
		(layer "In4.Cu")
	)
	(gr_line
		(start 174.31258 -1.52146)
		(end 175.45558 -1.52146)
		(stroke
			(width 0.1016)
			(type default)
		)
		(layer "In4.Cu")
	)
	(gr_line
		(start 174.31258 -1.421384)
		(end 175.45558 -1.421384)
		(stroke
			(width 0.1016)
			(type default)
		)
		(layer "In4.Cu")
	)
	(gr_line
		(start 174.33798 -12.512548)
		(end 174.33798 -9.947148)
		(stroke
			(width 0.1016)
			(type default)
		)
		(layer "In4.Cu")
	)
	(gr_line
		(start 174.33798 -12.412472)
		(end 174.33798 -9.847072)
		(stroke
			(width 0.1016)
			(type default)
		)
		(layer "In4.Cu")
	)
	(gr_line
		(start 174.33798 -9.947148)
		(end 174.59198 -9.947148)
		(stroke
			(width 0.1016)
			(type default)
		)
		(layer "In4.Cu")
	)
	(gr_line
		(start 174.33798 -9.847072)
		(end 174.59198 -9.847072)
		(stroke
			(width 0.1016)
			(type default)
		)
		(layer "In4.Cu")
	)
	(gr_line
		(start 174.33798 -8.312404)
		(end 174.33798 -5.747004)
		(stroke
			(width 0.1016)
			(type default)
		)
		(layer "In4.Cu")
	)
	(gr_line
		(start 174.33798 -8.212328)
		(end 174.33798 -5.646928)
		(stroke
			(width 0.1016)
			(type default)
		)
		(layer "In4.Cu")
	)
	(gr_line
		(start 174.33798 -5.747004)
		(end 174.59198 -5.747004)
		(stroke
			(width 0.1016)
			(type default)
		)
		(layer "In4.Cu")
	)
	(gr_line
		(start 174.33798 -5.646928)
		(end 174.59198 -5.646928)
		(stroke
			(width 0.1016)
			(type default)
		)
		(layer "In4.Cu")
	)
	(gr_line
		(start 174.33798 -4.11226)
		(end 174.33798 -1.54686)
		(stroke
			(width 0.1016)
			(type default)
		)
		(layer "In4.Cu")
	)
	(gr_line
		(start 174.33798 -4.012184)
		(end 174.33798 -1.446784)
		(stroke
			(width 0.1016)
			(type default)
		)
		(layer "In4.Cu")
	)
	(gr_line
		(start 174.33798 -1.54686)
		(end 174.59198 -1.54686)
		(stroke
			(width 0.1016)
			(type default)
		)
		(layer "In4.Cu")
	)
	(gr_line
		(start 174.33798 -1.446784)
		(end 174.59198 -1.446784)
		(stroke
			(width 0.1016)
			(type default)
		)
		(layer "In4.Cu")
	)
	(gr_line
		(start 174.36338 -12.512548)
		(end 174.36338 -9.947148)
		(stroke
			(width 0.2032)
			(type default)
		)
		(layer "In4.Cu")
	)
	(gr_line
		(start 174.36338 -12.412472)
		(end 174.36338 -9.847072)
		(stroke
			(width 0.2032)
			(type default)
		)
		(layer "In4.Cu")
	)
	(gr_line
		(start 174.36338 -9.947148)
		(end 175.37938 -9.947148)
		(stroke
			(width 0.2032)
			(type default)
		)
		(layer "In4.Cu")
	)
	(gr_line
		(start 174.36338 -9.847072)
		(end 175.37938 -9.847072)
		(stroke
			(width 0.2032)
			(type default)
		)
		(layer "In4.Cu")
	)
	(gr_line
		(start 174.36338 -8.312404)
		(end 174.36338 -5.747004)
		(stroke
			(width 0.2032)
			(type default)
		)
		(layer "In4.Cu")
	)
	(gr_line
		(start 174.36338 -8.212328)
		(end 174.36338 -5.646928)
		(stroke
			(width 0.2032)
			(type default)
		)
		(layer "In4.Cu")
	)
	(gr_line
		(start 174.36338 -5.747004)
		(end 175.37938 -5.747004)
		(stroke
			(width 0.2032)
			(type default)
		)
		(layer "In4.Cu")
	)
	(gr_line
		(start 174.36338 -5.646928)
		(end 175.37938 -5.646928)
		(stroke
			(width 0.2032)
			(type default)
		)
		(layer "In4.Cu")
	)
	(gr_line
		(start 174.36338 -4.11226)
		(end 174.36338 -1.54686)
		(stroke
			(width 0.2032)
			(type default)
		)
		(layer "In4.Cu")
	)
	(gr_line
		(start 174.36338 -4.012184)
		(end 174.36338 -1.446784)
		(stroke
			(width 0.2032)
			(type default)
		)
		(layer "In4.Cu")
	)
	(gr_line
		(start 174.36338 -1.54686)
		(end 175.37938 -1.54686)
		(stroke
			(width 0.2032)
			(type default)
		)
		(layer "In4.Cu")
	)
	(gr_line
		(start 174.36338 -1.446784)
		(end 175.37938 -1.446784)
		(stroke
			(width 0.2032)
			(type default)
		)
		(layer "In4.Cu")
	)
	(gr_line
		(start 174.41418 -12.487148)
		(end 174.41418 -9.997948)
		(stroke
			(width 0.2032)
			(type default)
		)
		(layer "In4.Cu")
	)
	(gr_line
		(start 174.41418 -12.487148)
		(end 174.41418 -9.997948)
		(stroke
			(width 0.254)
			(type default)
		)
		(layer "In4.Cu")
	)
	(gr_line
		(start 174.41418 -12.387072)
		(end 174.41418 -9.897872)
		(stroke
			(width 0.2032)
			(type default)
		)
		(layer "In4.Cu")
	)
	(gr_line
		(start 174.41418 -12.387072)
		(end 174.41418 -9.897872)
		(stroke
			(width 0.254)
			(type default)
		)
		(layer "In4.Cu")
	)
	(gr_line
		(start 174.41418 -9.997948)
		(end 174.61738 -9.997948)
		(stroke
			(width 0.2032)
			(type default)
		)
		(layer "In4.Cu")
	)
	(gr_line
		(start 174.41418 -9.997948)
		(end 175.30318 -9.997948)
		(stroke
			(width 0.254)
			(type default)
		)
		(layer "In4.Cu")
	)
	(gr_line
		(start 174.41418 -9.897872)
		(end 174.61738 -9.897872)
		(stroke
			(width 0.2032)
			(type default)
		)
		(layer "In4.Cu")
	)
	(gr_line
		(start 174.41418 -9.897872)
		(end 175.30318 -9.897872)
		(stroke
			(width 0.254)
			(type default)
		)
		(layer "In4.Cu")
	)
	(gr_line
		(start 174.41418 -8.287004)
		(end 174.41418 -5.797804)
		(stroke
			(width 0.2032)
			(type default)
		)
		(layer "In4.Cu")
	)
	(gr_line
		(start 174.41418 -8.287004)
		(end 174.41418 -5.797804)
		(stroke
			(width 0.254)
			(type default)
		)
		(layer "In4.Cu")
	)
	(gr_line
		(start 174.41418 -8.186928)
		(end 174.41418 -5.697728)
		(stroke
			(width 0.2032)
			(type default)
		)
		(layer "In4.Cu")
	)
	(gr_line
		(start 174.41418 -8.186928)
		(end 174.41418 -5.697728)
		(stroke
			(width 0.254)
			(type default)
		)
		(layer "In4.Cu")
	)
	(gr_line
		(start 174.41418 -5.797804)
		(end 174.61738 -5.797804)
		(stroke
			(width 0.2032)
			(type default)
		)
		(layer "In4.Cu")
	)
	(gr_line
		(start 174.41418 -5.797804)
		(end 175.30318 -5.797804)
		(stroke
			(width 0.254)
			(type default)
		)
		(layer "In4.Cu")
	)
	(gr_line
		(start 174.41418 -5.697728)
		(end 174.61738 -5.697728)
		(stroke
			(width 0.2032)
			(type default)
		)
		(layer "In4.Cu")
	)
	(gr_line
		(start 174.41418 -5.697728)
		(end 175.30318 -5.697728)
		(stroke
			(width 0.254)
			(type default)
		)
		(layer "In4.Cu")
	)
	(gr_line
		(start 174.41418 -4.08686)
		(end 174.41418 -1.59766)
		(stroke
			(width 0.2032)
			(type default)
		)
		(layer "In4.Cu")
	)
	(gr_line
		(start 174.41418 -4.08686)
		(end 174.41418 -1.59766)
		(stroke
			(width 0.254)
			(type default)
		)
		(layer "In4.Cu")
	)
	(gr_line
		(start 174.41418 -3.986784)
		(end 174.41418 -1.497584)
		(stroke
			(width 0.2032)
			(type default)
		)
		(layer "In4.Cu")
	)
	(gr_line
		(start 174.41418 -3.986784)
		(end 174.41418 -1.497584)
		(stroke
			(width 0.254)
			(type default)
		)
		(layer "In4.Cu")
	)
	(gr_line
		(start 174.41418 -1.59766)
		(end 174.61738 -1.59766)
		(stroke
			(width 0.2032)
			(type default)
		)
		(layer "In4.Cu")
	)
	(gr_line
		(start 174.41418 -1.59766)
		(end 175.30318 -1.59766)
		(stroke
			(width 0.254)
			(type default)
		)
		(layer "In4.Cu")
	)
	(gr_line
		(start 174.41418 -1.497584)
		(end 174.61738 -1.497584)
		(stroke
			(width 0.2032)
			(type default)
		)
		(layer "In4.Cu")
	)
	(gr_line
		(start 174.41418 -1.497584)
		(end 175.30318 -1.497584)
		(stroke
			(width 0.254)
			(type default)
		)
		(layer "In4.Cu")
	)
	(gr_line
		(start 174.43958 -12.461748)
		(end 174.43958 -10.023348)
		(stroke
			(width 0.254)
			(type default)
		)
		(layer "In4.Cu")
	)
	(gr_line
		(start 174.43958 -12.361672)
		(end 174.43958 -9.923272)
		(stroke
			(width 0.254)
			(type default)
		)
		(layer "In4.Cu")
	)
	(gr_line
		(start 174.43958 -10.023348)
		(end 175.27778 -10.023348)
		(stroke
			(width 0.254)
			(type default)
		)
		(layer "In4.Cu")
	)
	(gr_line
		(start 174.43958 -9.923272)
		(end 175.27778 -9.923272)
		(stroke
			(width 0.254)
			(type default)
		)
		(layer "In4.Cu")
	)
	(gr_line
		(start 174.43958 -8.261604)
		(end 174.43958 -5.823204)
		(stroke
			(width 0.254)
			(type default)
		)
		(layer "In4.Cu")
	)
	(gr_line
		(start 174.43958 -8.161528)
		(end 174.43958 -5.723128)
		(stroke
			(width 0.254)
			(type default)
		)
		(layer "In4.Cu")
	)
	(gr_line
		(start 174.43958 -5.823204)
		(end 175.27778 -5.823204)
		(stroke
			(width 0.254)
			(type default)
		)
		(layer "In4.Cu")
	)
	(gr_line
		(start 174.43958 -5.723128)
		(end 175.27778 -5.723128)
		(stroke
			(width 0.254)
			(type default)
		)
		(layer "In4.Cu")
	)
	(gr_line
		(start 174.43958 -4.06146)
		(end 174.43958 -1.62306)
		(stroke
			(width 0.254)
			(type default)
		)
		(layer "In4.Cu")
	)
	(gr_line
		(start 174.43958 -3.961384)
		(end 174.43958 -1.522984)
		(stroke
			(width 0.254)
			(type default)
		)
		(layer "In4.Cu")
	)
	(gr_line
		(start 174.43958 -1.62306)
		(end 175.27778 -1.62306)
		(stroke
			(width 0.254)
			(type default)
		)
		(layer "In4.Cu")
	)
	(gr_line
		(start 174.43958 -1.522984)
		(end 175.27778 -1.522984)
		(stroke
			(width 0.254)
			(type default)
		)
		(layer "In4.Cu")
	)
	(gr_line
		(start 174.46498 -12.436348)
		(end 174.46498 -10.048748)
		(stroke
			(width 0.254)
			(type default)
		)
		(layer "In4.Cu")
	)
	(gr_line
		(start 174.46498 -12.336272)
		(end 174.46498 -9.948672)
		(stroke
			(width 0.254)
			(type default)
		)
		(layer "In4.Cu")
	)
	(gr_line
		(start 174.46498 -10.048748)
		(end 175.25238 -10.048748)
		(stroke
			(width 0.254)
			(type default)
		)
		(layer "In4.Cu")
	)
	(gr_line
		(start 174.46498 -9.948672)
		(end 175.25238 -9.948672)
		(stroke
			(width 0.254)
			(type default)
		)
		(layer "In4.Cu")
	)
	(gr_line
		(start 174.46498 -8.236204)
		(end 174.46498 -5.848604)
		(stroke
			(width 0.254)
			(type default)
		)
		(layer "In4.Cu")
	)
	(gr_line
		(start 174.46498 -8.136128)
		(end 174.46498 -5.748528)
		(stroke
			(width 0.254)
			(type default)
		)
		(layer "In4.Cu")
	)
	(gr_line
		(start 174.46498 -5.848604)
		(end 175.25238 -5.848604)
		(stroke
			(width 0.254)
			(type default)
		)
		(layer "In4.Cu")
	)
	(gr_line
		(start 174.46498 -5.748528)
		(end 175.25238 -5.748528)
		(stroke
			(width 0.254)
			(type default)
		)
		(layer "In4.Cu")
	)
	(gr_line
		(start 174.46498 -4.03606)
		(end 174.46498 -1.64846)
		(stroke
			(width 0.254)
			(type default)
		)
		(layer "In4.Cu")
	)
	(gr_line
		(start 174.46498 -3.935984)
		(end 174.46498 -1.548384)
		(stroke
			(width 0.254)
			(type default)
		)
		(layer "In4.Cu")
	)
	(gr_line
		(start 174.46498 -1.64846)
		(end 175.25238 -1.64846)
		(stroke
			(width 0.254)
			(type default)
		)
		(layer "In4.Cu")
	)
	(gr_line
		(start 174.46498 -1.548384)
		(end 175.25238 -1.548384)
		(stroke
			(width 0.254)
			(type default)
		)
		(layer "In4.Cu")
	)
	(gr_line
		(start 174.49038 -12.360148)
		(end 175.12538 -12.360148)
		(stroke
			(width 0.508)
			(type default)
		)
		(layer "In4.Cu")
	)
	(gr_line
		(start 174.49038 -12.260072)
		(end 175.12538 -12.260072)
		(stroke
			(width 0.508)
			(type default)
		)
		(layer "In4.Cu")
	)
	(gr_line
		(start 174.49038 -10.175748)
		(end 175.12538 -10.175748)
		(stroke
			(width 0.508)
			(type default)
		)
		(layer "In4.Cu")
	)
	(gr_line
		(start 174.49038 -10.124948)
		(end 175.12538 -10.124948)
		(stroke
			(width 0.508)
			(type default)
		)
		(layer "In4.Cu")
	)
	(gr_line
		(start 174.49038 -10.075672)
		(end 175.12538 -10.075672)
		(stroke
			(width 0.508)
			(type default)
		)
		(layer "In4.Cu")
	)
	(gr_line
		(start 174.49038 -10.024872)
		(end 175.12538 -10.024872)
		(stroke
			(width 0.508)
			(type default)
		)
		(layer "In4.Cu")
	)
	(gr_line
		(start 174.49038 -8.160004)
		(end 175.12538 -8.160004)
		(stroke
			(width 0.508)
			(type default)
		)
		(layer "In4.Cu")
	)
	(gr_line
		(start 174.49038 -8.059928)
		(end 175.12538 -8.059928)
		(stroke
			(width 0.508)
			(type default)
		)
		(layer "In4.Cu")
	)
	(gr_line
		(start 174.49038 -5.975604)
		(end 175.12538 -5.975604)
		(stroke
			(width 0.508)
			(type default)
		)
		(layer "In4.Cu")
	)
	(gr_line
		(start 174.49038 -5.924804)
		(end 175.12538 -5.924804)
		(stroke
			(width 0.508)
			(type default)
		)
		(layer "In4.Cu")
	)
	(gr_line
		(start 174.49038 -5.875528)
		(end 175.12538 -5.875528)
		(stroke
			(width 0.508)
			(type default)
		)
		(layer "In4.Cu")
	)
	(gr_line
		(start 174.49038 -5.824728)
		(end 175.12538 -5.824728)
		(stroke
			(width 0.508)
			(type default)
		)
		(layer "In4.Cu")
	)
	(gr_line
		(start 174.49038 -3.95986)
		(end 175.12538 -3.95986)
		(stroke
			(width 0.508)
			(type default)
		)
		(layer "In4.Cu")
	)
	(gr_line
		(start 174.49038 -3.859784)
		(end 175.12538 -3.859784)
		(stroke
			(width 0.508)
			(type default)
		)
		(layer "In4.Cu")
	)
	(gr_line
		(start 174.49038 -1.77546)
		(end 175.12538 -1.77546)
		(stroke
			(width 0.508)
			(type default)
		)
		(layer "In4.Cu")
	)
	(gr_line
		(start 174.49038 -1.72466)
		(end 175.12538 -1.72466)
		(stroke
			(width 0.508)
			(type default)
		)
		(layer "In4.Cu")
	)
	(gr_line
		(start 174.49038 -1.675384)
		(end 175.12538 -1.675384)
		(stroke
			(width 0.508)
			(type default)
		)
		(layer "In4.Cu")
	)
	(gr_line
		(start 174.49038 -1.624584)
		(end 175.12538 -1.624584)
		(stroke
			(width 0.508)
			(type default)
		)
		(layer "In4.Cu")
	)
	(gr_line
		(start 174.51578 -10.429748)
		(end 175.15078 -10.429748)
		(stroke
			(width 0.508)
			(type default)
		)
		(layer "In4.Cu")
	)
	(gr_line
		(start 174.51578 -10.329672)
		(end 175.15078 -10.329672)
		(stroke
			(width 0.508)
			(type default)
		)
		(layer "In4.Cu")
	)
	(gr_line
		(start 174.51578 -6.229604)
		(end 175.15078 -6.229604)
		(stroke
			(width 0.508)
			(type default)
		)
		(layer "In4.Cu")
	)
	(gr_line
		(start 174.51578 -6.129528)
		(end 175.15078 -6.129528)
		(stroke
			(width 0.508)
			(type default)
		)
		(layer "In4.Cu")
	)
	(gr_line
		(start 174.51578 -2.02946)
		(end 175.15078 -2.02946)
		(stroke
			(width 0.508)
			(type default)
		)
		(layer "In4.Cu")
	)
	(gr_line
		(start 174.51578 -1.929384)
		(end 175.15078 -1.929384)
		(stroke
			(width 0.508)
			(type default)
		)
		(layer "In4.Cu")
	)
	(gr_line
		(start 174.54118 -12.385548)
		(end 174.54118 -10.124948)
		(stroke
			(width 0.254)
			(type default)
		)
		(layer "In4.Cu")
	)
	(gr_line
		(start 174.54118 -12.285472)
		(end 174.54118 -10.024872)
		(stroke
			(width 0.254)
			(type default)
		)
		(layer "In4.Cu")
	)
	(gr_line
		(start 174.54118 -12.233148)
		(end 175.17618 -12.233148)
		(stroke
			(width 0.508)
			(type default)
		)
		(layer "In4.Cu")
	)
	(gr_line
		(start 174.54118 -12.133072)
		(end 175.17618 -12.133072)
		(stroke
			(width 0.508)
			(type default)
		)
		(layer "In4.Cu")
	)
	(gr_line
		(start 174.54118 -10.124948)
		(end 175.17618 -10.124948)
		(stroke
			(width 0.254)
			(type default)
		)
		(layer "In4.Cu")
	)
	(gr_line
		(start 174.54118 -10.024872)
		(end 175.17618 -10.024872)
		(stroke
			(width 0.254)
			(type default)
		)
		(layer "In4.Cu")
	)
	(gr_line
		(start 174.54118 -8.185404)
		(end 174.54118 -5.924804)
		(stroke
			(width 0.254)
			(type default)
		)
		(layer "In4.Cu")
	)
	(gr_line
		(start 174.54118 -8.085328)
		(end 174.54118 -5.824728)
		(stroke
			(width 0.254)
			(type default)
		)
		(layer "In4.Cu")
	)
	(gr_line
		(start 174.54118 -8.033004)
		(end 175.17618 -8.033004)
		(stroke
			(width 0.508)
			(type default)
		)
		(layer "In4.Cu")
	)
	(gr_line
		(start 174.54118 -7.932928)
		(end 175.17618 -7.932928)
		(stroke
			(width 0.508)
			(type default)
		)
		(layer "In4.Cu")
	)
	(gr_line
		(start 174.54118 -5.924804)
		(end 175.17618 -5.924804)
		(stroke
			(width 0.254)
			(type default)
		)
		(layer "In4.Cu")
	)
	(gr_line
		(start 174.54118 -5.824728)
		(end 175.17618 -5.824728)
		(stroke
			(width 0.254)
			(type default)
		)
		(layer "In4.Cu")
	)
	(gr_line
		(start 174.54118 -3.98526)
		(end 174.54118 -1.72466)
		(stroke
			(width 0.254)
			(type default)
		)
		(layer "In4.Cu")
	)
	(gr_line
		(start 174.54118 -3.885184)
		(end 174.54118 -1.624584)
		(stroke
			(width 0.254)
			(type default)
		)
		(layer "In4.Cu")
	)
	(gr_line
		(start 174.54118 -3.83286)
		(end 175.17618 -3.83286)
		(stroke
			(width 0.508)
			(type default)
		)
		(layer "In4.Cu")
	)
	(gr_line
		(start 174.54118 -3.732784)
		(end 175.17618 -3.732784)
		(stroke
			(width 0.508)
			(type default)
		)
		(layer "In4.Cu")
	)
	(gr_line
		(start 174.54118 -1.72466)
		(end 175.17618 -1.72466)
		(stroke
			(width 0.254)
			(type default)
		)
		(layer "In4.Cu")
	)
	(gr_line
		(start 174.54118 -1.624584)
		(end 175.17618 -1.624584)
		(stroke
			(width 0.254)
			(type default)
		)
		(layer "In4.Cu")
	)
	(gr_line
		(start 174.56658 -12.080748)
		(end 175.20158 -12.080748)
		(stroke
			(width 0.508)
			(type default)
		)
		(layer "In4.Cu")
	)
	(gr_line
		(start 174.56658 -11.980672)
		(end 175.20158 -11.980672)
		(stroke
			(width 0.508)
			(type default)
		)
		(layer "In4.Cu")
	)
	(gr_line
		(start 174.56658 -7.880604)
		(end 175.20158 -7.880604)
		(stroke
			(width 0.508)
			(type default)
		)
		(layer "In4.Cu")
	)
	(gr_line
		(start 174.56658 -7.780528)
		(end 175.20158 -7.780528)
		(stroke
			(width 0.508)
			(type default)
		)
		(layer "In4.Cu")
	)
	(gr_line
		(start 174.56658 -3.68046)
		(end 175.20158 -3.68046)
		(stroke
			(width 0.508)
			(type default)
		)
		(layer "In4.Cu")
	)
	(gr_line
		(start 174.56658 -3.580384)
		(end 175.20158 -3.580384)
		(stroke
			(width 0.508)
			(type default)
		)
		(layer "In4.Cu")
	)
	(gr_line
		(start 174.59198 -12.360148)
		(end 175.22698 -12.360148)
		(stroke
			(width 0.508)
			(type default)
		)
		(layer "In4.Cu")
	)
	(gr_line
		(start 174.59198 -12.260072)
		(end 175.22698 -12.260072)
		(stroke
			(width 0.508)
			(type default)
		)
		(layer "In4.Cu")
	)
	(gr_line
		(start 174.59198 -9.947148)
		(end 175.43018 -9.947148)
		(stroke
			(width 0.2032)
			(type default)
		)
		(layer "In4.Cu")
	)
	(gr_line
		(start 174.59198 -9.847072)
		(end 175.43018 -9.847072)
		(stroke
			(width 0.2032)
			(type default)
		)
		(layer "In4.Cu")
	)
	(gr_line
		(start 174.59198 -8.160004)
		(end 175.22698 -8.160004)
		(stroke
			(width 0.508)
			(type default)
		)
		(layer "In4.Cu")
	)
	(gr_line
		(start 174.59198 -8.059928)
		(end 175.22698 -8.059928)
		(stroke
			(width 0.508)
			(type default)
		)
		(layer "In4.Cu")
	)
	(gr_line
		(start 174.59198 -5.747004)
		(end 175.43018 -5.747004)
		(stroke
			(width 0.2032)
			(type default)
		)
		(layer "In4.Cu")
	)
	(gr_line
		(start 174.59198 -5.646928)
		(end 175.43018 -5.646928)
		(stroke
			(width 0.2032)
			(type default)
		)
		(layer "In4.Cu")
	)
	(gr_line
		(start 174.59198 -3.95986)
		(end 175.22698 -3.95986)
		(stroke
			(width 0.508)
			(type default)
		)
		(layer "In4.Cu")
	)
	(gr_line
		(start 174.59198 -3.859784)
		(end 175.22698 -3.859784)
		(stroke
			(width 0.508)
			(type default)
		)
		(layer "In4.Cu")
	)
	(gr_line
		(start 174.59198 -1.54686)
		(end 175.43018 -1.54686)
		(stroke
			(width 0.2032)
			(type default)
		)
		(layer "In4.Cu")
	)
	(gr_line
		(start 174.59198 -1.446784)
		(end 175.43018 -1.446784)
		(stroke
			(width 0.2032)
			(type default)
		)
		(layer "In4.Cu")
	)
	(gr_line
		(start 174.61738 -12.360148)
		(end 174.61738 -10.175748)
		(stroke
			(width 0.254)
			(type default)
		)
		(layer "In4.Cu")
	)
	(gr_line
		(start 174.61738 -12.260072)
		(end 174.61738 -10.075672)
		(stroke
			(width 0.254)
			(type default)
		)
		(layer "In4.Cu")
	)
	(gr_line
		(start 174.61738 -10.175748)
		(end 175.09998 -10.175748)
		(stroke
			(width 0.254)
			(type default)
		)
		(layer "In4.Cu")
	)
	(gr_line
		(start 174.61738 -10.075672)
		(end 175.09998 -10.075672)
		(stroke
			(width 0.254)
			(type default)
		)
		(layer "In4.Cu")
	)
	(gr_line
		(start 174.61738 -9.997948)
		(end 175.35398 -9.997948)
		(stroke
			(width 0.254)
			(type default)
		)
		(layer "In4.Cu")
	)
	(gr_line
		(start 174.61738 -9.897872)
		(end 175.35398 -9.897872)
		(stroke
			(width 0.254)
			(type default)
		)
		(layer "In4.Cu")
	)
	(gr_line
		(start 174.61738 -8.160004)
		(end 174.61738 -5.975604)
		(stroke
			(width 0.254)
			(type default)
		)
		(layer "In4.Cu")
	)
	(gr_line
		(start 174.61738 -8.059928)
		(end 174.61738 -5.875528)
		(stroke
			(width 0.254)
			(type default)
		)
		(layer "In4.Cu")
	)
	(gr_line
		(start 174.61738 -5.975604)
		(end 175.09998 -5.975604)
		(stroke
			(width 0.254)
			(type default)
		)
		(layer "In4.Cu")
	)
	(gr_line
		(start 174.61738 -5.875528)
		(end 175.09998 -5.875528)
		(stroke
			(width 0.254)
			(type default)
		)
		(layer "In4.Cu")
	)
	(gr_line
		(start 174.61738 -5.797804)
		(end 175.35398 -5.797804)
		(stroke
			(width 0.254)
			(type default)
		)
		(layer "In4.Cu")
	)
	(gr_line
		(start 174.61738 -5.697728)
		(end 175.35398 -5.697728)
		(stroke
			(width 0.254)
			(type default)
		)
		(layer "In4.Cu")
	)
	(gr_line
		(start 174.61738 -3.95986)
		(end 174.61738 -1.77546)
		(stroke
			(width 0.254)
			(type default)
		)
		(layer "In4.Cu")
	)
	(gr_line
		(start 174.61738 -3.859784)
		(end 174.61738 -1.675384)
		(stroke
			(width 0.254)
			(type default)
		)
		(layer "In4.Cu")
	)
	(gr_line
		(start 174.61738 -1.77546)
		(end 175.09998 -1.77546)
		(stroke
			(width 0.254)
			(type default)
		)
		(layer "In4.Cu")
	)
	(gr_line
		(start 174.61738 -1.675384)
		(end 175.09998 -1.675384)
		(stroke
			(width 0.254)
			(type default)
		)
		(layer "In4.Cu")
	)
	(gr_line
		(start 174.61738 -1.59766)
		(end 175.35398 -1.59766)
		(stroke
			(width 0.254)
			(type default)
		)
		(layer "In4.Cu")
	)
	(gr_line
		(start 174.61738 -1.497584)
		(end 175.35398 -1.497584)
		(stroke
			(width 0.254)
			(type default)
		)
		(layer "In4.Cu")
	)
	(gr_line
		(start 174.635922 -10.110978)
		(end 175.270922 -10.110978)
		(stroke
			(width 0.508)
			(type default)
		)
		(layer "In4.Cu")
	)
	(gr_line
		(start 174.635922 -10.010902)
		(end 175.270922 -10.010902)
		(stroke
			(width 0.508)
			(type default)
		)
		(layer "In4.Cu")
	)
	(gr_line
		(start 174.635922 -5.910834)
		(end 175.270922 -5.910834)
		(stroke
			(width 0.508)
			(type default)
		)
		(layer "In4.Cu")
	)
	(gr_line
		(start 174.635922 -5.810758)
		(end 175.270922 -5.810758)
		(stroke
			(width 0.508)
			(type default)
		)
		(layer "In4.Cu")
	)
	(gr_line
		(start 174.635922 -1.71069)
		(end 175.270922 -1.71069)
		(stroke
			(width 0.508)
			(type default)
		)
		(layer "In4.Cu")
	)
	(gr_line
		(start 174.635922 -1.610614)
		(end 175.270922 -1.610614)
		(stroke
			(width 0.508)
			(type default)
		)
		(layer "In4.Cu")
	)
	(gr_line
		(start 174.64278 -12.360148)
		(end 175.27778 -12.360148)
		(stroke
			(width 0.508)
			(type default)
		)
		(layer "In4.Cu")
	)
	(gr_line
		(start 174.64278 -12.260072)
		(end 175.27778 -12.260072)
		(stroke
			(width 0.508)
			(type default)
		)
		(layer "In4.Cu")
	)
	(gr_line
		(start 174.64278 -12.233148)
		(end 174.64278 -10.251948)
		(stroke
			(width 0.762)
			(type default)
		)
		(layer "In4.Cu")
	)
	(gr_line
		(start 174.64278 -12.133072)
		(end 174.64278 -10.151872)
		(stroke
			(width 0.762)
			(type default)
		)
		(layer "In4.Cu")
	)
	(gr_line
		(start 174.64278 -10.251948)
		(end 175.27778 -10.251948)
		(stroke
			(width 0.508)
			(type default)
		)
		(layer "In4.Cu")
	)
	(gr_line
		(start 174.64278 -10.151872)
		(end 175.27778 -10.151872)
		(stroke
			(width 0.508)
			(type default)
		)
		(layer "In4.Cu")
	)
	(gr_line
		(start 174.64278 -8.160004)
		(end 175.27778 -8.160004)
		(stroke
			(width 0.508)
			(type default)
		)
		(layer "In4.Cu")
	)
	(gr_line
		(start 174.64278 -8.059928)
		(end 175.27778 -8.059928)
		(stroke
			(width 0.508)
			(type default)
		)
		(layer "In4.Cu")
	)
	(gr_line
		(start 174.64278 -8.033004)
		(end 174.64278 -6.051804)
		(stroke
			(width 0.762)
			(type default)
		)
		(layer "In4.Cu")
	)
	(gr_line
		(start 174.64278 -7.932928)
		(end 174.64278 -5.951728)
		(stroke
			(width 0.762)
			(type default)
		)
		(layer "In4.Cu")
	)
	(gr_line
		(start 174.64278 -6.051804)
		(end 175.27778 -6.051804)
		(stroke
			(width 0.508)
			(type default)
		)
		(layer "In4.Cu")
	)
	(gr_line
		(start 174.64278 -5.951728)
		(end 175.27778 -5.951728)
		(stroke
			(width 0.508)
			(type default)
		)
		(layer "In4.Cu")
	)
	(gr_line
		(start 174.64278 -3.95986)
		(end 175.27778 -3.95986)
		(stroke
			(width 0.508)
			(type default)
		)
		(layer "In4.Cu")
	)
	(gr_line
		(start 174.64278 -3.859784)
		(end 175.27778 -3.859784)
		(stroke
			(width 0.508)
			(type default)
		)
		(layer "In4.Cu")
	)
	(gr_line
		(start 174.64278 -3.83286)
		(end 174.64278 -1.85166)
		(stroke
			(width 0.762)
			(type default)
		)
		(layer "In4.Cu")
	)
	(gr_line
		(start 174.64278 -3.732784)
		(end 174.64278 -1.751584)
		(stroke
			(width 0.762)
			(type default)
		)
		(layer "In4.Cu")
	)
	(gr_line
		(start 174.64278 -1.85166)
		(end 175.27778 -1.85166)
		(stroke
			(width 0.508)
			(type default)
		)
		(layer "In4.Cu")
	)
	(gr_line
		(start 174.64278 -1.751584)
		(end 175.27778 -1.751584)
		(stroke
			(width 0.508)
			(type default)
		)
		(layer "In4.Cu")
	)
	(gr_line
		(start 174.69358 -12.283948)
		(end 174.69358 -10.251948)
		(stroke
			(width 0.254)
			(type default)
		)
		(layer "In4.Cu")
	)
	(gr_line
		(start 174.69358 -12.183872)
		(end 174.69358 -10.151872)
		(stroke
			(width 0.254)
			(type default)
		)
		(layer "In4.Cu")
	)
	(gr_line
		(start 174.69358 -10.251948)
		(end 175.02378 -10.251948)
		(stroke
			(width 0.254)
			(type default)
		)
		(layer "In4.Cu")
	)
	(gr_line
		(start 174.69358 -10.151872)
		(end 175.02378 -10.151872)
		(stroke
			(width 0.254)
			(type default)
		)
		(layer "In4.Cu")
	)
	(gr_line
		(start 174.69358 -8.083804)
		(end 174.69358 -6.051804)
		(stroke
			(width 0.254)
			(type default)
		)
		(layer "In4.Cu")
	)
	(gr_line
		(start 174.69358 -7.983728)
		(end 174.69358 -5.951728)
		(stroke
			(width 0.254)
			(type default)
		)
		(layer "In4.Cu")
	)
	(gr_line
		(start 174.69358 -6.051804)
		(end 175.02378 -6.051804)
		(stroke
			(width 0.254)
			(type default)
		)
		(layer "In4.Cu")
	)
	(gr_line
		(start 174.69358 -5.951728)
		(end 175.02378 -5.951728)
		(stroke
			(width 0.254)
			(type default)
		)
		(layer "In4.Cu")
	)
	(gr_line
		(start 174.69358 -3.88366)
		(end 174.69358 -1.85166)
		(stroke
			(width 0.254)
			(type default)
		)
		(layer "In4.Cu")
	)
	(gr_line
		(start 174.69358 -3.783584)
		(end 174.69358 -1.751584)
		(stroke
			(width 0.254)
			(type default)
		)
		(layer "In4.Cu")
	)
	(gr_line
		(start 174.69358 -1.85166)
		(end 175.02378 -1.85166)
		(stroke
			(width 0.254)
			(type default)
		)
		(layer "In4.Cu")
	)
	(gr_line
		(start 174.69358 -1.751584)
		(end 175.02378 -1.751584)
		(stroke
			(width 0.254)
			(type default)
		)
		(layer "In4.Cu")
	)
	(gr_line
		(start 174.79518 -12.207748)
		(end 174.79518 -10.404348)
		(stroke
			(width 0.254)
			(type default)
		)
		(layer "In4.Cu")
	)
	(gr_line
		(start 174.79518 -12.207748)
		(end 174.79518 -10.226548)
		(stroke
			(width 0.762)
			(type default)
		)
		(layer "In4.Cu")
	)
	(gr_line
		(start 174.79518 -12.107672)
		(end 174.79518 -10.304272)
		(stroke
			(width 0.254)
			(type default)
		)
		(layer "In4.Cu")
	)
	(gr_line
		(start 174.79518 -12.107672)
		(end 174.79518 -10.126472)
		(stroke
			(width 0.762)
			(type default)
		)
		(layer "In4.Cu")
	)
	(gr_line
		(start 174.79518 -10.404348)
		(end 174.89678 -10.404348)
		(stroke
			(width 0.254)
			(type default)
		)
		(layer "In4.Cu")
	)
	(gr_line
		(start 174.79518 -10.304272)
		(end 174.89678 -10.304272)
		(stroke
			(width 0.254)
			(type default)
		)
		(layer "In4.Cu")
	)
	(gr_line
		(start 174.79518 -8.007604)
		(end 174.79518 -6.204204)
		(stroke
			(width 0.254)
			(type default)
		)
		(layer "In4.Cu")
	)
	(gr_line
		(start 174.79518 -8.007604)
		(end 174.79518 -6.026404)
		(stroke
			(width 0.762)
			(type default)
		)
		(layer "In4.Cu")
	)
	(gr_line
		(start 174.79518 -7.907528)
		(end 174.79518 -6.104128)
		(stroke
			(width 0.254)
			(type default)
		)
		(layer "In4.Cu")
	)
	(gr_line
		(start 174.79518 -7.907528)
		(end 174.79518 -5.926328)
		(stroke
			(width 0.762)
			(type default)
		)
		(layer "In4.Cu")
	)
	(gr_line
		(start 174.79518 -6.204204)
		(end 174.89678 -6.204204)
		(stroke
			(width 0.254)
			(type default)
		)
		(layer "In4.Cu")
	)
	(gr_line
		(start 174.79518 -6.104128)
		(end 174.89678 -6.104128)
		(stroke
			(width 0.254)
			(type default)
		)
		(layer "In4.Cu")
	)
	(gr_line
		(start 174.79518 -3.80746)
		(end 174.79518 -2.00406)
		(stroke
			(width 0.254)
			(type default)
		)
		(layer "In4.Cu")
	)
	(gr_line
		(start 174.79518 -3.80746)
		(end 174.79518 -1.82626)
		(stroke
			(width 0.762)
			(type default)
		)
		(layer "In4.Cu")
	)
	(gr_line
		(start 174.79518 -3.707384)
		(end 174.79518 -1.903984)
		(stroke
			(width 0.254)
			(type default)
		)
		(layer "In4.Cu")
	)
	(gr_line
		(start 174.79518 -3.707384)
		(end 174.79518 -1.726184)
		(stroke
			(width 0.762)
			(type default)
		)
		(layer "In4.Cu")
	)
	(gr_line
		(start 174.79518 -2.00406)
		(end 174.89678 -2.00406)
		(stroke
			(width 0.254)
			(type default)
		)
		(layer "In4.Cu")
	)
	(gr_line
		(start 174.79518 -1.903984)
		(end 174.89678 -1.903984)
		(stroke
			(width 0.254)
			(type default)
		)
		(layer "In4.Cu")
	)
	(gr_line
		(start 174.89678 -12.309348)
		(end 174.84598 -12.309348)
		(stroke
			(width 0.254)
			(type default)
		)
		(layer "In4.Cu")
	)
	(gr_line
		(start 174.89678 -12.209272)
		(end 174.84598 -12.209272)
		(stroke
			(width 0.254)
			(type default)
		)
		(layer "In4.Cu")
	)
	(gr_line
		(start 174.89678 -10.404348)
		(end 174.89678 -12.309348)
		(stroke
			(width 0.254)
			(type default)
		)
		(layer "In4.Cu")
	)
	(gr_line
		(start 174.89678 -10.304272)
		(end 174.89678 -12.209272)
		(stroke
			(width 0.254)
			(type default)
		)
		(layer "In4.Cu")
	)
	(gr_line
		(start 174.89678 -8.109204)
		(end 174.84598 -8.109204)
		(stroke
			(width 0.254)
			(type default)
		)
		(layer "In4.Cu")
	)
	(gr_line
		(start 174.89678 -8.009128)
		(end 174.84598 -8.009128)
		(stroke
			(width 0.254)
			(type default)
		)
		(layer "In4.Cu")
	)
	(gr_line
		(start 174.89678 -6.204204)
		(end 174.89678 -8.109204)
		(stroke
			(width 0.254)
			(type default)
		)
		(layer "In4.Cu")
	)
	(gr_line
		(start 174.89678 -6.104128)
		(end 174.89678 -8.009128)
		(stroke
			(width 0.254)
			(type default)
		)
		(layer "In4.Cu")
	)
	(gr_line
		(start 174.89678 -3.90906)
		(end 174.84598 -3.90906)
		(stroke
			(width 0.254)
			(type default)
		)
		(layer "In4.Cu")
	)
	(gr_line
		(start 174.89678 -3.808984)
		(end 174.84598 -3.808984)
		(stroke
			(width 0.254)
			(type default)
		)
		(layer "In4.Cu")
	)
	(gr_line
		(start 174.89678 -2.00406)
		(end 174.89678 -3.90906)
		(stroke
			(width 0.254)
			(type default)
		)
		(layer "In4.Cu")
	)
	(gr_line
		(start 174.89678 -1.903984)
		(end 174.89678 -3.808984)
		(stroke
			(width 0.254)
			(type default)
		)
		(layer "In4.Cu")
	)
	(gr_line
		(start 174.94758 -12.233148)
		(end 174.94758 -10.251948)
		(stroke
			(width 0.762)
			(type default)
		)
		(layer "In4.Cu")
	)
	(gr_line
		(start 174.94758 -12.133072)
		(end 174.94758 -10.151872)
		(stroke
			(width 0.762)
			(type default)
		)
		(layer "In4.Cu")
	)
	(gr_line
		(start 174.94758 -8.033004)
		(end 174.94758 -6.051804)
		(stroke
			(width 0.762)
			(type default)
		)
		(layer "In4.Cu")
	)
	(gr_line
		(start 174.94758 -7.932928)
		(end 174.94758 -5.951728)
		(stroke
			(width 0.762)
			(type default)
		)
		(layer "In4.Cu")
	)
	(gr_line
		(start 174.94758 -3.83286)
		(end 174.94758 -1.85166)
		(stroke
			(width 0.762)
			(type default)
		)
		(layer "In4.Cu")
	)
	(gr_line
		(start 174.94758 -3.732784)
		(end 174.94758 -1.751584)
		(stroke
			(width 0.762)
			(type default)
		)
		(layer "In4.Cu")
	)
	(gr_line
		(start 175.02378 -12.207748)
		(end 174.79518 -12.207748)
		(stroke
			(width 0.254)
			(type default)
		)
		(layer "In4.Cu")
	)
	(gr_line
		(start 175.02378 -12.107672)
		(end 174.79518 -12.107672)
		(stroke
			(width 0.254)
			(type default)
		)
		(layer "In4.Cu")
	)
	(gr_line
		(start 175.02378 -10.251948)
		(end 175.02378 -12.207748)
		(stroke
			(width 0.254)
			(type default)
		)
		(layer "In4.Cu")
	)
	(gr_line
		(start 175.02378 -10.151872)
		(end 175.02378 -12.107672)
		(stroke
			(width 0.254)
			(type default)
		)
		(layer "In4.Cu")
	)
	(gr_line
		(start 175.02378 -8.007604)
		(end 174.79518 -8.007604)
		(stroke
			(width 0.254)
			(type default)
		)
		(layer "In4.Cu")
	)
	(gr_line
		(start 175.02378 -7.907528)
		(end 174.79518 -7.907528)
		(stroke
			(width 0.254)
			(type default)
		)
		(layer "In4.Cu")
	)
	(gr_line
		(start 175.02378 -6.051804)
		(end 175.02378 -8.007604)
		(stroke
			(width 0.254)
			(type default)
		)
		(layer "In4.Cu")
	)
	(gr_line
		(start 175.02378 -5.951728)
		(end 175.02378 -7.907528)
		(stroke
			(width 0.254)
			(type default)
		)
		(layer "In4.Cu")
	)
	(gr_line
		(start 175.02378 -3.80746)
		(end 174.79518 -3.80746)
		(stroke
			(width 0.254)
			(type default)
		)
		(layer "In4.Cu")
	)
	(gr_line
		(start 175.02378 -3.707384)
		(end 174.79518 -3.707384)
		(stroke
			(width 0.254)
			(type default)
		)
		(layer "In4.Cu")
	)
	(gr_line
		(start 175.02378 -1.85166)
		(end 175.02378 -3.80746)
		(stroke
			(width 0.254)
			(type default)
		)
		(layer "In4.Cu")
	)
	(gr_line
		(start 175.02378 -1.751584)
		(end 175.02378 -3.707384)
		(stroke
			(width 0.254)
			(type default)
		)
		(layer "In4.Cu")
	)
	(gr_line
		(start 175.07458 -12.563348)
		(end 175.07458 -12.512548)
		(stroke
			(width 0.1016)
			(type default)
		)
		(layer "In4.Cu")
	)
	(gr_line
		(start 175.07458 -12.563348)
		(end 175.48098 -12.563348)
		(stroke
			(width 0.1016)
			(type default)
		)
		(layer "In4.Cu")
	)
	(gr_line
		(start 175.07458 -12.512548)
		(end 174.31258 -12.512548)
		(stroke
			(width 0.1016)
			(type default)
		)
		(layer "In4.Cu")
	)
	(gr_line
		(start 175.07458 -12.463272)
		(end 175.07458 -12.412472)
		(stroke
			(width 0.1016)
			(type default)
		)
		(layer "In4.Cu")
	)
	(gr_line
		(start 175.07458 -12.463272)
		(end 175.48098 -12.463272)
		(stroke
			(width 0.1016)
			(type default)
		)
		(layer "In4.Cu")
	)
	(gr_line
		(start 175.07458 -12.412472)
		(end 174.31258 -12.412472)
		(stroke
			(width 0.1016)
			(type default)
		)
		(layer "In4.Cu")
	)
	(gr_line
		(start 175.07458 -12.233148)
		(end 175.07458 -10.251948)
		(stroke
			(width 0.762)
			(type default)
		)
		(layer "In4.Cu")
	)
	(gr_line
		(start 175.07458 -12.133072)
		(end 175.07458 -10.151872)
		(stroke
			(width 0.762)
			(type default)
		)
		(layer "In4.Cu")
	)
	(gr_line
		(start 175.07458 -8.363204)
		(end 175.07458 -8.312404)
		(stroke
			(width 0.1016)
			(type default)
		)
		(layer "In4.Cu")
	)
	(gr_line
		(start 175.07458 -8.363204)
		(end 175.48098 -8.363204)
		(stroke
			(width 0.1016)
			(type default)
		)
		(layer "In4.Cu")
	)
	(gr_line
		(start 175.07458 -8.312404)
		(end 174.31258 -8.312404)
		(stroke
			(width 0.1016)
			(type default)
		)
		(layer "In4.Cu")
	)
	(gr_line
		(start 175.07458 -8.263128)
		(end 175.07458 -8.212328)
		(stroke
			(width 0.1016)
			(type default)
		)
		(layer "In4.Cu")
	)
	(gr_line
		(start 175.07458 -8.263128)
		(end 175.48098 -8.263128)
		(stroke
			(width 0.1016)
			(type default)
		)
		(layer "In4.Cu")
	)
	(gr_line
		(start 175.07458 -8.212328)
		(end 174.31258 -8.212328)
		(stroke
			(width 0.1016)
			(type default)
		)
		(layer "In4.Cu")
	)
	(gr_line
		(start 175.07458 -8.033004)
		(end 175.07458 -6.051804)
		(stroke
			(width 0.762)
			(type default)
		)
		(layer "In4.Cu")
	)
	(gr_line
		(start 175.07458 -7.932928)
		(end 175.07458 -5.951728)
		(stroke
			(width 0.762)
			(type default)
		)
		(layer "In4.Cu")
	)
	(gr_line
		(start 175.07458 -4.16306)
		(end 175.07458 -4.11226)
		(stroke
			(width 0.1016)
			(type default)
		)
		(layer "In4.Cu")
	)
	(gr_line
		(start 175.07458 -4.16306)
		(end 175.48098 -4.16306)
		(stroke
			(width 0.1016)
			(type default)
		)
		(layer "In4.Cu")
	)
	(gr_line
		(start 175.07458 -4.11226)
		(end 174.31258 -4.11226)
		(stroke
			(width 0.1016)
			(type default)
		)
		(layer "In4.Cu")
	)
	(gr_line
		(start 175.07458 -4.062984)
		(end 175.07458 -4.012184)
		(stroke
			(width 0.1016)
			(type default)
		)
		(layer "In4.Cu")
	)
	(gr_line
		(start 175.07458 -4.062984)
		(end 175.48098 -4.062984)
		(stroke
			(width 0.1016)
			(type default)
		)
		(layer "In4.Cu")
	)
	(gr_line
		(start 175.07458 -4.012184)
		(end 174.31258 -4.012184)
		(stroke
			(width 0.1016)
			(type default)
		)
		(layer "In4.Cu")
	)
	(gr_line
		(start 175.07458 -3.83286)
		(end 175.07458 -1.85166)
		(stroke
			(width 0.762)
			(type default)
		)
		(layer "In4.Cu")
	)
	(gr_line
		(start 175.07458 -3.732784)
		(end 175.07458 -1.751584)
		(stroke
			(width 0.762)
			(type default)
		)
		(layer "In4.Cu")
	)
	(gr_line
		(start 175.09998 -12.283948)
		(end 174.69358 -12.283948)
		(stroke
			(width 0.254)
			(type default)
		)
		(layer "In4.Cu")
	)
	(gr_line
		(start 175.09998 -12.183872)
		(end 174.69358 -12.183872)
		(stroke
			(width 0.254)
			(type default)
		)
		(layer "In4.Cu")
	)
	(gr_line
		(start 175.09998 -10.175748)
		(end 175.09998 -12.283948)
		(stroke
			(width 0.254)
			(type default)
		)
		(layer "In4.Cu")
	)
	(gr_line
		(start 175.09998 -10.075672)
		(end 175.09998 -12.183872)
		(stroke
			(width 0.254)
			(type default)
		)
		(layer "In4.Cu")
	)
	(gr_line
		(start 175.09998 -8.083804)
		(end 174.69358 -8.083804)
		(stroke
			(width 0.254)
			(type default)
		)
		(layer "In4.Cu")
	)
	(gr_line
		(start 175.09998 -7.983728)
		(end 174.69358 -7.983728)
		(stroke
			(width 0.254)
			(type default)
		)
		(layer "In4.Cu")
	)
	(gr_line
		(start 175.09998 -5.975604)
		(end 175.09998 -8.083804)
		(stroke
			(width 0.254)
			(type default)
		)
		(layer "In4.Cu")
	)
	(gr_line
		(start 175.09998 -5.875528)
		(end 175.09998 -7.983728)
		(stroke
			(width 0.254)
			(type default)
		)
		(layer "In4.Cu")
	)
	(gr_line
		(start 175.09998 -3.88366)
		(end 174.69358 -3.88366)
		(stroke
			(width 0.254)
			(type default)
		)
		(layer "In4.Cu")
	)
	(gr_line
		(start 175.09998 -3.783584)
		(end 174.69358 -3.783584)
		(stroke
			(width 0.254)
			(type default)
		)
		(layer "In4.Cu")
	)
	(gr_line
		(start 175.09998 -1.77546)
		(end 175.09998 -3.88366)
		(stroke
			(width 0.254)
			(type default)
		)
		(layer "In4.Cu")
	)
	(gr_line
		(start 175.09998 -1.675384)
		(end 175.09998 -3.783584)
		(stroke
			(width 0.254)
			(type default)
		)
		(layer "In4.Cu")
	)
	(gr_line
		(start 175.15078 -12.233148)
		(end 175.15078 -10.251948)
		(stroke
			(width 0.762)
			(type default)
		)
		(layer "In4.Cu")
	)
	(gr_line
		(start 175.15078 -12.133072)
		(end 175.15078 -10.151872)
		(stroke
			(width 0.762)
			(type default)
		)
		(layer "In4.Cu")
	)
	(gr_line
		(start 175.15078 -8.033004)
		(end 175.15078 -6.051804)
		(stroke
			(width 0.762)
			(type default)
		)
		(layer "In4.Cu")
	)
	(gr_line
		(start 175.15078 -7.932928)
		(end 175.15078 -5.951728)
		(stroke
			(width 0.762)
			(type default)
		)
		(layer "In4.Cu")
	)
	(gr_line
		(start 175.15078 -3.83286)
		(end 175.15078 -1.85166)
		(stroke
			(width 0.762)
			(type default)
		)
		(layer "In4.Cu")
	)
	(gr_line
		(start 175.15078 -3.732784)
		(end 175.15078 -1.751584)
		(stroke
			(width 0.762)
			(type default)
		)
		(layer "In4.Cu")
	)
	(gr_line
		(start 175.17618 -12.360148)
		(end 174.61738 -12.360148)
		(stroke
			(width 0.254)
			(type default)
		)
		(layer "In4.Cu")
	)
	(gr_line
		(start 175.17618 -12.260072)
		(end 174.61738 -12.260072)
		(stroke
			(width 0.254)
			(type default)
		)
		(layer "In4.Cu")
	)
	(gr_line
		(start 175.17618 -10.124948)
		(end 175.17618 -12.360148)
		(stroke
			(width 0.254)
			(type default)
		)
		(layer "In4.Cu")
	)
	(gr_line
		(start 175.17618 -10.024872)
		(end 175.17618 -12.260072)
		(stroke
			(width 0.254)
			(type default)
		)
		(layer "In4.Cu")
	)
	(gr_line
		(start 175.17618 -8.160004)
		(end 174.61738 -8.160004)
		(stroke
			(width 0.254)
			(type default)
		)
		(layer "In4.Cu")
	)
	(gr_line
		(start 175.17618 -8.059928)
		(end 174.61738 -8.059928)
		(stroke
			(width 0.254)
			(type default)
		)
		(layer "In4.Cu")
	)
	(gr_line
		(start 175.17618 -5.924804)
		(end 175.17618 -8.160004)
		(stroke
			(width 0.254)
			(type default)
		)
		(layer "In4.Cu")
	)
	(gr_line
		(start 175.17618 -5.824728)
		(end 175.17618 -8.059928)
		(stroke
			(width 0.254)
			(type default)
		)
		(layer "In4.Cu")
	)
	(gr_line
		(start 175.17618 -3.95986)
		(end 174.61738 -3.95986)
		(stroke
			(width 0.254)
			(type default)
		)
		(layer "In4.Cu")
	)
	(gr_line
		(start 175.17618 -3.859784)
		(end 174.61738 -3.859784)
		(stroke
			(width 0.254)
			(type default)
		)
		(layer "In4.Cu")
	)
	(gr_line
		(start 175.17618 -1.72466)
		(end 175.17618 -3.95986)
		(stroke
			(width 0.254)
			(type default)
		)
		(layer "In4.Cu")
	)
	(gr_line
		(start 175.17618 -1.624584)
		(end 175.17618 -3.859784)
		(stroke
			(width 0.254)
			(type default)
		)
		(layer "In4.Cu")
	)
	(gr_line
		(start 175.25238 -12.385548)
		(end 174.54118 -12.385548)
		(stroke
			(width 0.254)
			(type default)
		)
		(layer "In4.Cu")
	)
	(gr_line
		(start 175.25238 -12.285472)
		(end 174.54118 -12.285472)
		(stroke
			(width 0.254)
			(type default)
		)
		(layer "In4.Cu")
	)
	(gr_line
		(start 175.25238 -10.048748)
		(end 175.25238 -12.385548)
		(stroke
			(width 0.254)
			(type default)
		)
		(layer "In4.Cu")
	)
	(gr_line
		(start 175.25238 -9.948672)
		(end 175.25238 -12.285472)
		(stroke
			(width 0.254)
			(type default)
		)
		(layer "In4.Cu")
	)
	(gr_line
		(start 175.25238 -8.185404)
		(end 174.54118 -8.185404)
		(stroke
			(width 0.254)
			(type default)
		)
		(layer "In4.Cu")
	)
	(gr_line
		(start 175.25238 -8.085328)
		(end 174.54118 -8.085328)
		(stroke
			(width 0.254)
			(type default)
		)
		(layer "In4.Cu")
	)
	(gr_line
		(start 175.25238 -5.848604)
		(end 175.25238 -8.185404)
		(stroke
			(width 0.254)
			(type default)
		)
		(layer "In4.Cu")
	)
	(gr_line
		(start 175.25238 -5.748528)
		(end 175.25238 -8.085328)
		(stroke
			(width 0.254)
			(type default)
		)
		(layer "In4.Cu")
	)
	(gr_line
		(start 175.25238 -3.98526)
		(end 174.54118 -3.98526)
		(stroke
			(width 0.254)
			(type default)
		)
		(layer "In4.Cu")
	)
	(gr_line
		(start 175.25238 -3.885184)
		(end 174.54118 -3.885184)
		(stroke
			(width 0.254)
			(type default)
		)
		(layer "In4.Cu")
	)
	(gr_line
		(start 175.25238 -1.64846)
		(end 175.25238 -3.98526)
		(stroke
			(width 0.254)
			(type default)
		)
		(layer "In4.Cu")
	)
	(gr_line
		(start 175.25238 -1.548384)
		(end 175.25238 -3.885184)
		(stroke
			(width 0.254)
			(type default)
		)
		(layer "In4.Cu")
	)
	(gr_line
		(start 175.27778 -12.512548)
		(end 174.28718 -12.512548)
		(stroke
			(width 0.1016)
			(type default)
		)
		(layer "In4.Cu")
	)
	(gr_line
		(start 175.27778 -12.436348)
		(end 174.46498 -12.436348)
		(stroke
			(width 0.254)
			(type default)
		)
		(layer "In4.Cu")
	)
	(gr_line
		(start 175.27778 -12.412472)
		(end 174.28718 -12.412472)
		(stroke
			(width 0.1016)
			(type default)
		)
		(layer "In4.Cu")
	)
	(gr_line
		(start 175.27778 -12.336272)
		(end 174.46498 -12.336272)
		(stroke
			(width 0.254)
			(type default)
		)
		(layer "In4.Cu")
	)
	(gr_line
		(start 175.27778 -10.023348)
		(end 175.27778 -12.436348)
		(stroke
			(width 0.254)
			(type default)
		)
		(layer "In4.Cu")
	)
	(gr_line
		(start 175.27778 -9.923272)
		(end 175.27778 -12.336272)
		(stroke
			(width 0.254)
			(type default)
		)
		(layer "In4.Cu")
	)
	(gr_line
		(start 175.27778 -8.312404)
		(end 174.28718 -8.312404)
		(stroke
			(width 0.1016)
			(type default)
		)
		(layer "In4.Cu")
	)
	(gr_line
		(start 175.27778 -8.236204)
		(end 174.46498 -8.236204)
		(stroke
			(width 0.254)
			(type default)
		)
		(layer "In4.Cu")
	)
	(gr_line
		(start 175.27778 -8.212328)
		(end 174.28718 -8.212328)
		(stroke
			(width 0.1016)
			(type default)
		)
		(layer "In4.Cu")
	)
	(gr_line
		(start 175.27778 -8.136128)
		(end 174.46498 -8.136128)
		(stroke
			(width 0.254)
			(type default)
		)
		(layer "In4.Cu")
	)
	(gr_line
		(start 175.27778 -5.823204)
		(end 175.27778 -8.236204)
		(stroke
			(width 0.254)
			(type default)
		)
		(layer "In4.Cu")
	)
	(gr_line
		(start 175.27778 -5.723128)
		(end 175.27778 -8.136128)
		(stroke
			(width 0.254)
			(type default)
		)
		(layer "In4.Cu")
	)
	(gr_line
		(start 175.27778 -4.11226)
		(end 174.28718 -4.11226)
		(stroke
			(width 0.1016)
			(type default)
		)
		(layer "In4.Cu")
	)
	(gr_line
		(start 175.27778 -4.03606)
		(end 174.46498 -4.03606)
		(stroke
			(width 0.254)
			(type default)
		)
		(layer "In4.Cu")
	)
	(gr_line
		(start 175.27778 -4.012184)
		(end 174.28718 -4.012184)
		(stroke
			(width 0.1016)
			(type default)
		)
		(layer "In4.Cu")
	)
	(gr_line
		(start 175.27778 -3.935984)
		(end 174.46498 -3.935984)
		(stroke
			(width 0.254)
			(type default)
		)
		(layer "In4.Cu")
	)
	(gr_line
		(start 175.27778 -1.62306)
		(end 175.27778 -4.03606)
		(stroke
			(width 0.254)
			(type default)
		)
		(layer "In4.Cu")
	)
	(gr_line
		(start 175.27778 -1.522984)
		(end 175.27778 -3.935984)
		(stroke
			(width 0.254)
			(type default)
		)
		(layer "In4.Cu")
	)
	(gr_line
		(start 175.30318 -12.461748)
		(end 174.43958 -12.461748)
		(stroke
			(width 0.254)
			(type default)
		)
		(layer "In4.Cu")
	)
	(gr_line
		(start 175.30318 -12.361672)
		(end 174.43958 -12.361672)
		(stroke
			(width 0.254)
			(type default)
		)
		(layer "In4.Cu")
	)
	(gr_line
		(start 175.30318 -9.997948)
		(end 175.30318 -12.461748)
		(stroke
			(width 0.254)
			(type default)
		)
		(layer "In4.Cu")
	)
	(gr_line
		(start 175.30318 -9.897872)
		(end 175.30318 -12.361672)
		(stroke
			(width 0.254)
			(type default)
		)
		(layer "In4.Cu")
	)
	(gr_line
		(start 175.30318 -8.261604)
		(end 174.43958 -8.261604)
		(stroke
			(width 0.254)
			(type default)
		)
		(layer "In4.Cu")
	)
	(gr_line
		(start 175.30318 -8.161528)
		(end 174.43958 -8.161528)
		(stroke
			(width 0.254)
			(type default)
		)
		(layer "In4.Cu")
	)
	(gr_line
		(start 175.30318 -5.797804)
		(end 175.30318 -8.261604)
		(stroke
			(width 0.254)
			(type default)
		)
		(layer "In4.Cu")
	)
	(gr_line
		(start 175.30318 -5.697728)
		(end 175.30318 -8.161528)
		(stroke
			(width 0.254)
			(type default)
		)
		(layer "In4.Cu")
	)
	(gr_line
		(start 175.30318 -4.06146)
		(end 174.43958 -4.06146)
		(stroke
			(width 0.254)
			(type default)
		)
		(layer "In4.Cu")
	)
	(gr_line
		(start 175.30318 -3.961384)
		(end 174.43958 -3.961384)
		(stroke
			(width 0.254)
			(type default)
		)
		(layer "In4.Cu")
	)
	(gr_line
		(start 175.30318 -1.59766)
		(end 175.30318 -4.06146)
		(stroke
			(width 0.254)
			(type default)
		)
		(layer "In4.Cu")
	)
	(gr_line
		(start 175.30318 -1.497584)
		(end 175.30318 -3.961384)
		(stroke
			(width 0.254)
			(type default)
		)
		(layer "In4.Cu")
	)
	(gr_line
		(start 175.35398 -12.487148)
		(end 174.41418 -12.487148)
		(stroke
			(width 0.254)
			(type default)
		)
		(layer "In4.Cu")
	)
	(gr_line
		(start 175.35398 -12.387072)
		(end 174.41418 -12.387072)
		(stroke
			(width 0.254)
			(type default)
		)
		(layer "In4.Cu")
	)
	(gr_line
		(start 175.35398 -9.997948)
		(end 175.35398 -12.487148)
		(stroke
			(width 0.254)
			(type default)
		)
		(layer "In4.Cu")
	)
	(gr_line
		(start 175.35398 -9.897872)
		(end 175.35398 -12.387072)
		(stroke
			(width 0.254)
			(type default)
		)
		(layer "In4.Cu")
	)
	(gr_line
		(start 175.35398 -8.287004)
		(end 174.41418 -8.287004)
		(stroke
			(width 0.254)
			(type default)
		)
		(layer "In4.Cu")
	)
	(gr_line
		(start 175.35398 -8.186928)
		(end 174.41418 -8.186928)
		(stroke
			(width 0.254)
			(type default)
		)
		(layer "In4.Cu")
	)
	(gr_line
		(start 175.35398 -5.797804)
		(end 175.35398 -8.287004)
		(stroke
			(width 0.254)
			(type default)
		)
		(layer "In4.Cu")
	)
	(gr_line
		(start 175.35398 -5.697728)
		(end 175.35398 -8.186928)
		(stroke
			(width 0.254)
			(type default)
		)
		(layer "In4.Cu")
	)
	(gr_line
		(start 175.35398 -4.08686)
		(end 174.41418 -4.08686)
		(stroke
			(width 0.254)
			(type default)
		)
		(layer "In4.Cu")
	)
	(gr_line
		(start 175.35398 -3.986784)
		(end 174.41418 -3.986784)
		(stroke
			(width 0.254)
			(type default)
		)
		(layer "In4.Cu")
	)
	(gr_line
		(start 175.35398 -1.59766)
		(end 175.35398 -4.08686)
		(stroke
			(width 0.254)
			(type default)
		)
		(layer "In4.Cu")
	)
	(gr_line
		(start 175.35398 -1.497584)
		(end 175.35398 -3.986784)
		(stroke
			(width 0.254)
			(type default)
		)
		(layer "In4.Cu")
	)
	(gr_line
		(start 175.37938 -12.487148)
		(end 174.41418 -12.487148)
		(stroke
			(width 0.2032)
			(type default)
		)
		(layer "In4.Cu")
	)
	(gr_line
		(start 175.37938 -12.387072)
		(end 174.41418 -12.387072)
		(stroke
			(width 0.2032)
			(type default)
		)
		(layer "In4.Cu")
	)
	(gr_line
		(start 175.37938 -9.947148)
		(end 175.37938 -12.487148)
		(stroke
			(width 0.2032)
			(type default)
		)
		(layer "In4.Cu")
	)
	(gr_line
		(start 175.37938 -9.847072)
		(end 175.37938 -12.387072)
		(stroke
			(width 0.2032)
			(type default)
		)
		(layer "In4.Cu")
	)
	(gr_line
		(start 175.37938 -8.287004)
		(end 174.41418 -8.287004)
		(stroke
			(width 0.2032)
			(type default)
		)
		(layer "In4.Cu")
	)
	(gr_line
		(start 175.37938 -8.186928)
		(end 174.41418 -8.186928)
		(stroke
			(width 0.2032)
			(type default)
		)
		(layer "In4.Cu")
	)
	(gr_line
		(start 175.37938 -5.747004)
		(end 175.37938 -8.287004)
		(stroke
			(width 0.2032)
			(type default)
		)
		(layer "In4.Cu")
	)
	(gr_line
		(start 175.37938 -5.646928)
		(end 175.37938 -8.186928)
		(stroke
			(width 0.2032)
			(type default)
		)
		(layer "In4.Cu")
	)
	(gr_line
		(start 175.37938 -4.08686)
		(end 174.41418 -4.08686)
		(stroke
			(width 0.2032)
			(type default)
		)
		(layer "In4.Cu")
	)
	(gr_line
		(start 175.37938 -3.986784)
		(end 174.41418 -3.986784)
		(stroke
			(width 0.2032)
			(type default)
		)
		(layer "In4.Cu")
	)
	(gr_line
		(start 175.37938 -1.54686)
		(end 175.37938 -4.08686)
		(stroke
			(width 0.2032)
			(type default)
		)
		(layer "In4.Cu")
	)
	(gr_line
		(start 175.37938 -1.446784)
		(end 175.37938 -3.986784)
		(stroke
			(width 0.2032)
			(type default)
		)
		(layer "In4.Cu")
	)
	(gr_line
		(start 175.43018 -12.512548)
		(end 174.36338 -12.512548)
		(stroke
			(width 0.2032)
			(type default)
		)
		(layer "In4.Cu")
	)
	(gr_line
		(start 175.43018 -12.412472)
		(end 174.36338 -12.412472)
		(stroke
			(width 0.2032)
			(type default)
		)
		(layer "In4.Cu")
	)
	(gr_line
		(start 175.43018 -9.947148)
		(end 175.43018 -12.512548)
		(stroke
			(width 0.2032)
			(type default)
		)
		(layer "In4.Cu")
	)
	(gr_line
		(start 175.43018 -9.847072)
		(end 175.43018 -12.412472)
		(stroke
			(width 0.2032)
			(type default)
		)
		(layer "In4.Cu")
	)
	(gr_line
		(start 175.43018 -8.312404)
		(end 174.36338 -8.312404)
		(stroke
			(width 0.2032)
			(type default)
		)
		(layer "In4.Cu")
	)
	(gr_line
		(start 175.43018 -8.212328)
		(end 174.36338 -8.212328)
		(stroke
			(width 0.2032)
			(type default)
		)
		(layer "In4.Cu")
	)
	(gr_line
		(start 175.43018 -5.747004)
		(end 175.43018 -8.312404)
		(stroke
			(width 0.2032)
			(type default)
		)
		(layer "In4.Cu")
	)
	(gr_line
		(start 175.43018 -5.646928)
		(end 175.43018 -8.212328)
		(stroke
			(width 0.2032)
			(type default)
		)
		(layer "In4.Cu")
	)
	(gr_line
		(start 175.43018 -4.11226)
		(end 174.36338 -4.11226)
		(stroke
			(width 0.2032)
			(type default)
		)
		(layer "In4.Cu")
	)
	(gr_line
		(start 175.43018 -4.012184)
		(end 174.36338 -4.012184)
		(stroke
			(width 0.2032)
			(type default)
		)
		(layer "In4.Cu")
	)
	(gr_line
		(start 175.43018 -1.54686)
		(end 175.43018 -4.11226)
		(stroke
			(width 0.2032)
			(type default)
		)
		(layer "In4.Cu")
	)
	(gr_line
		(start 175.43018 -1.446784)
		(end 175.43018 -4.012184)
		(stroke
			(width 0.2032)
			(type default)
		)
		(layer "In4.Cu")
	)
	(gr_line
		(start 175.45558 -12.512548)
		(end 174.33798 -12.512548)
		(stroke
			(width 0.1016)
			(type default)
		)
		(layer "In4.Cu")
	)
	(gr_line
		(start 175.45558 -12.412472)
		(end 174.33798 -12.412472)
		(stroke
			(width 0.1016)
			(type default)
		)
		(layer "In4.Cu")
	)
	(gr_line
		(start 175.45558 -9.921748)
		(end 175.45558 -12.512548)
		(stroke
			(width 0.1016)
			(type default)
		)
		(layer "In4.Cu")
	)
	(gr_line
		(start 175.45558 -9.821672)
		(end 175.45558 -12.412472)
		(stroke
			(width 0.1016)
			(type default)
		)
		(layer "In4.Cu")
	)
	(gr_line
		(start 175.45558 -8.312404)
		(end 174.33798 -8.312404)
		(stroke
			(width 0.1016)
			(type default)
		)
		(layer "In4.Cu")
	)
	(gr_line
		(start 175.45558 -8.212328)
		(end 174.33798 -8.212328)
		(stroke
			(width 0.1016)
			(type default)
		)
		(layer "In4.Cu")
	)
	(gr_line
		(start 175.45558 -5.721604)
		(end 175.45558 -8.312404)
		(stroke
			(width 0.1016)
			(type default)
		)
		(layer "In4.Cu")
	)
	(gr_line
		(start 175.45558 -5.621528)
		(end 175.45558 -8.212328)
		(stroke
			(width 0.1016)
			(type default)
		)
		(layer "In4.Cu")
	)
	(gr_line
		(start 175.45558 -4.11226)
		(end 174.33798 -4.11226)
		(stroke
			(width 0.1016)
			(type default)
		)
		(layer "In4.Cu")
	)
	(gr_line
		(start 175.45558 -4.012184)
		(end 174.33798 -4.012184)
		(stroke
			(width 0.1016)
			(type default)
		)
		(layer "In4.Cu")
	)
	(gr_line
		(start 175.45558 -1.52146)
		(end 175.45558 -4.11226)
		(stroke
			(width 0.1016)
			(type default)
		)
		(layer "In4.Cu")
	)
	(gr_line
		(start 175.45558 -1.421384)
		(end 175.45558 -4.012184)
		(stroke
			(width 0.1016)
			(type default)
		)
		(layer "In4.Cu")
	)
	(gr_line
		(start 175.48098 -12.563348)
		(end 175.07458 -12.563348)
		(stroke
			(width 0.1016)
			(type default)
		)
		(layer "In4.Cu")
	)
	(gr_line
		(start 175.48098 -12.563348)
		(end 175.48098 -9.896348)
		(stroke
			(width 0.1016)
			(type default)
		)
		(layer "In4.Cu")
	)
	(gr_line
		(start 175.48098 -12.463272)
		(end 175.07458 -12.463272)
		(stroke
			(width 0.1016)
			(type default)
		)
		(layer "In4.Cu")
	)
	(gr_line
		(start 175.48098 -12.463272)
		(end 175.48098 -9.796272)
		(stroke
			(width 0.1016)
			(type default)
		)
		(layer "In4.Cu")
	)
	(gr_line
		(start 175.48098 -9.896348)
		(end 174.28718 -9.896348)
		(stroke
			(width 0.1016)
			(type default)
		)
		(layer "In4.Cu")
	)
	(gr_line
		(start 175.48098 -9.896348)
		(end 175.48098 -12.563348)
		(stroke
			(width 0.1016)
			(type default)
		)
		(layer "In4.Cu")
	)
	(gr_line
		(start 175.48098 -9.796272)
		(end 174.28718 -9.796272)
		(stroke
			(width 0.1016)
			(type default)
		)
		(layer "In4.Cu")
	)
	(gr_line
		(start 175.48098 -9.796272)
		(end 175.48098 -12.463272)
		(stroke
			(width 0.1016)
			(type default)
		)
		(layer "In4.Cu")
	)
	(gr_line
		(start 175.48098 -8.363204)
		(end 175.07458 -8.363204)
		(stroke
			(width 0.1016)
			(type default)
		)
		(layer "In4.Cu")
	)
	(gr_line
		(start 175.48098 -8.363204)
		(end 175.48098 -5.696204)
		(stroke
			(width 0.1016)
			(type default)
		)
		(layer "In4.Cu")
	)
	(gr_line
		(start 175.48098 -8.263128)
		(end 175.07458 -8.263128)
		(stroke
			(width 0.1016)
			(type default)
		)
		(layer "In4.Cu")
	)
	(gr_line
		(start 175.48098 -8.263128)
		(end 175.48098 -5.596128)
		(stroke
			(width 0.1016)
			(type default)
		)
		(layer "In4.Cu")
	)
	(gr_line
		(start 175.48098 -5.696204)
		(end 174.28718 -5.696204)
		(stroke
			(width 0.1016)
			(type default)
		)
		(layer "In4.Cu")
	)
	(gr_line
		(start 175.48098 -5.696204)
		(end 175.48098 -8.363204)
		(stroke
			(width 0.1016)
			(type default)
		)
		(layer "In4.Cu")
	)
	(gr_line
		(start 175.48098 -5.596128)
		(end 174.28718 -5.596128)
		(stroke
			(width 0.1016)
			(type default)
		)
		(layer "In4.Cu")
	)
	(gr_line
		(start 175.48098 -5.596128)
		(end 175.48098 -8.263128)
		(stroke
			(width 0.1016)
			(type default)
		)
		(layer "In4.Cu")
	)
	(gr_line
		(start 175.48098 -4.16306)
		(end 175.07458 -4.16306)
		(stroke
			(width 0.1016)
			(type default)
		)
		(layer "In4.Cu")
	)
	(gr_line
		(start 175.48098 -4.16306)
		(end 175.48098 -1.49606)
		(stroke
			(width 0.1016)
			(type default)
		)
		(layer "In4.Cu")
	)
	(gr_line
		(start 175.48098 -4.062984)
		(end 175.07458 -4.062984)
		(stroke
			(width 0.1016)
			(type default)
		)
		(layer "In4.Cu")
	)
	(gr_line
		(start 175.48098 -4.062984)
		(end 175.48098 -1.395984)
		(stroke
			(width 0.1016)
			(type default)
		)
		(layer "In4.Cu")
	)
	(gr_line
		(start 175.48098 -1.49606)
		(end 174.28718 -1.49606)
		(stroke
			(width 0.1016)
			(type default)
		)
		(layer "In4.Cu")
	)
	(gr_line
		(start 175.48098 -1.49606)
		(end 175.48098 -4.16306)
		(stroke
			(width 0.1016)
			(type default)
		)
		(layer "In4.Cu")
	)
	(gr_line
		(start 175.48098 -1.494028)
		(end 174.26178 -1.494028)
		(stroke
			(width 0.1016)
			(type default)
		)
		(layer "In4.Cu")
	)
	(gr_line
		(start 175.48098 -1.494028)
		(end 174.28718 -1.494028)
		(stroke
			(width 0.1016)
			(type default)
		)
		(layer "In4.Cu")
	)
	(gr_line
		(start 175.48098 -1.395984)
		(end 174.28718 -1.395984)
		(stroke
			(width 0.1016)
			(type default)
		)
		(layer "In4.Cu")
	)
	(gr_line
		(start 175.48098 -1.395984)
		(end 175.48098 -4.062984)
		(stroke
			(width 0.1016)
			(type default)
		)
		(layer "In4.Cu")
	)
	(gr_line
		(start 175.50638 -1.468628)
		(end 174.26178 -1.468628)
		(stroke
			(width 0.1016)
			(type default)
		)
		(layer "In4.Cu")
	)
	(gr_line
		(start 176.520094 -30.99562)
		(end 175.250094 -30.99562)
		(stroke
			(width 0.7874)
			(type default)
		)
		(layer "In4.Cu")
	)
	(gr_line
		(start 178.22418 -24.6634)
		(end 178.22418 -23.3934)
		(stroke
			(width 0.7874)
			(type default)
		)
		(layer "In4.Cu")
	)
	(gr_line
		(start 183.9976 -26.8224)
		(end 185.2676 -26.8224)
		(stroke
			(width 0.7874)
			(type default)
		)
		(layer "In4.Cu")
	)
	(gr_line
		(start 184.22874 -29.30906)
		(end 185.49874 -29.30906)
		(stroke
			(width 0.7874)
			(type default)
		)
		(layer "In4.Cu")
	)
	(gr_line
		(start 189.45987 -30.594808)
		(end 190.72987 -30.594808)
		(stroke
			(width 0.7874)
			(type default)
		)
		(layer "In4.Cu")
	)
	(gr_line
		(start 191.12992 -23.57882)
		(end 189.85992 -23.57882)
		(stroke
			(width 0.7874)
			(type default)
		)
		(layer "In4.Cu")
	)
	(gr_line
		(start 191.87414 -31.68142)
		(end 193.14414 -31.68142)
		(stroke
			(width 0.7874)
			(type default)
		)
		(layer "In4.Cu")
	)
	(gr_line
		(start 193.529966 -18.5166)
		(end 192.259966 -18.5166)
		(stroke
			(width 0.7874)
			(type default)
		)
		(layer "In4.Cu")
	)
	(gr_line
		(start 194.259962 -30.56382)
		(end 195.529962 -30.56382)
		(stroke
			(width 0.7874)
			(type default)
		)
		(layer "In4.Cu")
	)
	(gr_arc
		(start 197.300088 -8.263382)
		(mid 198.922885 -13.697276)
		(end 201.00036 -8.420608)
		(stroke
			(width 2.032)
			(type default)
		)
		(layer "In4.Cu")
	)
	(gr_line
		(start 197.300088 -4.907788)
		(end 197.300088 -8.263382)
		(stroke
			(width 2.032)
			(type default)
		)
		(layer "In4.Cu")
	)
	(gr_line
		(start 197.310756 -4.89712)
		(end 197.300088 -4.907788)
		(stroke
			(width 2.032)
			(type default)
		)
		(layer "In4.Cu")
	)
	(gr_line
		(start 197.6628 -24.67102)
		(end 197.6628 -23.40102)
		(stroke
			(width 0.7874)
			(type default)
		)
		(layer "In4.Cu")
	)
	(gr_line
		(start 199.04964 -10.700004)
		(end 199.049894 -10.700258)
		(stroke
			(width 4.064)
			(type default)
		)
		(layer "In4.Cu")
	)
	(gr_line
		(start 199.04964 -4.699762)
		(end 199.04964 -10.700004)
		(stroke
			(width 4.064)
			(type default)
		)
		(layer "In4.Cu")
	)
	(gr_line
		(start 199.049894 -10.700258)
		(end 199.049894 -10.700004)
		(stroke
			(width 6.604)
			(type default)
		)
		(layer "In4.Cu")
	)
	(gr_line
		(start 200.799954 -8.220202)
		(end 200.799954 -4.700016)
		(stroke
			(width 2.032)
			(type default)
		)
		(layer "In4.Cu")
	)
	(gr_arc
		(start 200.799954 -4.700016)
		(mid 198.951198 -2.952487)
		(end 197.310756 -4.89712)
		(stroke
			(width 2.032)
			(type default)
		)
		(layer "In4.Cu")
	)
	(gr_line
		(start 201.00036 -8.420608)
		(end 200.799954 -8.220202)
		(stroke
			(width 2.032)
			(type default)
		)
		(layer "In4.Cu")
	)
	(gr_line
		(start 202.989942 -50.390044)
		(end 203.36891 -50.464466)
		(stroke
			(width 2.032)
			(type default)
		)
		(layer "In4.Cu")
	)
	(gr_line
		(start 203.36891 -50.464466)
		(end 203.691236 -50.677064)
		(stroke
			(width 2.032)
			(type default)
		)
		(layer "In4.Cu")
	)
	(gr_line
		(start 203.691236 -50.677064)
		(end 203.909168 -50.996088)
		(stroke
			(width 2.032)
			(type default)
		)
		(layer "In4.Cu")
	)
	(gr_line
		(start 203.909168 -50.996088)
		(end 203.997814 -51.376072)
		(stroke
			(width 2.032)
			(type default)
		)
		(layer "In4.Cu")
	)
	(gr_line
		(start 203.997814 -51.376072)
		(end 204.06614 -51.702716)
		(stroke
			(width 2.032)
			(type default)
		)
		(layer "In4.Cu")
	)
	(gr_line
		(start 204.06614 -51.702716)
		(end 204.282802 -52.027074)
		(stroke
			(width 2.032)
			(type default)
		)
		(layer "In4.Cu")
	)
	(gr_line
		(start 204.282802 -52.027074)
		(end 204.607414 -52.24399)
		(stroke
			(width 2.032)
			(type default)
		)
		(layer "In4.Cu")
	)
	(gr_line
		(start 204.68336 -52.319936)
		(end 204.607414 -52.24399)
		(stroke
			(width 2.032)
			(type default)
		)
		(layer "In4.Cu")
	)
	(gr_arc
		(start 208.060036 -45.06341)
		(mid 209.682833 -50.497304)
		(end 211.760308 -45.220636)
		(stroke
			(width 2.032)
			(type default)
		)
		(layer "In4.Cu")
	)
	(gr_line
		(start 208.060036 -41.707816)
		(end 208.060036 -45.06341)
		(stroke
			(width 2.032)
			(type default)
		)
		(layer "In4.Cu")
	)
	(gr_line
		(start 208.070704 -41.697148)
		(end 208.060036 -41.707816)
		(stroke
			(width 2.032)
			(type default)
		)
		(layer "In4.Cu")
	)
	(gr_line
		(start 209.809588 -47.500032)
		(end 209.809842 -47.500286)
		(stroke
			(width 4.064)
			(type default)
		)
		(layer "In4.Cu")
	)
	(gr_line
		(start 209.809588 -41.49979)
		(end 209.809588 -47.500032)
		(stroke
			(width 4.064)
			(type default)
		)
		(layer "In4.Cu")
	)
	(gr_line
		(start 209.809842 -47.500286)
		(end 209.809842 -47.500032)
		(stroke
			(width 6.604)
			(type default)
		)
		(layer "In4.Cu")
	)
	(gr_line
		(start 211.559902 -45.02023)
		(end 211.559902 -41.500044)
		(stroke
			(width 2.032)
			(type default)
		)
		(layer "In4.Cu")
	)
	(gr_arc
		(start 211.559902 -41.500044)
		(mid 209.711146 -39.752515)
		(end 208.070704 -41.697148)
		(stroke
			(width 2.032)
			(type default)
		)
		(layer "In4.Cu")
	)
	(gr_line
		(start 211.760308 -45.220636)
		(end 211.559902 -45.02023)
		(stroke
			(width 2.032)
			(type default)
		)
		(layer "In4.Cu")
	)
	(gr_arc
		(start 278.06015 -8.263128)
		(mid 279.682947 -13.697022)
		(end 281.760422 -8.420354)
		(stroke
			(width 2.032)
			(type default)
		)
		(layer "In4.Cu")
	)
	(gr_line
		(start 278.06015 -4.907534)
		(end 278.06015 -8.263128)
		(stroke
			(width 2.032)
			(type default)
		)
		(layer "In4.Cu")
	)
	(gr_line
		(start 278.070818 -4.896866)
		(end 278.06015 -4.907534)
		(stroke
			(width 2.032)
			(type default)
		)
		(layer "In4.Cu")
	)
	(gr_line
		(start 279.809702 -10.69975)
		(end 279.809956 -10.700004)
		(stroke
			(width 4.064)
			(type default)
		)
		(layer "In4.Cu")
	)
	(gr_line
		(start 279.809702 -4.699508)
		(end 279.809702 -10.69975)
		(stroke
			(width 4.064)
			(type default)
		)
		(layer "In4.Cu")
	)
	(gr_line
		(start 279.809956 -10.700004)
		(end 279.809956 -10.69975)
		(stroke
			(width 6.604)
			(type default)
		)
		(layer "In4.Cu")
	)
	(gr_line
		(start 281.560016 -8.219948)
		(end 281.560016 -4.699762)
		(stroke
			(width 2.032)
			(type default)
		)
		(layer "In4.Cu")
	)
	(gr_arc
		(start 281.560016 -4.699762)
		(mid 279.71126 -2.952233)
		(end 278.070818 -4.896866)
		(stroke
			(width 2.032)
			(type default)
		)
		(layer "In4.Cu")
	)
	(gr_line
		(start 281.760422 -8.420354)
		(end 281.560016 -8.219948)
		(stroke
			(width 2.032)
			(type default)
		)
		(layer "In4.Cu")
	)
	(gr_arc
		(start 299.060108 -45.06341)
		(mid 300.682905 -50.497304)
		(end 302.76038 -45.220636)
		(stroke
			(width 2.032)
			(type default)
		)
		(layer "In4.Cu")
	)
	(gr_line
		(start 299.060108 -41.707816)
		(end 299.060108 -45.06341)
		(stroke
			(width 2.032)
			(type default)
		)
		(layer "In4.Cu")
	)
	(gr_line
		(start 299.070776 -41.697148)
		(end 299.060108 -41.707816)
		(stroke
			(width 2.032)
			(type default)
		)
		(layer "In4.Cu")
	)
	(gr_line
		(start 300.80966 -47.500032)
		(end 300.809914 -47.500286)
		(stroke
			(width 4.064)
			(type default)
		)
		(layer "In4.Cu")
	)
	(gr_line
		(start 300.80966 -41.49979)
		(end 300.80966 -47.500032)
		(stroke
			(width 4.064)
			(type default)
		)
		(layer "In4.Cu")
	)
	(gr_line
		(start 300.809914 -47.500286)
		(end 300.809914 -47.500032)
		(stroke
			(width 6.604)
			(type default)
		)
		(layer "In4.Cu")
	)
	(gr_line
		(start 302.559974 -45.02023)
		(end 302.559974 -41.500044)
		(stroke
			(width 2.032)
			(type default)
		)
		(layer "In4.Cu")
	)
	(gr_arc
		(start 302.559974 -41.500044)
		(mid 300.711218 -39.752515)
		(end 299.070776 -41.697148)
		(stroke
			(width 2.032)
			(type default)
		)
		(layer "In4.Cu")
	)
	(gr_line
		(start 302.76038 -45.220636)
		(end 302.559974 -45.02023)
		(stroke
			(width 2.032)
			(type default)
		)
		(layer "In4.Cu")
	)
	(gr_line
		(start 316.06998 -52.319936)
		(end 204.68336 -52.319936)
		(stroke
			(width 2.032)
			(type default)
		)
		(layer "In4.Cu")
	)
	(gr_arc
		(start 316.06998 -52.319936)
		(mid 316.777112 -52.027053)
		(end 317.069978 -51.319938)
		(stroke
			(width 2.032)
			(type default)
		)
		(layer "In4.Cu")
	)
	(gr_line
		(start 317.069978 -50.8)
		(end 317.069978 -51.319938)
		(stroke
			(width 2.032)
			(type default)
		)
		(layer "In4.Cu")
	)
	(gr_arc
		(start 318.069976 -49.800002)
		(mid 317.362871 -50.092895)
		(end 317.069978 -50.8)
		(stroke
			(width 2.032)
			(type default)
		)
		(layer "In4.Cu")
	)
	(gr_line
		(start 322.576698 -11.3792)
		(end 322.576698 -9.1948)
		(stroke
			(width 0.254)
			(type default)
		)
		(layer "In4.Cu")
	)
	(gr_line
		(start 322.576698 -9.1948)
		(end 324.151498 -9.1948)
		(stroke
			(width 0.254)
			(type default)
		)
		(layer "In4.Cu")
	)
	(gr_line
		(start 322.602098 -11.3792)
		(end 322.602098 -9.2456)
		(stroke
			(width 0.254)
			(type default)
		)
		(layer "In4.Cu")
	)
	(gr_line
		(start 322.602098 -9.2456)
		(end 324.126098 -9.2456)
		(stroke
			(width 0.254)
			(type default)
		)
		(layer "In4.Cu")
	)
	(gr_line
		(start 322.652898 -11.3538)
		(end 322.652898 -9.3726)
		(stroke
			(width 0.254)
			(type default)
		)
		(layer "In4.Cu")
	)
	(gr_line
		(start 322.652898 -9.3726)
		(end 324.100698 -9.3726)
		(stroke
			(width 0.254)
			(type default)
		)
		(layer "In4.Cu")
	)
	(gr_line
		(start 322.707 -11.303)
		(end 323.0118 -11.303)
		(stroke
			(width 0.1016)
			(type default)
		)
		(layer "In4.Cu")
	)
	(gr_line
		(start 322.707 -9.2964)
		(end 322.707 -11.303)
		(stroke
			(width 0.1016)
			(type default)
		)
		(layer "In4.Cu")
	)
	(gr_line
		(start 322.7578 -11.2268)
		(end 323.85 -11.2268)
		(stroke
			(width 0.2032)
			(type default)
		)
		(layer "In4.Cu")
	)
	(gr_line
		(start 322.7578 -9.3726)
		(end 322.7578 -11.2268)
		(stroke
			(width 0.2032)
			(type default)
		)
		(layer "In4.Cu")
	)
	(gr_line
		(start 322.7832 -11.2268)
		(end 323.9516 -11.2268)
		(stroke
			(width 0.2032)
			(type default)
		)
		(layer "In4.Cu")
	)
	(gr_line
		(start 322.7832 -9.4234)
		(end 322.7832 -11.2268)
		(stroke
			(width 0.2032)
			(type default)
		)
		(layer "In4.Cu")
	)
	(gr_line
		(start 322.830698 -11.1252)
		(end 322.830698 -9.5758)
		(stroke
			(width 0.762)
			(type default)
		)
		(layer "In4.Cu")
	)
	(gr_line
		(start 322.830698 -11.1252)
		(end 323.745098 -11.1252)
		(stroke
			(width 0.762)
			(type default)
		)
		(layer "In4.Cu")
	)
	(gr_line
		(start 322.830698 -11.0998)
		(end 322.830698 -9.5504)
		(stroke
			(width 0.762)
			(type default)
		)
		(layer "In4.Cu")
	)
	(gr_line
		(start 322.830698 -10.9982)
		(end 322.830698 -9.4488)
		(stroke
			(width 0.762)
			(type default)
		)
		(layer "In4.Cu")
	)
	(gr_line
		(start 322.830698 -9.4488)
		(end 323.745098 -9.4488)
		(stroke
			(width 0.762)
			(type default)
		)
		(layer "In4.Cu")
	)
	(gr_line
		(start 322.834 -11.176)
		(end 323.9262 -11.176)
		(stroke
			(width 0.2032)
			(type default)
		)
		(layer "In4.Cu")
	)
	(gr_line
		(start 322.834 -9.4742)
		(end 322.834 -11.176)
		(stroke
			(width 0.2032)
			(type default)
		)
		(layer "In4.Cu")
	)
	(gr_line
		(start 322.856098 -10.9982)
		(end 323.770498 -10.9982)
		(stroke
			(width 0.762)
			(type default)
		)
		(layer "In4.Cu")
	)
	(gr_line
		(start 322.856098 -9.5758)
		(end 323.770498 -9.5758)
		(stroke
			(width 0.762)
			(type default)
		)
		(layer "In4.Cu")
	)
	(gr_line
		(start 322.9356 -11.0744)
		(end 323.723 -11.0744)
		(stroke
			(width 0.508)
			(type default)
		)
		(layer "In4.Cu")
	)
	(gr_line
		(start 322.9356 -11.049)
		(end 322.9356 -9.525)
		(stroke
			(width 0.508)
			(type default)
		)
		(layer "In4.Cu")
	)
	(gr_line
		(start 322.961 -11.0744)
		(end 322.961 -9.5504)
		(stroke
			(width 0.508)
			(type default)
		)
		(layer "In4.Cu")
	)
	(gr_line
		(start 322.983098 -11.1252)
		(end 323.897498 -11.1252)
		(stroke
			(width 0.762)
			(type default)
		)
		(layer "In4.Cu")
	)
	(gr_line
		(start 322.983098 -9.4488)
		(end 323.897498 -9.4488)
		(stroke
			(width 0.762)
			(type default)
		)
		(layer "In4.Cu")
	)
	(gr_line
		(start 322.9864 -9.525)
		(end 323.723 -9.525)
		(stroke
			(width 0.508)
			(type default)
		)
		(layer "In4.Cu")
	)
	(gr_line
		(start 323.0118 -11.303)
		(end 324.0024 -11.303)
		(stroke
			(width 0.1016)
			(type default)
		)
		(layer "In4.Cu")
	)
	(gr_line
		(start 323.0118 -11.0744)
		(end 323.0118 -9.5504)
		(stroke
			(width 0.508)
			(type default)
		)
		(layer "In4.Cu")
	)
	(gr_line
		(start 323.0372 -11.0744)
		(end 323.0372 -9.5504)
		(stroke
			(width 0.508)
			(type default)
		)
		(layer "In4.Cu")
	)
	(gr_line
		(start 323.0626 -11.0744)
		(end 323.0626 -9.5504)
		(stroke
			(width 0.508)
			(type default)
		)
		(layer "In4.Cu")
	)
	(gr_line
		(start 323.088 -11.0744)
		(end 323.088 -9.5504)
		(stroke
			(width 0.508)
			(type default)
		)
		(layer "In4.Cu")
	)
	(gr_line
		(start 323.088 -11.049)
		(end 323.088 -9.525)
		(stroke
			(width 0.508)
			(type default)
		)
		(layer "In4.Cu")
	)
	(gr_line
		(start 323.1134 -11.0744)
		(end 323.1134 -9.5504)
		(stroke
			(width 0.508)
			(type default)
		)
		(layer "In4.Cu")
	)
	(gr_line
		(start 323.1388 -11.0744)
		(end 323.1388 -9.5504)
		(stroke
			(width 0.508)
			(type default)
		)
		(layer "In4.Cu")
	)
	(gr_line
		(start 323.1896 -11.0744)
		(end 323.1896 -9.5504)
		(stroke
			(width 0.508)
			(type default)
		)
		(layer "In4.Cu")
	)
	(gr_line
		(start 323.1896 -11.049)
		(end 323.1896 -9.525)
		(stroke
			(width 0.508)
			(type default)
		)
		(layer "In4.Cu")
	)
	(gr_line
		(start 323.215 -11.0744)
		(end 323.215 -9.5504)
		(stroke
			(width 0.508)
			(type default)
		)
		(layer "In4.Cu")
	)
	(gr_line
		(start 323.2404 -11.0744)
		(end 323.2404 -9.5504)
		(stroke
			(width 0.508)
			(type default)
		)
		(layer "In4.Cu")
	)
	(gr_line
		(start 323.2658 -11.0744)
		(end 323.2658 -9.5504)
		(stroke
			(width 0.508)
			(type default)
		)
		(layer "In4.Cu")
	)
	(gr_line
		(start 323.3166 -11.0744)
		(end 323.3166 -9.5504)
		(stroke
			(width 0.508)
			(type default)
		)
		(layer "In4.Cu")
	)
	(gr_line
		(start 323.342 -11.0744)
		(end 323.342 -9.5504)
		(stroke
			(width 0.508)
			(type default)
		)
		(layer "In4.Cu")
	)
	(gr_line
		(start 323.342 -11.049)
		(end 323.342 -9.525)
		(stroke
			(width 0.508)
			(type default)
		)
		(layer "In4.Cu")
	)
	(gr_line
		(start 323.3674 -11.0744)
		(end 323.3674 -9.5504)
		(stroke
			(width 0.508)
			(type default)
		)
		(layer "In4.Cu")
	)
	(gr_line
		(start 323.3928 -11.0744)
		(end 323.3928 -9.5504)
		(stroke
			(width 0.508)
			(type default)
		)
		(layer "In4.Cu")
	)
	(gr_line
		(start 323.4182 -11.0744)
		(end 323.4182 -9.5504)
		(stroke
			(width 0.508)
			(type default)
		)
		(layer "In4.Cu")
	)
	(gr_line
		(start 323.4182 -11.049)
		(end 323.4182 -9.525)
		(stroke
			(width 0.508)
			(type default)
		)
		(layer "In4.Cu")
	)
	(gr_line
		(start 323.4436 -11.0744)
		(end 323.4436 -9.5504)
		(stroke
			(width 0.508)
			(type default)
		)
		(layer "In4.Cu")
	)
	(gr_line
		(start 323.469 -11.0744)
		(end 323.469 -9.5504)
		(stroke
			(width 0.508)
			(type default)
		)
		(layer "In4.Cu")
	)
	(gr_line
		(start 323.469 -11.049)
		(end 323.469 -9.525)
		(stroke
			(width 0.508)
			(type default)
		)
		(layer "In4.Cu")
	)
	(gr_line
		(start 323.4944 -11.0744)
		(end 323.4944 -9.5504)
		(stroke
			(width 0.508)
			(type default)
		)
		(layer "In4.Cu")
	)
	(gr_line
		(start 323.4944 -11.049)
		(end 323.4944 -9.525)
		(stroke
			(width 0.508)
			(type default)
		)
		(layer "In4.Cu")
	)
	(gr_line
		(start 323.5198 -11.049)
		(end 323.5198 -9.525)
		(stroke
			(width 0.508)
			(type default)
		)
		(layer "In4.Cu")
	)
	(gr_line
		(start 323.5452 -11.0744)
		(end 323.5452 -9.5504)
		(stroke
			(width 0.508)
			(type default)
		)
		(layer "In4.Cu")
	)
	(gr_line
		(start 323.567298 -11.3792)
		(end 322.576698 -11.3792)
		(stroke
			(width 0.254)
			(type default)
		)
		(layer "In4.Cu")
	)
	(gr_line
		(start 323.5706 -11.049)
		(end 323.5706 -9.525)
		(stroke
			(width 0.508)
			(type default)
		)
		(layer "In4.Cu")
	)
	(gr_line
		(start 323.596 -11.049)
		(end 323.596 -9.525)
		(stroke
			(width 0.508)
			(type default)
		)
		(layer "In4.Cu")
	)
	(gr_line
		(start 323.6214 -11.0744)
		(end 323.6214 -9.5504)
		(stroke
			(width 0.508)
			(type default)
		)
		(layer "In4.Cu")
	)
	(gr_line
		(start 323.6468 -11.0744)
		(end 323.6468 -9.5504)
		(stroke
			(width 0.508)
			(type default)
		)
		(layer "In4.Cu")
	)
	(gr_line
		(start 323.6468 -11.049)
		(end 323.6468 -9.525)
		(stroke
			(width 0.508)
			(type default)
		)
		(layer "In4.Cu")
	)
	(gr_line
		(start 323.6976 -11.0744)
		(end 323.6976 -9.5504)
		(stroke
			(width 0.508)
			(type default)
		)
		(layer "In4.Cu")
	)
	(gr_line
		(start 323.6976 -11.049)
		(end 323.6976 -9.525)
		(stroke
			(width 0.508)
			(type default)
		)
		(layer "In4.Cu")
	)
	(gr_line
		(start 323.7484 -11.0744)
		(end 323.7484 -9.5504)
		(stroke
			(width 0.508)
			(type default)
		)
		(layer "In4.Cu")
	)
	(gr_line
		(start 323.7484 -11.049)
		(end 323.7484 -9.525)
		(stroke
			(width 0.508)
			(type default)
		)
		(layer "In4.Cu")
	)
	(gr_line
		(start 323.770498 -11.0998)
		(end 323.770498 -9.5504)
		(stroke
			(width 0.762)
			(type default)
		)
		(layer "In4.Cu")
	)
	(gr_line
		(start 323.7738 -11.0744)
		(end 323.7738 -9.5504)
		(stroke
			(width 0.508)
			(type default)
		)
		(layer "In4.Cu")
	)
	(gr_line
		(start 323.7992 -11.0744)
		(end 323.7992 -9.5504)
		(stroke
			(width 0.508)
			(type default)
		)
		(layer "In4.Cu")
	)
	(gr_line
		(start 323.85 -11.2268)
		(end 323.8754 -11.2268)
		(stroke
			(width 0.2032)
			(type default)
		)
		(layer "In4.Cu")
	)
	(gr_line
		(start 323.8754 -11.2268)
		(end 323.8754 -9.4742)
		(stroke
			(width 0.2032)
			(type default)
		)
		(layer "In4.Cu")
	)
	(gr_line
		(start 323.8754 -9.4742)
		(end 322.834 -9.4742)
		(stroke
			(width 0.2032)
			(type default)
		)
		(layer "In4.Cu")
	)
	(gr_line
		(start 323.897498 -11.1252)
		(end 323.897498 -9.5758)
		(stroke
			(width 0.762)
			(type default)
		)
		(layer "In4.Cu")
	)
	(gr_line
		(start 323.897498 -11.0998)
		(end 323.897498 -9.6012)
		(stroke
			(width 0.762)
			(type default)
		)
		(layer "In4.Cu")
	)
	(gr_line
		(start 323.897498 -10.9982)
		(end 323.897498 -9.4488)
		(stroke
			(width 0.762)
			(type default)
		)
		(layer "In4.Cu")
	)
	(gr_line
		(start 323.9262 -11.176)
		(end 323.9262 -9.4234)
		(stroke
			(width 0.2032)
			(type default)
		)
		(layer "In4.Cu")
	)
	(gr_line
		(start 323.9262 -9.4234)
		(end 322.7832 -9.4234)
		(stroke
			(width 0.2032)
			(type default)
		)
		(layer "In4.Cu")
	)
	(gr_line
		(start 323.9516 -11.2268)
		(end 323.9516 -9.3726)
		(stroke
			(width 0.2032)
			(type default)
		)
		(layer "In4.Cu")
	)
	(gr_line
		(start 323.9516 -9.3726)
		(end 322.7578 -9.3726)
		(stroke
			(width 0.2032)
			(type default)
		)
		(layer "In4.Cu")
	)
	(gr_line
		(start 324.0024 -11.303)
		(end 324.0024 -9.2964)
		(stroke
			(width 0.1016)
			(type default)
		)
		(layer "In4.Cu")
	)
	(gr_line
		(start 324.0024 -9.2964)
		(end 322.707 -9.2964)
		(stroke
			(width 0.1016)
			(type default)
		)
		(layer "In4.Cu")
	)
	(gr_line
		(start 324.00494 -5.57784)
		(end 322.73494 -5.57784)
		(stroke
			(width 1.016)
			(type default)
		)
		(layer "In4.Cu")
	)
	(gr_line
		(start 324.100698 -11.2268)
		(end 323.85 -11.2268)
		(stroke
			(width 0.254)
			(type default)
		)
		(layer "In4.Cu")
	)
	(gr_line
		(start 324.100698 -9.3726)
		(end 324.100698 -11.2268)
		(stroke
			(width 0.254)
			(type default)
		)
		(layer "In4.Cu")
	)
	(gr_line
		(start 324.126098 -11.3538)
		(end 322.652898 -11.3538)
		(stroke
			(width 0.254)
			(type default)
		)
		(layer "In4.Cu")
	)
	(gr_line
		(start 324.126098 -9.2456)
		(end 324.126098 -11.3538)
		(stroke
			(width 0.254)
			(type default)
		)
		(layer "In4.Cu")
	)
	(gr_line
		(start 324.151498 -11.3792)
		(end 322.602098 -11.3792)
		(stroke
			(width 0.254)
			(type default)
		)
		(layer "In4.Cu")
	)
	(gr_line
		(start 324.151498 -9.1948)
		(end 324.151498 -11.3792)
		(stroke
			(width 0.254)
			(type default)
		)
		(layer "In4.Cu")
	)
	(gr_line
		(start 327.37679 -11.3792)
		(end 327.37679 -9.1948)
		(stroke
			(width 0.254)
			(type default)
		)
		(layer "In4.Cu")
	)
	(gr_line
		(start 327.37679 -9.1948)
		(end 328.95159 -9.1948)
		(stroke
			(width 0.254)
			(type default)
		)
		(layer "In4.Cu")
	)
	(gr_line
		(start 327.40219 -11.3792)
		(end 327.40219 -9.2456)
		(stroke
			(width 0.254)
			(type default)
		)
		(layer "In4.Cu")
	)
	(gr_line
		(start 327.40219 -9.2456)
		(end 328.92619 -9.2456)
		(stroke
			(width 0.254)
			(type default)
		)
		(layer "In4.Cu")
	)
	(gr_line
		(start 327.45299 -11.3538)
		(end 327.45299 -9.3726)
		(stroke
			(width 0.254)
			(type default)
		)
		(layer "In4.Cu")
	)
	(gr_line
		(start 327.45299 -9.3726)
		(end 328.90079 -9.3726)
		(stroke
			(width 0.254)
			(type default)
		)
		(layer "In4.Cu")
	)
	(gr_line
		(start 327.507092 -11.303)
		(end 327.811892 -11.303)
		(stroke
			(width 0.1016)
			(type default)
		)
		(layer "In4.Cu")
	)
	(gr_line
		(start 327.507092 -9.2964)
		(end 327.507092 -11.303)
		(stroke
			(width 0.1016)
			(type default)
		)
		(layer "In4.Cu")
	)
	(gr_line
		(start 327.557892 -11.2268)
		(end 328.650092 -11.2268)
		(stroke
			(width 0.2032)
			(type default)
		)
		(layer "In4.Cu")
	)
	(gr_line
		(start 327.557892 -9.3726)
		(end 327.557892 -11.2268)
		(stroke
			(width 0.2032)
			(type default)
		)
		(layer "In4.Cu")
	)
	(gr_line
		(start 327.583292 -11.2268)
		(end 328.751692 -11.2268)
		(stroke
			(width 0.2032)
			(type default)
		)
		(layer "In4.Cu")
	)
	(gr_line
		(start 327.583292 -9.4234)
		(end 327.583292 -11.2268)
		(stroke
			(width 0.2032)
			(type default)
		)
		(layer "In4.Cu")
	)
	(gr_line
		(start 327.63079 -11.1252)
		(end 327.63079 -9.5758)
		(stroke
			(width 0.762)
			(type default)
		)
		(layer "In4.Cu")
	)
	(gr_line
		(start 327.63079 -11.1252)
		(end 328.54519 -11.1252)
		(stroke
			(width 0.762)
			(type default)
		)
		(layer "In4.Cu")
	)
	(gr_line
		(start 327.63079 -11.0998)
		(end 327.63079 -9.5504)
		(stroke
			(width 0.762)
			(type default)
		)
		(layer "In4.Cu")
	)
	(gr_line
		(start 327.63079 -10.9982)
		(end 327.63079 -9.4488)
		(stroke
			(width 0.762)
			(type default)
		)
		(layer "In4.Cu")
	)
	(gr_line
		(start 327.63079 -9.4488)
		(end 328.54519 -9.4488)
		(stroke
			(width 0.762)
			(type default)
		)
		(layer "In4.Cu")
	)
	(gr_line
		(start 327.634092 -11.176)
		(end 328.726292 -11.176)
		(stroke
			(width 0.2032)
			(type default)
		)
		(layer "In4.Cu")
	)
	(gr_line
		(start 327.634092 -9.4742)
		(end 327.634092 -11.176)
		(stroke
			(width 0.2032)
			(type default)
		)
		(layer "In4.Cu")
	)
	(gr_line
		(start 327.65619 -10.9982)
		(end 328.57059 -10.9982)
		(stroke
			(width 0.762)
			(type default)
		)
		(layer "In4.Cu")
	)
	(gr_line
		(start 327.65619 -9.5758)
		(end 328.57059 -9.5758)
		(stroke
			(width 0.762)
			(type default)
		)
		(layer "In4.Cu")
	)
	(gr_line
		(start 327.735692 -11.0744)
		(end 328.523092 -11.0744)
		(stroke
			(width 0.508)
			(type default)
		)
		(layer "In4.Cu")
	)
	(gr_line
		(start 327.735692 -11.049)
		(end 327.735692 -9.525)
		(stroke
			(width 0.508)
			(type default)
		)
		(layer "In4.Cu")
	)
	(gr_line
		(start 327.761092 -11.0744)
		(end 327.761092 -9.5504)
		(stroke
			(width 0.508)
			(type default)
		)
		(layer "In4.Cu")
	)
	(gr_line
		(start 327.78319 -11.1252)
		(end 328.69759 -11.1252)
		(stroke
			(width 0.762)
			(type default)
		)
		(layer "In4.Cu")
	)
	(gr_line
		(start 327.78319 -9.4488)
		(end 328.69759 -9.4488)
		(stroke
			(width 0.762)
			(type default)
		)
		(layer "In4.Cu")
	)
	(gr_line
		(start 327.786492 -9.525)
		(end 328.523092 -9.525)
		(stroke
			(width 0.508)
			(type default)
		)
		(layer "In4.Cu")
	)
	(gr_line
		(start 327.811892 -11.303)
		(end 328.802492 -11.303)
		(stroke
			(width 0.1016)
			(type default)
		)
		(layer "In4.Cu")
	)
	(gr_line
		(start 327.811892 -11.0744)
		(end 327.811892 -9.5504)
		(stroke
			(width 0.508)
			(type default)
		)
		(layer "In4.Cu")
	)
	(gr_line
		(start 327.837292 -11.0744)
		(end 327.837292 -9.5504)
		(stroke
			(width 0.508)
			(type default)
		)
		(layer "In4.Cu")
	)
	(gr_line
		(start 327.862692 -11.0744)
		(end 327.862692 -9.5504)
		(stroke
			(width 0.508)
			(type default)
		)
		(layer "In4.Cu")
	)
	(gr_line
		(start 327.888092 -11.0744)
		(end 327.888092 -9.5504)
		(stroke
			(width 0.508)
			(type default)
		)
		(layer "In4.Cu")
	)
	(gr_line
		(start 327.888092 -11.049)
		(end 327.888092 -9.525)
		(stroke
			(width 0.508)
			(type default)
		)
		(layer "In4.Cu")
	)
	(gr_line
		(start 327.913492 -11.0744)
		(end 327.913492 -9.5504)
		(stroke
			(width 0.508)
			(type default)
		)
		(layer "In4.Cu")
	)
	(gr_line
		(start 327.938892 -11.0744)
		(end 327.938892 -9.5504)
		(stroke
			(width 0.508)
			(type default)
		)
		(layer "In4.Cu")
	)
	(gr_line
		(start 327.989692 -11.0744)
		(end 327.989692 -9.5504)
		(stroke
			(width 0.508)
			(type default)
		)
		(layer "In4.Cu")
	)
	(gr_line
		(start 327.989692 -11.049)
		(end 327.989692 -9.525)
		(stroke
			(width 0.508)
			(type default)
		)
		(layer "In4.Cu")
	)
	(gr_line
		(start 328.015092 -11.0744)
		(end 328.015092 -9.5504)
		(stroke
			(width 0.508)
			(type default)
		)
		(layer "In4.Cu")
	)
	(gr_line
		(start 328.040492 -11.0744)
		(end 328.040492 -9.5504)
		(stroke
			(width 0.508)
			(type default)
		)
		(layer "In4.Cu")
	)
	(gr_line
		(start 328.065892 -11.0744)
		(end 328.065892 -9.5504)
		(stroke
			(width 0.508)
			(type default)
		)
		(layer "In4.Cu")
	)
	(gr_line
		(start 328.116692 -11.0744)
		(end 328.116692 -9.5504)
		(stroke
			(width 0.508)
			(type default)
		)
		(layer "In4.Cu")
	)
	(gr_line
		(start 328.142092 -11.0744)
		(end 328.142092 -9.5504)
		(stroke
			(width 0.508)
			(type default)
		)
		(layer "In4.Cu")
	)
	(gr_line
		(start 328.142092 -11.049)
		(end 328.142092 -9.525)
		(stroke
			(width 0.508)
			(type default)
		)
		(layer "In4.Cu")
	)
	(gr_line
		(start 328.167492 -11.0744)
		(end 328.167492 -9.5504)
		(stroke
			(width 0.508)
			(type default)
		)
		(layer "In4.Cu")
	)
	(gr_line
		(start 328.192892 -11.0744)
		(end 328.192892 -9.5504)
		(stroke
			(width 0.508)
			(type default)
		)
		(layer "In4.Cu")
	)
	(gr_line
		(start 328.218292 -11.0744)
		(end 328.218292 -9.5504)
		(stroke
			(width 0.508)
			(type default)
		)
		(layer "In4.Cu")
	)
	(gr_line
		(start 328.218292 -11.049)
		(end 328.218292 -9.525)
		(stroke
			(width 0.508)
			(type default)
		)
		(layer "In4.Cu")
	)
	(gr_line
		(start 328.243692 -11.0744)
		(end 328.243692 -9.5504)
		(stroke
			(width 0.508)
			(type default)
		)
		(layer "In4.Cu")
	)
	(gr_line
		(start 328.269092 -11.0744)
		(end 328.269092 -9.5504)
		(stroke
			(width 0.508)
			(type default)
		)
		(layer "In4.Cu")
	)
	(gr_line
		(start 328.269092 -11.049)
		(end 328.269092 -9.525)
		(stroke
			(width 0.508)
			(type default)
		)
		(layer "In4.Cu")
	)
	(gr_line
		(start 328.294492 -11.0744)
		(end 328.294492 -9.5504)
		(stroke
			(width 0.508)
			(type default)
		)
		(layer "In4.Cu")
	)
	(gr_line
		(start 328.294492 -11.049)
		(end 328.294492 -9.525)
		(stroke
			(width 0.508)
			(type default)
		)
		(layer "In4.Cu")
	)
	(gr_line
		(start 328.319892 -11.049)
		(end 328.319892 -9.525)
		(stroke
			(width 0.508)
			(type default)
		)
		(layer "In4.Cu")
	)
	(gr_line
		(start 328.345292 -11.0744)
		(end 328.345292 -9.5504)
		(stroke
			(width 0.508)
			(type default)
		)
		(layer "In4.Cu")
	)
	(gr_line
		(start 328.36739 -11.3792)
		(end 327.37679 -11.3792)
		(stroke
			(width 0.254)
			(type default)
		)
		(layer "In4.Cu")
	)
	(gr_line
		(start 328.370692 -11.049)
		(end 328.370692 -9.525)
		(stroke
			(width 0.508)
			(type default)
		)
		(layer "In4.Cu")
	)
	(gr_line
		(start 328.396092 -11.049)
		(end 328.396092 -9.525)
		(stroke
			(width 0.508)
			(type default)
		)
		(layer "In4.Cu")
	)
	(gr_line
		(start 328.421492 -11.0744)
		(end 328.421492 -9.5504)
		(stroke
			(width 0.508)
			(type default)
		)
		(layer "In4.Cu")
	)
	(gr_line
		(start 328.446892 -11.0744)
		(end 328.446892 -9.5504)
		(stroke
			(width 0.508)
			(type default)
		)
		(layer "In4.Cu")
	)
	(gr_line
		(start 328.446892 -11.049)
		(end 328.446892 -9.525)
		(stroke
			(width 0.508)
			(type default)
		)
		(layer "In4.Cu")
	)
	(gr_line
		(start 328.497692 -11.0744)
		(end 328.497692 -9.5504)
		(stroke
			(width 0.508)
			(type default)
		)
		(layer "In4.Cu")
	)
	(gr_line
		(start 328.497692 -11.049)
		(end 328.497692 -9.525)
		(stroke
			(width 0.508)
			(type default)
		)
		(layer "In4.Cu")
	)
	(gr_line
		(start 328.548492 -11.0744)
		(end 328.548492 -9.5504)
		(stroke
			(width 0.508)
			(type default)
		)
		(layer "In4.Cu")
	)
	(gr_line
		(start 328.548492 -11.049)
		(end 328.548492 -9.525)
		(stroke
			(width 0.508)
			(type default)
		)
		(layer "In4.Cu")
	)
	(gr_line
		(start 328.57059 -11.0998)
		(end 328.57059 -9.5504)
		(stroke
			(width 0.762)
			(type default)
		)
		(layer "In4.Cu")
	)
	(gr_line
		(start 328.573892 -11.0744)
		(end 328.573892 -9.5504)
		(stroke
			(width 0.508)
			(type default)
		)
		(layer "In4.Cu")
	)
	(gr_line
		(start 328.599292 -11.0744)
		(end 328.599292 -9.5504)
		(stroke
			(width 0.508)
			(type default)
		)
		(layer "In4.Cu")
	)
	(gr_line
		(start 328.650092 -11.2268)
		(end 328.675492 -11.2268)
		(stroke
			(width 0.2032)
			(type default)
		)
		(layer "In4.Cu")
	)
	(gr_line
		(start 328.675492 -11.2268)
		(end 328.675492 -9.4742)
		(stroke
			(width 0.2032)
			(type default)
		)
		(layer "In4.Cu")
	)
	(gr_line
		(start 328.675492 -9.4742)
		(end 327.634092 -9.4742)
		(stroke
			(width 0.2032)
			(type default)
		)
		(layer "In4.Cu")
	)
	(gr_line
		(start 328.69759 -11.1252)
		(end 328.69759 -9.5758)
		(stroke
			(width 0.762)
			(type default)
		)
		(layer "In4.Cu")
	)
	(gr_line
		(start 328.69759 -11.0998)
		(end 328.69759 -9.6012)
		(stroke
			(width 0.762)
			(type default)
		)
		(layer "In4.Cu")
	)
	(gr_line
		(start 328.69759 -10.9982)
		(end 328.69759 -9.4488)
		(stroke
			(width 0.762)
			(type default)
		)
		(layer "In4.Cu")
	)
	(gr_line
		(start 328.726292 -11.176)
		(end 328.726292 -9.4234)
		(stroke
			(width 0.2032)
			(type default)
		)
		(layer "In4.Cu")
	)
	(gr_line
		(start 328.726292 -9.4234)
		(end 327.583292 -9.4234)
		(stroke
			(width 0.2032)
			(type default)
		)
		(layer "In4.Cu")
	)
	(gr_line
		(start 328.751692 -11.2268)
		(end 328.751692 -9.3726)
		(stroke
			(width 0.2032)
			(type default)
		)
		(layer "In4.Cu")
	)
	(gr_line
		(start 328.751692 -9.3726)
		(end 327.557892 -9.3726)
		(stroke
			(width 0.2032)
			(type default)
		)
		(layer "In4.Cu")
	)
	(gr_line
		(start 328.802492 -11.303)
		(end 328.802492 -9.2964)
		(stroke
			(width 0.1016)
			(type default)
		)
		(layer "In4.Cu")
	)
	(gr_line
		(start 328.802492 -9.2964)
		(end 327.507092 -9.2964)
		(stroke
			(width 0.1016)
			(type default)
		)
		(layer "In4.Cu")
	)
	(gr_line
		(start 328.90079 -11.2268)
		(end 328.650092 -11.2268)
		(stroke
			(width 0.254)
			(type default)
		)
		(layer "In4.Cu")
	)
	(gr_line
		(start 328.90079 -9.3726)
		(end 328.90079 -11.2268)
		(stroke
			(width 0.254)
			(type default)
		)
		(layer "In4.Cu")
	)
	(gr_line
		(start 328.92619 -11.3538)
		(end 327.45299 -11.3538)
		(stroke
			(width 0.254)
			(type default)
		)
		(layer "In4.Cu")
	)
	(gr_line
		(start 328.92619 -9.2456)
		(end 328.92619 -11.3538)
		(stroke
			(width 0.254)
			(type default)
		)
		(layer "In4.Cu")
	)
	(gr_line
		(start 328.95159 -11.3792)
		(end 327.40219 -11.3792)
		(stroke
			(width 0.254)
			(type default)
		)
		(layer "In4.Cu")
	)
	(gr_line
		(start 328.95159 -9.1948)
		(end 328.95159 -11.3792)
		(stroke
			(width 0.254)
			(type default)
		)
		(layer "In4.Cu")
	)
	(gr_line
		(start 333.069946 -49.800002)
		(end 318.069976 -49.800002)
		(stroke
			(width 2.032)
			(type default)
		)
		(layer "In4.Cu")
	)
	(gr_line
		(start 334.069944 -51.319938)
		(end 334.069944 -50.8)
		(stroke
			(width 2.032)
			(type default)
		)
		(layer "In4.Cu")
	)
	(gr_arc
		(start 334.069944 -51.319938)
		(mid 334.362853 -52.027004)
		(end 335.069942 -52.319936)
		(stroke
			(width 2.032)
			(type default)
		)
		(layer "In4.Cu")
	)
	(gr_arc
		(start 334.069944 -50.8)
		(mid 333.777051 -50.092895)
		(end 333.069946 -49.800002)
		(stroke
			(width 2.032)
			(type default)
		)
		(layer "In4.Cu")
	)
	(gr_line
		(start 334.761586 -9.1948)
		(end 336.183986 -9.1948)
		(stroke
			(width 1.016)
			(type default)
		)
		(layer "In4.Cu")
	)
	(gr_line
		(start 338.856066 -13.843)
		(end 339.694266 -13.843)
		(stroke
			(width 0.1016)
			(type default)
		)
		(layer "In4.Cu")
	)
	(gr_line
		(start 338.856066 -11.1252)
		(end 338.856066 -13.843)
		(stroke
			(width 0.1016)
			(type default)
		)
		(layer "In4.Cu")
	)
	(gr_line
		(start 338.856066 -9.64311)
		(end 339.694266 -9.64311)
		(stroke
			(width 0.1016)
			(type default)
		)
		(layer "In4.Cu")
	)
	(gr_line
		(start 338.856066 -6.92531)
		(end 338.856066 -9.64311)
		(stroke
			(width 0.1016)
			(type default)
		)
		(layer "In4.Cu")
	)
	(gr_line
		(start 338.881466 -13.8176)
		(end 338.881466 -11.1506)
		(stroke
			(width 0.127)
			(type default)
		)
		(layer "In4.Cu")
	)
	(gr_line
		(start 338.881466 -11.1506)
		(end 340.176866 -11.1506)
		(stroke
			(width 0.127)
			(type default)
		)
		(layer "In4.Cu")
	)
	(gr_line
		(start 338.881466 -9.61771)
		(end 338.881466 -6.95071)
		(stroke
			(width 0.127)
			(type default)
		)
		(layer "In4.Cu")
	)
	(gr_line
		(start 338.881466 -6.95071)
		(end 340.176866 -6.95071)
		(stroke
			(width 0.127)
			(type default)
		)
		(layer "In4.Cu")
	)
	(gr_line
		(start 338.906866 -13.8176)
		(end 338.906866 -11.176)
		(stroke
			(width 0.127)
			(type default)
		)
		(layer "In4.Cu")
	)
	(gr_line
		(start 338.906866 -13.7922)
		(end 338.906866 -11.176)
		(stroke
			(width 0.1778)
			(type default)
		)
		(layer "In4.Cu")
	)
	(gr_line
		(start 338.906866 -11.176)
		(end 340.151466 -11.176)
		(stroke
			(width 0.127)
			(type default)
		)
		(layer "In4.Cu")
	)
	(gr_line
		(start 338.906866 -11.176)
		(end 340.151466 -11.176)
		(stroke
			(width 0.1778)
			(type default)
		)
		(layer "In4.Cu")
	)
	(gr_line
		(start 338.906866 -9.61771)
		(end 338.906866 -6.97611)
		(stroke
			(width 0.127)
			(type default)
		)
		(layer "In4.Cu")
	)
	(gr_line
		(start 338.906866 -9.59231)
		(end 338.906866 -6.97611)
		(stroke
			(width 0.1778)
			(type default)
		)
		(layer "In4.Cu")
	)
	(gr_line
		(start 338.906866 -6.97611)
		(end 340.151466 -6.97611)
		(stroke
			(width 0.127)
			(type default)
		)
		(layer "In4.Cu")
	)
	(gr_line
		(start 338.906866 -6.97611)
		(end 340.151466 -6.97611)
		(stroke
			(width 0.1778)
			(type default)
		)
		(layer "In4.Cu")
	)
	(gr_line
		(start 338.932266 -13.7922)
		(end 338.932266 -11.2014)
		(stroke
			(width 0.1778)
			(type default)
		)
		(layer "In4.Cu")
	)
	(gr_line
		(start 338.932266 -11.2014)
		(end 340.126066 -11.2014)
		(stroke
			(width 0.1778)
			(type default)
		)
		(layer "In4.Cu")
	)
	(gr_line
		(start 338.932266 -9.59231)
		(end 338.932266 -7.00151)
		(stroke
			(width 0.1778)
			(type default)
		)
		(layer "In4.Cu")
	)
	(gr_line
		(start 338.932266 -7.00151)
		(end 340.126066 -7.00151)
		(stroke
			(width 0.1778)
			(type default)
		)
		(layer "In4.Cu")
	)
	(gr_line
		(start 338.957666 -13.7668)
		(end 338.957666 -11.2268)
		(stroke
			(width 0.254)
			(type default)
		)
		(layer "In4.Cu")
	)
	(gr_line
		(start 338.957666 -11.2268)
		(end 340.126066 -11.2268)
		(stroke
			(width 0.254)
			(type default)
		)
		(layer "In4.Cu")
	)
	(gr_line
		(start 338.957666 -9.56691)
		(end 338.957666 -7.02691)
		(stroke
			(width 0.254)
			(type default)
		)
		(layer "In4.Cu")
	)
	(gr_line
		(start 338.957666 -7.02691)
		(end 340.126066 -7.02691)
		(stroke
			(width 0.254)
			(type default)
		)
		(layer "In4.Cu")
	)
	(gr_line
		(start 338.983066 -13.7668)
		(end 338.983066 -11.2522)
		(stroke
			(width 0.254)
			(type default)
		)
		(layer "In4.Cu")
	)
	(gr_line
		(start 338.983066 -11.2522)
		(end 340.100666 -11.2522)
		(stroke
			(width 0.254)
			(type default)
		)
		(layer "In4.Cu")
	)
	(gr_line
		(start 338.983066 -9.56691)
		(end 338.983066 -7.05231)
		(stroke
			(width 0.254)
			(type default)
		)
		(layer "In4.Cu")
	)
	(gr_line
		(start 338.983066 -7.05231)
		(end 340.100666 -7.05231)
		(stroke
			(width 0.254)
			(type default)
		)
		(layer "In4.Cu")
	)
	(gr_line
		(start 339.008466 -13.716)
		(end 339.008466 -11.2776)
		(stroke
			(width 0.3556)
			(type default)
		)
		(layer "In4.Cu")
	)
	(gr_line
		(start 339.008466 -11.2776)
		(end 340.049866 -11.2776)
		(stroke
			(width 0.3556)
			(type default)
		)
		(layer "In4.Cu")
	)
	(gr_line
		(start 339.008466 -9.51611)
		(end 339.008466 -7.07771)
		(stroke
			(width 0.3556)
			(type default)
		)
		(layer "In4.Cu")
	)
	(gr_line
		(start 339.008466 -7.07771)
		(end 340.049866 -7.07771)
		(stroke
			(width 0.3556)
			(type default)
		)
		(layer "In4.Cu")
	)
	(gr_line
		(start 339.059266 -13.6906)
		(end 339.059266 -11.3284)
		(stroke
			(width 0.381)
			(type default)
		)
		(layer "In4.Cu")
	)
	(gr_line
		(start 339.059266 -11.3284)
		(end 339.999066 -11.3284)
		(stroke
			(width 0.381)
			(type default)
		)
		(layer "In4.Cu")
	)
	(gr_line
		(start 339.059266 -9.49071)
		(end 339.059266 -7.12851)
		(stroke
			(width 0.381)
			(type default)
		)
		(layer "In4.Cu")
	)
	(gr_line
		(start 339.059266 -7.12851)
		(end 339.999066 -7.12851)
		(stroke
			(width 0.381)
			(type default)
		)
		(layer "In4.Cu")
	)
	(gr_line
		(start 339.135466 -13.6398)
		(end 339.135466 -11.3792)
		(stroke
			(width 0.381)
			(type default)
		)
		(layer "In4.Cu")
	)
	(gr_line
		(start 339.135466 -11.3792)
		(end 339.948266 -11.3792)
		(stroke
			(width 0.381)
			(type default)
		)
		(layer "In4.Cu")
	)
	(gr_line
		(start 339.135466 -9.43991)
		(end 339.135466 -7.17931)
		(stroke
			(width 0.381)
			(type default)
		)
		(layer "In4.Cu")
	)
	(gr_line
		(start 339.135466 -7.17931)
		(end 339.948266 -7.17931)
		(stroke
			(width 0.381)
			(type default)
		)
		(layer "In4.Cu")
	)
	(gr_line
		(start 339.160866 -13.5636)
		(end 339.160866 -11.3792)
		(stroke
			(width 0.508)
			(type default)
		)
		(layer "In4.Cu")
	)
	(gr_line
		(start 339.160866 -11.3792)
		(end 339.922866 -11.3792)
		(stroke
			(width 0.508)
			(type default)
		)
		(layer "In4.Cu")
	)
	(gr_line
		(start 339.160866 -9.36371)
		(end 339.160866 -7.17931)
		(stroke
			(width 0.508)
			(type default)
		)
		(layer "In4.Cu")
	)
	(gr_line
		(start 339.160866 -7.17931)
		(end 339.922866 -7.17931)
		(stroke
			(width 0.508)
			(type default)
		)
		(layer "In4.Cu")
	)
	(gr_line
		(start 339.186266 -13.4112)
		(end 339.770466 -13.4112)
		(stroke
			(width 0.762)
			(type default)
		)
		(layer "In4.Cu")
	)
	(gr_line
		(start 339.186266 -11.5824)
		(end 339.770466 -11.5824)
		(stroke
			(width 0.762)
			(type default)
		)
		(layer "In4.Cu")
	)
	(gr_line
		(start 339.186266 -9.21131)
		(end 339.770466 -9.21131)
		(stroke
			(width 0.762)
			(type default)
		)
		(layer "In4.Cu")
	)
	(gr_line
		(start 339.186266 -7.38251)
		(end 339.770466 -7.38251)
		(stroke
			(width 0.762)
			(type default)
		)
		(layer "In4.Cu")
	)
	(gr_line
		(start 339.211666 -13.5636)
		(end 339.211666 -11.43)
		(stroke
			(width 0.635)
			(type default)
		)
		(layer "In4.Cu")
	)
	(gr_line
		(start 339.211666 -13.5128)
		(end 339.211666 -11.4808)
		(stroke
			(width 0.762)
			(type default)
		)
		(layer "In4.Cu")
	)
	(gr_line
		(start 339.211666 -11.43)
		(end 339.897466 -11.43)
		(stroke
			(width 0.635)
			(type default)
		)
		(layer "In4.Cu")
	)
	(gr_line
		(start 339.211666 -9.36371)
		(end 339.211666 -7.23011)
		(stroke
			(width 0.635)
			(type default)
		)
		(layer "In4.Cu")
	)
	(gr_line
		(start 339.211666 -9.31291)
		(end 339.211666 -7.28091)
		(stroke
			(width 0.762)
			(type default)
		)
		(layer "In4.Cu")
	)
	(gr_line
		(start 339.211666 -7.23011)
		(end 339.897466 -7.23011)
		(stroke
			(width 0.635)
			(type default)
		)
		(layer "In4.Cu")
	)
	(gr_line
		(start 339.237066 -13.5128)
		(end 339.237066 -11.4808)
		(stroke
			(width 0.762)
			(type default)
		)
		(layer "In4.Cu")
	)
	(gr_line
		(start 339.237066 -11.4808)
		(end 339.821266 -11.4808)
		(stroke
			(width 0.762)
			(type default)
		)
		(layer "In4.Cu")
	)
	(gr_line
		(start 339.237066 -9.31291)
		(end 339.237066 -7.28091)
		(stroke
			(width 0.762)
			(type default)
		)
		(layer "In4.Cu")
	)
	(gr_line
		(start 339.237066 -7.28091)
		(end 339.821266 -7.28091)
		(stroke
			(width 0.762)
			(type default)
		)
		(layer "In4.Cu")
	)
	(gr_line
		(start 339.262466 -13.5128)
		(end 339.262466 -11.4808)
		(stroke
			(width 0.762)
			(type default)
		)
		(layer "In4.Cu")
	)
	(gr_line
		(start 339.262466 -13.5128)
		(end 339.846666 -13.5128)
		(stroke
			(width 0.762)
			(type default)
		)
		(layer "In4.Cu")
	)
	(gr_line
		(start 339.262466 -13.4874)
		(end 339.262466 -11.4554)
		(stroke
			(width 0.762)
			(type default)
		)
		(layer "In4.Cu")
	)
	(gr_line
		(start 339.262466 -9.31291)
		(end 339.262466 -7.28091)
		(stroke
			(width 0.762)
			(type default)
		)
		(layer "In4.Cu")
	)
	(gr_line
		(start 339.262466 -9.31291)
		(end 339.846666 -9.31291)
		(stroke
			(width 0.762)
			(type default)
		)
		(layer "In4.Cu")
	)
	(gr_line
		(start 339.262466 -9.28751)
		(end 339.262466 -7.25551)
		(stroke
			(width 0.762)
			(type default)
		)
		(layer "In4.Cu")
	)
	(gr_line
		(start 339.287866 -13.5128)
		(end 339.287866 -11.4808)
		(stroke
			(width 0.762)
			(type default)
		)
		(layer "In4.Cu")
	)
	(gr_line
		(start 339.287866 -9.31291)
		(end 339.287866 -7.28091)
		(stroke
			(width 0.762)
			(type default)
		)
		(layer "In4.Cu")
	)
	(gr_line
		(start 339.313266 -13.5128)
		(end 339.313266 -11.4808)
		(stroke
			(width 0.762)
			(type default)
		)
		(layer "In4.Cu")
	)
	(gr_line
		(start 339.313266 -9.31291)
		(end 339.313266 -7.28091)
		(stroke
			(width 0.762)
			(type default)
		)
		(layer "In4.Cu")
	)
	(gr_line
		(start 339.338666 -13.5128)
		(end 339.338666 -11.4808)
		(stroke
			(width 0.762)
			(type default)
		)
		(layer "In4.Cu")
	)
	(gr_line
		(start 339.338666 -9.31291)
		(end 339.338666 -7.28091)
		(stroke
			(width 0.762)
			(type default)
		)
		(layer "In4.Cu")
	)
	(gr_line
		(start 339.389466 -13.5128)
		(end 339.389466 -11.4808)
		(stroke
			(width 0.762)
			(type default)
		)
		(layer "In4.Cu")
	)
	(gr_line
		(start 339.389466 -9.31291)
		(end 339.389466 -7.28091)
		(stroke
			(width 0.762)
			(type default)
		)
		(layer "In4.Cu")
	)
	(gr_line
		(start 339.414866 -13.5128)
		(end 339.414866 -11.4808)
		(stroke
			(width 0.762)
			(type default)
		)
		(layer "In4.Cu")
	)
	(gr_line
		(start 339.414866 -9.31291)
		(end 339.414866 -7.28091)
		(stroke
			(width 0.762)
			(type default)
		)
		(layer "In4.Cu")
	)
	(gr_line
		(start 339.440266 -13.5128)
		(end 339.440266 -11.7094)
		(stroke
			(width 0.635)
			(type default)
		)
		(layer "In4.Cu")
	)
	(gr_line
		(start 339.440266 -11.7094)
		(end 339.541866 -11.7094)
		(stroke
			(width 0.635)
			(type default)
		)
		(layer "In4.Cu")
	)
	(gr_line
		(start 339.440266 -9.31291)
		(end 339.440266 -7.50951)
		(stroke
			(width 0.635)
			(type default)
		)
		(layer "In4.Cu")
	)
	(gr_line
		(start 339.440266 -7.50951)
		(end 339.541866 -7.50951)
		(stroke
			(width 0.635)
			(type default)
		)
		(layer "In4.Cu")
	)
	(gr_line
		(start 339.465666 -13.5128)
		(end 339.465666 -11.4808)
		(stroke
			(width 0.762)
			(type default)
		)
		(layer "In4.Cu")
	)
	(gr_line
		(start 339.465666 -13.4874)
		(end 339.465666 -11.4554)
		(stroke
			(width 0.762)
			(type default)
		)
		(layer "In4.Cu")
	)
	(gr_line
		(start 339.465666 -13.4366)
		(end 339.465666 -11.6586)
		(stroke
			(width 0.635)
			(type default)
		)
		(layer "In4.Cu")
	)
	(gr_line
		(start 339.465666 -9.31291)
		(end 339.465666 -7.28091)
		(stroke
			(width 0.762)
			(type default)
		)
		(layer "In4.Cu")
	)
	(gr_line
		(start 339.465666 -9.28751)
		(end 339.465666 -7.25551)
		(stroke
			(width 0.762)
			(type default)
		)
		(layer "In4.Cu")
	)
	(gr_line
		(start 339.465666 -9.23671)
		(end 339.465666 -7.45871)
		(stroke
			(width 0.635)
			(type default)
		)
		(layer "In4.Cu")
	)
	(gr_line
		(start 339.516466 -13.5128)
		(end 339.516466 -11.4808)
		(stroke
			(width 0.762)
			(type default)
		)
		(layer "In4.Cu")
	)
	(gr_line
		(start 339.516466 -9.31291)
		(end 339.516466 -7.28091)
		(stroke
			(width 0.762)
			(type default)
		)
		(layer "In4.Cu")
	)
	(gr_line
		(start 339.541866 -13.5128)
		(end 339.541866 -11.4808)
		(stroke
			(width 0.762)
			(type default)
		)
		(layer "In4.Cu")
	)
	(gr_line
		(start 339.541866 -13.4874)
		(end 339.541866 -11.4554)
		(stroke
			(width 0.762)
			(type default)
		)
		(layer "In4.Cu")
	)
	(gr_line
		(start 339.541866 -13.4366)
		(end 339.465666 -13.4366)
		(stroke
			(width 0.635)
			(type default)
		)
		(layer "In4.Cu")
	)
	(gr_line
		(start 339.541866 -11.7094)
		(end 339.541866 -13.4366)
		(stroke
			(width 0.635)
			(type default)
		)
		(layer "In4.Cu")
	)
	(gr_line
		(start 339.541866 -9.31291)
		(end 339.541866 -7.28091)
		(stroke
			(width 0.762)
			(type default)
		)
		(layer "In4.Cu")
	)
	(gr_line
		(start 339.541866 -9.28751)
		(end 339.541866 -7.25551)
		(stroke
			(width 0.762)
			(type default)
		)
		(layer "In4.Cu")
	)
	(gr_line
		(start 339.541866 -9.23671)
		(end 339.465666 -9.23671)
		(stroke
			(width 0.635)
			(type default)
		)
		(layer "In4.Cu")
	)
	(gr_line
		(start 339.541866 -7.50951)
		(end 339.541866 -9.23671)
		(stroke
			(width 0.635)
			(type default)
		)
		(layer "In4.Cu")
	)
	(gr_line
		(start 339.592666 -13.4874)
		(end 339.592666 -11.4554)
		(stroke
			(width 0.762)
			(type default)
		)
		(layer "In4.Cu")
	)
	(gr_line
		(start 339.592666 -9.28751)
		(end 339.592666 -7.25551)
		(stroke
			(width 0.762)
			(type default)
		)
		(layer "In4.Cu")
	)
	(gr_line
		(start 339.618066 -13.4874)
		(end 339.618066 -11.4554)
		(stroke
			(width 0.762)
			(type default)
		)
		(layer "In4.Cu")
	)
	(gr_line
		(start 339.618066 -9.28751)
		(end 339.618066 -7.25551)
		(stroke
			(width 0.762)
			(type default)
		)
		(layer "In4.Cu")
	)
	(gr_line
		(start 339.668866 -13.5128)
		(end 339.668866 -11.4808)
		(stroke
			(width 0.762)
			(type default)
		)
		(layer "In4.Cu")
	)
	(gr_line
		(start 339.668866 -9.31291)
		(end 339.668866 -7.28091)
		(stroke
			(width 0.762)
			(type default)
		)
		(layer "In4.Cu")
	)
	(gr_line
		(start 339.694266 -13.843)
		(end 340.202266 -13.843)
		(stroke
			(width 0.1016)
			(type default)
		)
		(layer "In4.Cu")
	)
	(gr_line
		(start 339.694266 -13.4874)
		(end 339.694266 -11.4554)
		(stroke
			(width 0.762)
			(type default)
		)
		(layer "In4.Cu")
	)
	(gr_line
		(start 339.694266 -9.64311)
		(end 340.202266 -9.64311)
		(stroke
			(width 0.1016)
			(type default)
		)
		(layer "In4.Cu")
	)
	(gr_line
		(start 339.694266 -9.28751)
		(end 339.694266 -7.25551)
		(stroke
			(width 0.762)
			(type default)
		)
		(layer "In4.Cu")
	)
	(gr_line
		(start 339.745066 -13.5128)
		(end 339.745066 -11.4808)
		(stroke
			(width 0.762)
			(type default)
		)
		(layer "In4.Cu")
	)
	(gr_line
		(start 339.745066 -13.4874)
		(end 339.745066 -11.4554)
		(stroke
			(width 0.762)
			(type default)
		)
		(layer "In4.Cu")
	)
	(gr_line
		(start 339.745066 -9.31291)
		(end 339.745066 -7.28091)
		(stroke
			(width 0.762)
			(type default)
		)
		(layer "In4.Cu")
	)
	(gr_line
		(start 339.745066 -9.28751)
		(end 339.745066 -7.25551)
		(stroke
			(width 0.762)
			(type default)
		)
		(layer "In4.Cu")
	)
	(gr_line
		(start 339.770466 -13.4874)
		(end 339.770466 -11.4554)
		(stroke
			(width 0.762)
			(type default)
		)
		(layer "In4.Cu")
	)
	(gr_line
		(start 339.770466 -9.28751)
		(end 339.770466 -7.25551)
		(stroke
			(width 0.762)
			(type default)
		)
		(layer "In4.Cu")
	)
	(gr_line
		(start 339.795866 -13.5636)
		(end 339.160866 -13.5636)
		(stroke
			(width 0.508)
			(type default)
		)
		(layer "In4.Cu")
	)
	(gr_line
		(start 339.795866 -13.5636)
		(end 339.211666 -13.5636)
		(stroke
			(width 0.635)
			(type default)
		)
		(layer "In4.Cu")
	)
	(gr_line
		(start 339.795866 -9.36371)
		(end 339.160866 -9.36371)
		(stroke
			(width 0.508)
			(type default)
		)
		(layer "In4.Cu")
	)
	(gr_line
		(start 339.795866 -9.36371)
		(end 339.211666 -9.36371)
		(stroke
			(width 0.635)
			(type default)
		)
		(layer "In4.Cu")
	)
	(gr_line
		(start 339.821266 -13.4874)
		(end 339.821266 -11.4554)
		(stroke
			(width 0.762)
			(type default)
		)
		(layer "In4.Cu")
	)
	(gr_line
		(start 339.821266 -9.28751)
		(end 339.821266 -7.25551)
		(stroke
			(width 0.762)
			(type default)
		)
		(layer "In4.Cu")
	)
	(gr_line
		(start 339.846666 -13.716)
		(end 339.008466 -13.716)
		(stroke
			(width 0.3556)
			(type default)
		)
		(layer "In4.Cu")
	)
	(gr_line
		(start 339.846666 -13.6906)
		(end 339.059266 -13.6906)
		(stroke
			(width 0.381)
			(type default)
		)
		(layer "In4.Cu")
	)
	(gr_line
		(start 339.846666 -9.51611)
		(end 339.008466 -9.51611)
		(stroke
			(width 0.3556)
			(type default)
		)
		(layer "In4.Cu")
	)
	(gr_line
		(start 339.846666 -9.49071)
		(end 339.059266 -9.49071)
		(stroke
			(width 0.381)
			(type default)
		)
		(layer "In4.Cu")
	)
	(gr_line
		(start 339.872066 -13.5128)
		(end 339.872066 -11.4808)
		(stroke
			(width 0.762)
			(type default)
		)
		(layer "In4.Cu")
	)
	(gr_line
		(start 339.872066 -9.31291)
		(end 339.872066 -7.28091)
		(stroke
			(width 0.762)
			(type default)
		)
		(layer "In4.Cu")
	)
	(gr_line
		(start 339.897466 -13.7668)
		(end 338.957666 -13.7668)
		(stroke
			(width 0.254)
			(type default)
		)
		(layer "In4.Cu")
	)
	(gr_line
		(start 339.897466 -13.5128)
		(end 339.440266 -13.5128)
		(stroke
			(width 0.635)
			(type default)
		)
		(layer "In4.Cu")
	)
	(gr_line
		(start 339.897466 -11.43)
		(end 339.897466 -13.5128)
		(stroke
			(width 0.635)
			(type default)
		)
		(layer "In4.Cu")
	)
	(gr_line
		(start 339.897466 -9.56691)
		(end 338.957666 -9.56691)
		(stroke
			(width 0.254)
			(type default)
		)
		(layer "In4.Cu")
	)
	(gr_line
		(start 339.897466 -9.31291)
		(end 339.440266 -9.31291)
		(stroke
			(width 0.635)
			(type default)
		)
		(layer "In4.Cu")
	)
	(gr_line
		(start 339.897466 -7.23011)
		(end 339.897466 -9.31291)
		(stroke
			(width 0.635)
			(type default)
		)
		(layer "In4.Cu")
	)
	(gr_line
		(start 339.922866 -13.7922)
		(end 338.906866 -13.7922)
		(stroke
			(width 0.1778)
			(type default)
		)
		(layer "In4.Cu")
	)
	(gr_line
		(start 339.922866 -13.5636)
		(end 339.795866 -13.5636)
		(stroke
			(width 0.508)
			(type default)
		)
		(layer "In4.Cu")
	)
	(gr_line
		(start 339.922866 -11.3792)
		(end 339.922866 -13.5636)
		(stroke
			(width 0.508)
			(type default)
		)
		(layer "In4.Cu")
	)
	(gr_line
		(start 339.922866 -9.59231)
		(end 338.906866 -9.59231)
		(stroke
			(width 0.1778)
			(type default)
		)
		(layer "In4.Cu")
	)
	(gr_line
		(start 339.922866 -9.36371)
		(end 339.795866 -9.36371)
		(stroke
			(width 0.508)
			(type default)
		)
		(layer "In4.Cu")
	)
	(gr_line
		(start 339.922866 -7.17931)
		(end 339.922866 -9.36371)
		(stroke
			(width 0.508)
			(type default)
		)
		(layer "In4.Cu")
	)
	(gr_line
		(start 339.948266 -13.5636)
		(end 339.795866 -13.5636)
		(stroke
			(width 0.381)
			(type default)
		)
		(layer "In4.Cu")
	)
	(gr_line
		(start 339.948266 -11.3792)
		(end 339.948266 -13.5636)
		(stroke
			(width 0.381)
			(type default)
		)
		(layer "In4.Cu")
	)
	(gr_line
		(start 339.948266 -9.36371)
		(end 339.795866 -9.36371)
		(stroke
			(width 0.381)
			(type default)
		)
		(layer "In4.Cu")
	)
	(gr_line
		(start 339.948266 -7.17931)
		(end 339.948266 -9.36371)
		(stroke
			(width 0.381)
			(type default)
		)
		(layer "In4.Cu")
	)
	(gr_line
		(start 339.999066 -13.6398)
		(end 339.135466 -13.6398)
		(stroke
			(width 0.381)
			(type default)
		)
		(layer "In4.Cu")
	)
	(gr_line
		(start 339.999066 -11.3284)
		(end 339.999066 -13.6398)
		(stroke
			(width 0.381)
			(type default)
		)
		(layer "In4.Cu")
	)
	(gr_line
		(start 339.999066 -9.43991)
		(end 339.135466 -9.43991)
		(stroke
			(width 0.381)
			(type default)
		)
		(layer "In4.Cu")
	)
	(gr_line
		(start 339.999066 -7.12851)
		(end 339.999066 -9.43991)
		(stroke
			(width 0.381)
			(type default)
		)
		(layer "In4.Cu")
	)
	(gr_line
		(start 340.049866 -13.6906)
		(end 339.846666 -13.6906)
		(stroke
			(width 0.3556)
			(type default)
		)
		(layer "In4.Cu")
	)
	(gr_line
		(start 340.049866 -11.2776)
		(end 340.049866 -13.6906)
		(stroke
			(width 0.3556)
			(type default)
		)
		(layer "In4.Cu")
	)
	(gr_line
		(start 340.049866 -9.49071)
		(end 339.846666 -9.49071)
		(stroke
			(width 0.3556)
			(type default)
		)
		(layer "In4.Cu")
	)
	(gr_line
		(start 340.049866 -7.07771)
		(end 340.049866 -9.49071)
		(stroke
			(width 0.3556)
			(type default)
		)
		(layer "In4.Cu")
	)
	(gr_line
		(start 340.075266 -13.8176)
		(end 338.881466 -13.8176)
		(stroke
			(width 0.127)
			(type default)
		)
		(layer "In4.Cu")
	)
	(gr_line
		(start 340.075266 -9.61771)
		(end 338.881466 -9.61771)
		(stroke
			(width 0.127)
			(type default)
		)
		(layer "In4.Cu")
	)
	(gr_line
		(start 340.100666 -13.716)
		(end 339.846666 -13.716)
		(stroke
			(width 0.254)
			(type default)
		)
		(layer "In4.Cu")
	)
	(gr_line
		(start 340.100666 -11.2522)
		(end 340.100666 -13.716)
		(stroke
			(width 0.254)
			(type default)
		)
		(layer "In4.Cu")
	)
	(gr_line
		(start 340.100666 -9.51611)
		(end 339.846666 -9.51611)
		(stroke
			(width 0.254)
			(type default)
		)
		(layer "In4.Cu")
	)
	(gr_line
		(start 340.100666 -7.05231)
		(end 340.100666 -9.51611)
		(stroke
			(width 0.254)
			(type default)
		)
		(layer "In4.Cu")
	)
	(gr_line
		(start 340.126066 -13.7668)
		(end 338.983066 -13.7668)
		(stroke
			(width 0.254)
			(type default)
		)
		(layer "In4.Cu")
	)
	(gr_line
		(start 340.126066 -13.7668)
		(end 339.897466 -13.7668)
		(stroke
			(width 0.1778)
			(type default)
		)
		(layer "In4.Cu")
	)
	(gr_line
		(start 340.126066 -11.2268)
		(end 340.126066 -13.7668)
		(stroke
			(width 0.254)
			(type default)
		)
		(layer "In4.Cu")
	)
	(gr_line
		(start 340.126066 -11.2014)
		(end 340.126066 -13.7668)
		(stroke
			(width 0.1778)
			(type default)
		)
		(layer "In4.Cu")
	)
	(gr_line
		(start 340.126066 -9.56691)
		(end 338.983066 -9.56691)
		(stroke
			(width 0.254)
			(type default)
		)
		(layer "In4.Cu")
	)
	(gr_line
		(start 340.126066 -9.56691)
		(end 339.897466 -9.56691)
		(stroke
			(width 0.1778)
			(type default)
		)
		(layer "In4.Cu")
	)
	(gr_line
		(start 340.126066 -7.02691)
		(end 340.126066 -9.56691)
		(stroke
			(width 0.254)
			(type default)
		)
		(layer "In4.Cu")
	)
	(gr_line
		(start 340.126066 -7.00151)
		(end 340.126066 -9.56691)
		(stroke
			(width 0.1778)
			(type default)
		)
		(layer "In4.Cu")
	)
	(gr_line
		(start 340.151466 -13.7922)
		(end 338.932266 -13.7922)
		(stroke
			(width 0.1778)
			(type default)
		)
		(layer "In4.Cu")
	)
	(gr_line
		(start 340.151466 -13.7922)
		(end 339.922866 -13.7922)
		(stroke
			(width 0.127)
			(type default)
		)
		(layer "In4.Cu")
	)
	(gr_line
		(start 340.151466 -11.176)
		(end 340.151466 -13.7922)
		(stroke
			(width 0.127)
			(type default)
		)
		(layer "In4.Cu")
	)
	(gr_line
		(start 340.151466 -11.176)
		(end 340.151466 -13.7922)
		(stroke
			(width 0.1778)
			(type default)
		)
		(layer "In4.Cu")
	)
	(gr_line
		(start 340.151466 -9.59231)
		(end 338.932266 -9.59231)
		(stroke
			(width 0.1778)
			(type default)
		)
		(layer "In4.Cu")
	)
	(gr_line
		(start 340.151466 -9.59231)
		(end 339.922866 -9.59231)
		(stroke
			(width 0.127)
			(type default)
		)
		(layer "In4.Cu")
	)
	(gr_line
		(start 340.151466 -6.97611)
		(end 340.151466 -9.59231)
		(stroke
			(width 0.127)
			(type default)
		)
		(layer "In4.Cu")
	)
	(gr_line
		(start 340.151466 -6.97611)
		(end 340.151466 -9.59231)
		(stroke
			(width 0.1778)
			(type default)
		)
		(layer "In4.Cu")
	)
	(gr_line
		(start 340.176866 -13.8176)
		(end 338.906866 -13.8176)
		(stroke
			(width 0.127)
			(type default)
		)
		(layer "In4.Cu")
	)
	(gr_line
		(start 340.176866 -11.1506)
		(end 340.176866 -13.8176)
		(stroke
			(width 0.127)
			(type default)
		)
		(layer "In4.Cu")
	)
	(gr_line
		(start 340.176866 -9.61771)
		(end 338.906866 -9.61771)
		(stroke
			(width 0.127)
			(type default)
		)
		(layer "In4.Cu")
	)
	(gr_line
		(start 340.176866 -6.95071)
		(end 340.176866 -9.61771)
		(stroke
			(width 0.127)
			(type default)
		)
		(layer "In4.Cu")
	)
	(gr_line
		(start 340.202266 -13.843)
		(end 340.202266 -11.1252)
		(stroke
			(width 0.1016)
			(type default)
		)
		(layer "In4.Cu")
	)
	(gr_line
		(start 340.202266 -11.1252)
		(end 338.856066 -11.1252)
		(stroke
			(width 0.1016)
			(type default)
		)
		(layer "In4.Cu")
	)
	(gr_line
		(start 340.202266 -9.64311)
		(end 340.202266 -6.92531)
		(stroke
			(width 0.1016)
			(type default)
		)
		(layer "In4.Cu")
	)
	(gr_line
		(start 340.202266 -6.92531)
		(end 338.856066 -6.92531)
		(stroke
			(width 0.1016)
			(type default)
		)
		(layer "In4.Cu")
	)
	(gr_line
		(start 348.856046 -12.543028)
		(end 349.694246 -12.543028)
		(stroke
			(width 0.1016)
			(type default)
		)
		(layer "In4.Cu")
	)
	(gr_line
		(start 348.856046 -9.825228)
		(end 348.856046 -12.543028)
		(stroke
			(width 0.1016)
			(type default)
		)
		(layer "In4.Cu")
	)
	(gr_line
		(start 348.856046 -8.343138)
		(end 349.694246 -8.343138)
		(stroke
			(width 0.1016)
			(type default)
		)
		(layer "In4.Cu")
	)
	(gr_line
		(start 348.856046 -5.625338)
		(end 348.856046 -8.343138)
		(stroke
			(width 0.1016)
			(type default)
		)
		(layer "In4.Cu")
	)
	(gr_line
		(start 348.881446 -12.517628)
		(end 348.881446 -9.850628)
		(stroke
			(width 0.127)
			(type default)
		)
		(layer "In4.Cu")
	)
	(gr_line
		(start 348.881446 -9.850628)
		(end 350.176846 -9.850628)
		(stroke
			(width 0.127)
			(type default)
		)
		(layer "In4.Cu")
	)
	(gr_line
		(start 348.881446 -8.317738)
		(end 348.881446 -5.650738)
		(stroke
			(width 0.127)
			(type default)
		)
		(layer "In4.Cu")
	)
	(gr_line
		(start 348.881446 -5.650738)
		(end 350.176846 -5.650738)
		(stroke
			(width 0.127)
			(type default)
		)
		(layer "In4.Cu")
	)
	(gr_line
		(start 348.906846 -12.517628)
		(end 348.906846 -9.876028)
		(stroke
			(width 0.127)
			(type default)
		)
		(layer "In4.Cu")
	)
	(gr_line
		(start 348.906846 -12.492228)
		(end 348.906846 -9.876028)
		(stroke
			(width 0.1778)
			(type default)
		)
		(layer "In4.Cu")
	)
	(gr_line
		(start 348.906846 -9.876028)
		(end 350.151446 -9.876028)
		(stroke
			(width 0.127)
			(type default)
		)
		(layer "In4.Cu")
	)
	(gr_line
		(start 348.906846 -9.876028)
		(end 350.151446 -9.876028)
		(stroke
			(width 0.1778)
			(type default)
		)
		(layer "In4.Cu")
	)
	(gr_line
		(start 348.906846 -8.317738)
		(end 348.906846 -5.676138)
		(stroke
			(width 0.127)
			(type default)
		)
		(layer "In4.Cu")
	)
	(gr_line
		(start 348.906846 -8.292338)
		(end 348.906846 -5.676138)
		(stroke
			(width 0.1778)
			(type default)
		)
		(layer "In4.Cu")
	)
	(gr_line
		(start 348.906846 -5.676138)
		(end 350.151446 -5.676138)
		(stroke
			(width 0.127)
			(type default)
		)
		(layer "In4.Cu")
	)
	(gr_line
		(start 348.906846 -5.676138)
		(end 350.151446 -5.676138)
		(stroke
			(width 0.1778)
			(type default)
		)
		(layer "In4.Cu")
	)
	(gr_line
		(start 348.932246 -12.492228)
		(end 348.932246 -9.901428)
		(stroke
			(width 0.1778)
			(type default)
		)
		(layer "In4.Cu")
	)
	(gr_line
		(start 348.932246 -9.901428)
		(end 350.126046 -9.901428)
		(stroke
			(width 0.1778)
			(type default)
		)
		(layer "In4.Cu")
	)
	(gr_line
		(start 348.932246 -8.292338)
		(end 348.932246 -5.701538)
		(stroke
			(width 0.1778)
			(type default)
		)
		(layer "In4.Cu")
	)
	(gr_line
		(start 348.932246 -5.701538)
		(end 350.126046 -5.701538)
		(stroke
			(width 0.1778)
			(type default)
		)
		(layer "In4.Cu")
	)
	(gr_line
		(start 348.957646 -12.466828)
		(end 348.957646 -9.926828)
		(stroke
			(width 0.254)
			(type default)
		)
		(layer "In4.Cu")
	)
	(gr_line
		(start 348.957646 -9.926828)
		(end 350.126046 -9.926828)
		(stroke
			(width 0.254)
			(type default)
		)
		(layer "In4.Cu")
	)
	(gr_line
		(start 348.957646 -8.266938)
		(end 348.957646 -5.726938)
		(stroke
			(width 0.254)
			(type default)
		)
		(layer "In4.Cu")
	)
	(gr_line
		(start 348.957646 -5.726938)
		(end 350.126046 -5.726938)
		(stroke
			(width 0.254)
			(type default)
		)
		(layer "In4.Cu")
	)
	(gr_line
		(start 348.983046 -12.466828)
		(end 348.983046 -9.952228)
		(stroke
			(width 0.254)
			(type default)
		)
		(layer "In4.Cu")
	)
	(gr_line
		(start 348.983046 -9.952228)
		(end 350.100646 -9.952228)
		(stroke
			(width 0.254)
			(type default)
		)
		(layer "In4.Cu")
	)
	(gr_line
		(start 348.983046 -8.266938)
		(end 348.983046 -5.752338)
		(stroke
			(width 0.254)
			(type default)
		)
		(layer "In4.Cu")
	)
	(gr_line
		(start 348.983046 -5.752338)
		(end 350.100646 -5.752338)
		(stroke
			(width 0.254)
			(type default)
		)
		(layer "In4.Cu")
	)
	(gr_line
		(start 349.008446 -12.416028)
		(end 349.008446 -9.977628)
		(stroke
			(width 0.3556)
			(type default)
		)
		(layer "In4.Cu")
	)
	(gr_line
		(start 349.008446 -9.977628)
		(end 350.049846 -9.977628)
		(stroke
			(width 0.3556)
			(type default)
		)
		(layer "In4.Cu")
	)
	(gr_line
		(start 349.008446 -8.216138)
		(end 349.008446 -5.777738)
		(stroke
			(width 0.3556)
			(type default)
		)
		(layer "In4.Cu")
	)
	(gr_line
		(start 349.008446 -5.777738)
		(end 350.049846 -5.777738)
		(stroke
			(width 0.3556)
			(type default)
		)
		(layer "In4.Cu")
	)
	(gr_line
		(start 349.059246 -12.390628)
		(end 349.059246 -10.028428)
		(stroke
			(width 0.381)
			(type default)
		)
		(layer "In4.Cu")
	)
	(gr_line
		(start 349.059246 -10.028428)
		(end 349.999046 -10.028428)
		(stroke
			(width 0.381)
			(type default)
		)
		(layer "In4.Cu")
	)
	(gr_line
		(start 349.059246 -8.190738)
		(end 349.059246 -5.828538)
		(stroke
			(width 0.381)
			(type default)
		)
		(layer "In4.Cu")
	)
	(gr_line
		(start 349.059246 -5.828538)
		(end 349.999046 -5.828538)
		(stroke
			(width 0.381)
			(type default)
		)
		(layer "In4.Cu")
	)
	(gr_line
		(start 349.135446 -12.339828)
		(end 349.135446 -10.079228)
		(stroke
			(width 0.381)
			(type default)
		)
		(layer "In4.Cu")
	)
	(gr_line
		(start 349.135446 -10.079228)
		(end 349.948246 -10.079228)
		(stroke
			(width 0.381)
			(type default)
		)
		(layer "In4.Cu")
	)
	(gr_line
		(start 349.135446 -8.139938)
		(end 349.135446 -5.879338)
		(stroke
			(width 0.381)
			(type default)
		)
		(layer "In4.Cu")
	)
	(gr_line
		(start 349.135446 -5.879338)
		(end 349.948246 -5.879338)
		(stroke
			(width 0.381)
			(type default)
		)
		(layer "In4.Cu")
	)
	(gr_line
		(start 349.160846 -12.263628)
		(end 349.160846 -10.079228)
		(stroke
			(width 0.508)
			(type default)
		)
		(layer "In4.Cu")
	)
	(gr_line
		(start 349.160846 -10.079228)
		(end 349.922846 -10.079228)
		(stroke
			(width 0.508)
			(type default)
		)
		(layer "In4.Cu")
	)
	(gr_line
		(start 349.160846 -8.063738)
		(end 349.160846 -5.879338)
		(stroke
			(width 0.508)
			(type default)
		)
		(layer "In4.Cu")
	)
	(gr_line
		(start 349.160846 -5.879338)
		(end 349.922846 -5.879338)
		(stroke
			(width 0.508)
			(type default)
		)
		(layer "In4.Cu")
	)
	(gr_line
		(start 349.186246 -12.111228)
		(end 349.770446 -12.111228)
		(stroke
			(width 0.762)
			(type default)
		)
		(layer "In4.Cu")
	)
	(gr_line
		(start 349.186246 -10.282428)
		(end 349.770446 -10.282428)
		(stroke
			(width 0.762)
			(type default)
		)
		(layer "In4.Cu")
	)
	(gr_line
		(start 349.186246 -7.911338)
		(end 349.770446 -7.911338)
		(stroke
			(width 0.762)
			(type default)
		)
		(layer "In4.Cu")
	)
	(gr_line
		(start 349.186246 -6.082538)
		(end 349.770446 -6.082538)
		(stroke
			(width 0.762)
			(type default)
		)
		(layer "In4.Cu")
	)
	(gr_line
		(start 349.211646 -12.263628)
		(end 349.211646 -10.130028)
		(stroke
			(width 0.635)
			(type default)
		)
		(layer "In4.Cu")
	)
	(gr_line
		(start 349.211646 -12.212828)
		(end 349.211646 -10.180828)
		(stroke
			(width 0.762)
			(type default)
		)
		(layer "In4.Cu")
	)
	(gr_line
		(start 349.211646 -10.130028)
		(end 349.897446 -10.130028)
		(stroke
			(width 0.635)
			(type default)
		)
		(layer "In4.Cu")
	)
	(gr_line
		(start 349.211646 -8.063738)
		(end 349.211646 -5.930138)
		(stroke
			(width 0.635)
			(type default)
		)
		(layer "In4.Cu")
	)
	(gr_line
		(start 349.211646 -8.012938)
		(end 349.211646 -5.980938)
		(stroke
			(width 0.762)
			(type default)
		)
		(layer "In4.Cu")
	)
	(gr_line
		(start 349.211646 -5.930138)
		(end 349.897446 -5.930138)
		(stroke
			(width 0.635)
			(type default)
		)
		(layer "In4.Cu")
	)
	(gr_line
		(start 349.237046 -12.212828)
		(end 349.237046 -10.180828)
		(stroke
			(width 0.762)
			(type default)
		)
		(layer "In4.Cu")
	)
	(gr_line
		(start 349.237046 -10.180828)
		(end 349.821246 -10.180828)
		(stroke
			(width 0.762)
			(type default)
		)
		(layer "In4.Cu")
	)
	(gr_line
		(start 349.237046 -8.012938)
		(end 349.237046 -5.980938)
		(stroke
			(width 0.762)
			(type default)
		)
		(layer "In4.Cu")
	)
	(gr_line
		(start 349.237046 -5.980938)
		(end 349.821246 -5.980938)
		(stroke
			(width 0.762)
			(type default)
		)
		(layer "In4.Cu")
	)
	(gr_line
		(start 349.262446 -12.212828)
		(end 349.262446 -10.180828)
		(stroke
			(width 0.762)
			(type default)
		)
		(layer "In4.Cu")
	)
	(gr_line
		(start 349.262446 -12.212828)
		(end 349.846646 -12.212828)
		(stroke
			(width 0.762)
			(type default)
		)
		(layer "In4.Cu")
	)
	(gr_line
		(start 349.262446 -12.187428)
		(end 349.262446 -10.155428)
		(stroke
			(width 0.762)
			(type default)
		)
		(layer "In4.Cu")
	)
	(gr_line
		(start 349.262446 -8.012938)
		(end 349.262446 -5.980938)
		(stroke
			(width 0.762)
			(type default)
		)
		(layer "In4.Cu")
	)
	(gr_line
		(start 349.262446 -8.012938)
		(end 349.846646 -8.012938)
		(stroke
			(width 0.762)
			(type default)
		)
		(layer "In4.Cu")
	)
	(gr_line
		(start 349.262446 -7.987538)
		(end 349.262446 -5.955538)
		(stroke
			(width 0.762)
			(type default)
		)
		(layer "In4.Cu")
	)
	(gr_line
		(start 349.287846 -12.212828)
		(end 349.287846 -10.180828)
		(stroke
			(width 0.762)
			(type default)
		)
		(layer "In4.Cu")
	)
	(gr_line
		(start 349.287846 -8.012938)
		(end 349.287846 -5.980938)
		(stroke
			(width 0.762)
			(type default)
		)
		(layer "In4.Cu")
	)
	(gr_line
		(start 349.313246 -12.212828)
		(end 349.313246 -10.180828)
		(stroke
			(width 0.762)
			(type default)
		)
		(layer "In4.Cu")
	)
	(gr_line
		(start 349.313246 -8.012938)
		(end 349.313246 -5.980938)
		(stroke
			(width 0.762)
			(type default)
		)
		(layer "In4.Cu")
	)
	(gr_line
		(start 349.338646 -12.212828)
		(end 349.338646 -10.180828)
		(stroke
			(width 0.762)
			(type default)
		)
		(layer "In4.Cu")
	)
	(gr_line
		(start 349.338646 -8.012938)
		(end 349.338646 -5.980938)
		(stroke
			(width 0.762)
			(type default)
		)
		(layer "In4.Cu")
	)
	(gr_line
		(start 349.389446 -12.212828)
		(end 349.389446 -10.180828)
		(stroke
			(width 0.762)
			(type default)
		)
		(layer "In4.Cu")
	)
	(gr_line
		(start 349.389446 -8.012938)
		(end 349.389446 -5.980938)
		(stroke
			(width 0.762)
			(type default)
		)
		(layer "In4.Cu")
	)
	(gr_line
		(start 349.414846 -12.212828)
		(end 349.414846 -10.180828)
		(stroke
			(width 0.762)
			(type default)
		)
		(layer "In4.Cu")
	)
	(gr_line
		(start 349.414846 -8.012938)
		(end 349.414846 -5.980938)
		(stroke
			(width 0.762)
			(type default)
		)
		(layer "In4.Cu")
	)
	(gr_line
		(start 349.440246 -12.212828)
		(end 349.440246 -10.409428)
		(stroke
			(width 0.635)
			(type default)
		)
		(layer "In4.Cu")
	)
	(gr_line
		(start 349.440246 -10.409428)
		(end 349.541846 -10.409428)
		(stroke
			(width 0.635)
			(type default)
		)
		(layer "In4.Cu")
	)
	(gr_line
		(start 349.440246 -8.012938)
		(end 349.440246 -6.209538)
		(stroke
			(width 0.635)
			(type default)
		)
		(layer "In4.Cu")
	)
	(gr_line
		(start 349.440246 -6.209538)
		(end 349.541846 -6.209538)
		(stroke
			(width 0.635)
			(type default)
		)
		(layer "In4.Cu")
	)
	(gr_line
		(start 349.465646 -12.212828)
		(end 349.465646 -10.180828)
		(stroke
			(width 0.762)
			(type default)
		)
		(layer "In4.Cu")
	)
	(gr_line
		(start 349.465646 -12.187428)
		(end 349.465646 -10.155428)
		(stroke
			(width 0.762)
			(type default)
		)
		(layer "In4.Cu")
	)
	(gr_line
		(start 349.465646 -12.136628)
		(end 349.465646 -10.358628)
		(stroke
			(width 0.635)
			(type default)
		)
		(layer "In4.Cu")
	)
	(gr_line
		(start 349.465646 -8.012938)
		(end 349.465646 -5.980938)
		(stroke
			(width 0.762)
			(type default)
		)
		(layer "In4.Cu")
	)
	(gr_line
		(start 349.465646 -7.987538)
		(end 349.465646 -5.955538)
		(stroke
			(width 0.762)
			(type default)
		)
		(layer "In4.Cu")
	)
	(gr_line
		(start 349.465646 -7.936738)
		(end 349.465646 -6.158738)
		(stroke
			(width 0.635)
			(type default)
		)
		(layer "In4.Cu")
	)
	(gr_line
		(start 349.516446 -12.212828)
		(end 349.516446 -10.180828)
		(stroke
			(width 0.762)
			(type default)
		)
		(layer "In4.Cu")
	)
	(gr_line
		(start 349.516446 -8.012938)
		(end 349.516446 -5.980938)
		(stroke
			(width 0.762)
			(type default)
		)
		(layer "In4.Cu")
	)
	(gr_line
		(start 349.541846 -12.212828)
		(end 349.541846 -10.180828)
		(stroke
			(width 0.762)
			(type default)
		)
		(layer "In4.Cu")
	)
	(gr_line
		(start 349.541846 -12.187428)
		(end 349.541846 -10.155428)
		(stroke
			(width 0.762)
			(type default)
		)
		(layer "In4.Cu")
	)
	(gr_line
		(start 349.541846 -12.136628)
		(end 349.465646 -12.136628)
		(stroke
			(width 0.635)
			(type default)
		)
		(layer "In4.Cu")
	)
	(gr_line
		(start 349.541846 -10.409428)
		(end 349.541846 -12.136628)
		(stroke
			(width 0.635)
			(type default)
		)
		(layer "In4.Cu")
	)
	(gr_line
		(start 349.541846 -8.012938)
		(end 349.541846 -5.980938)
		(stroke
			(width 0.762)
			(type default)
		)
		(layer "In4.Cu")
	)
	(gr_line
		(start 349.541846 -7.987538)
		(end 349.541846 -5.955538)
		(stroke
			(width 0.762)
			(type default)
		)
		(layer "In4.Cu")
	)
	(gr_line
		(start 349.541846 -7.936738)
		(end 349.465646 -7.936738)
		(stroke
			(width 0.635)
			(type default)
		)
		(layer "In4.Cu")
	)
	(gr_line
		(start 349.541846 -6.209538)
		(end 349.541846 -7.936738)
		(stroke
			(width 0.635)
			(type default)
		)
		(layer "In4.Cu")
	)
	(gr_line
		(start 349.592646 -12.187428)
		(end 349.592646 -10.155428)
		(stroke
			(width 0.762)
			(type default)
		)
		(layer "In4.Cu")
	)
	(gr_line
		(start 349.592646 -7.987538)
		(end 349.592646 -5.955538)
		(stroke
			(width 0.762)
			(type default)
		)
		(layer "In4.Cu")
	)
	(gr_line
		(start 349.618046 -12.187428)
		(end 349.618046 -10.155428)
		(stroke
			(width 0.762)
			(type default)
		)
		(layer "In4.Cu")
	)
	(gr_line
		(start 349.618046 -7.987538)
		(end 349.618046 -5.955538)
		(stroke
			(width 0.762)
			(type default)
		)
		(layer "In4.Cu")
	)
	(gr_line
		(start 349.668846 -12.212828)
		(end 349.668846 -10.180828)
		(stroke
			(width 0.762)
			(type default)
		)
		(layer "In4.Cu")
	)
	(gr_line
		(start 349.668846 -8.012938)
		(end 349.668846 -5.980938)
		(stroke
			(width 0.762)
			(type default)
		)
		(layer "In4.Cu")
	)
	(gr_line
		(start 349.694246 -12.543028)
		(end 350.202246 -12.543028)
		(stroke
			(width 0.1016)
			(type default)
		)
		(layer "In4.Cu")
	)
	(gr_line
		(start 349.694246 -12.187428)
		(end 349.694246 -10.155428)
		(stroke
			(width 0.762)
			(type default)
		)
		(layer "In4.Cu")
	)
	(gr_line
		(start 349.694246 -8.343138)
		(end 350.202246 -8.343138)
		(stroke
			(width 0.1016)
			(type default)
		)
		(layer "In4.Cu")
	)
	(gr_line
		(start 349.694246 -7.987538)
		(end 349.694246 -5.955538)
		(stroke
			(width 0.762)
			(type default)
		)
		(layer "In4.Cu")
	)
	(gr_line
		(start 349.745046 -12.212828)
		(end 349.745046 -10.180828)
		(stroke
			(width 0.762)
			(type default)
		)
		(layer "In4.Cu")
	)
	(gr_line
		(start 349.745046 -12.187428)
		(end 349.745046 -10.155428)
		(stroke
			(width 0.762)
			(type default)
		)
		(layer "In4.Cu")
	)
	(gr_line
		(start 349.745046 -8.012938)
		(end 349.745046 -5.980938)
		(stroke
			(width 0.762)
			(type default)
		)
		(layer "In4.Cu")
	)
	(gr_line
		(start 349.745046 -7.987538)
		(end 349.745046 -5.955538)
		(stroke
			(width 0.762)
			(type default)
		)
		(layer "In4.Cu")
	)
	(gr_line
		(start 349.770446 -12.187428)
		(end 349.770446 -10.155428)
		(stroke
			(width 0.762)
			(type default)
		)
		(layer "In4.Cu")
	)
	(gr_line
		(start 349.770446 -7.987538)
		(end 349.770446 -5.955538)
		(stroke
			(width 0.762)
			(type default)
		)
		(layer "In4.Cu")
	)
	(gr_line
		(start 349.795846 -12.263628)
		(end 349.160846 -12.263628)
		(stroke
			(width 0.508)
			(type default)
		)
		(layer "In4.Cu")
	)
	(gr_line
		(start 349.795846 -12.263628)
		(end 349.211646 -12.263628)
		(stroke
			(width 0.635)
			(type default)
		)
		(layer "In4.Cu")
	)
	(gr_line
		(start 349.795846 -8.063738)
		(end 349.160846 -8.063738)
		(stroke
			(width 0.508)
			(type default)
		)
		(layer "In4.Cu")
	)
	(gr_line
		(start 349.795846 -8.063738)
		(end 349.211646 -8.063738)
		(stroke
			(width 0.635)
			(type default)
		)
		(layer "In4.Cu")
	)
	(gr_line
		(start 349.821246 -12.187428)
		(end 349.821246 -10.155428)
		(stroke
			(width 0.762)
			(type default)
		)
		(layer "In4.Cu")
	)
	(gr_line
		(start 349.821246 -7.987538)
		(end 349.821246 -5.955538)
		(stroke
			(width 0.762)
			(type default)
		)
		(layer "In4.Cu")
	)
	(gr_line
		(start 349.846646 -12.416028)
		(end 349.008446 -12.416028)
		(stroke
			(width 0.3556)
			(type default)
		)
		(layer "In4.Cu")
	)
	(gr_line
		(start 349.846646 -12.390628)
		(end 349.059246 -12.390628)
		(stroke
			(width 0.381)
			(type default)
		)
		(layer "In4.Cu")
	)
	(gr_line
		(start 349.846646 -8.216138)
		(end 349.008446 -8.216138)
		(stroke
			(width 0.3556)
			(type default)
		)
		(layer "In4.Cu")
	)
	(gr_line
		(start 349.846646 -8.190738)
		(end 349.059246 -8.190738)
		(stroke
			(width 0.381)
			(type default)
		)
		(layer "In4.Cu")
	)
	(gr_line
		(start 349.872046 -12.212828)
		(end 349.872046 -10.180828)
		(stroke
			(width 0.762)
			(type default)
		)
		(layer "In4.Cu")
	)
	(gr_line
		(start 349.872046 -8.012938)
		(end 349.872046 -5.980938)
		(stroke
			(width 0.762)
			(type default)
		)
		(layer "In4.Cu")
	)
	(gr_line
		(start 349.897446 -12.466828)
		(end 348.957646 -12.466828)
		(stroke
			(width 0.254)
			(type default)
		)
		(layer "In4.Cu")
	)
	(gr_line
		(start 349.897446 -12.212828)
		(end 349.440246 -12.212828)
		(stroke
			(width 0.635)
			(type default)
		)
		(layer "In4.Cu")
	)
	(gr_line
		(start 349.897446 -10.130028)
		(end 349.897446 -12.212828)
		(stroke
			(width 0.635)
			(type default)
		)
		(layer "In4.Cu")
	)
	(gr_line
		(start 349.897446 -8.266938)
		(end 348.957646 -8.266938)
		(stroke
			(width 0.254)
			(type default)
		)
		(layer "In4.Cu")
	)
	(gr_line
		(start 349.897446 -8.012938)
		(end 349.440246 -8.012938)
		(stroke
			(width 0.635)
			(type default)
		)
		(layer "In4.Cu")
	)
	(gr_line
		(start 349.897446 -5.930138)
		(end 349.897446 -8.012938)
		(stroke
			(width 0.635)
			(type default)
		)
		(layer "In4.Cu")
	)
	(gr_line
		(start 349.922846 -12.492228)
		(end 348.906846 -12.492228)
		(stroke
			(width 0.1778)
			(type default)
		)
		(layer "In4.Cu")
	)
	(gr_line
		(start 349.922846 -12.263628)
		(end 349.795846 -12.263628)
		(stroke
			(width 0.508)
			(type default)
		)
		(layer "In4.Cu")
	)
	(gr_line
		(start 349.922846 -10.079228)
		(end 349.922846 -12.263628)
		(stroke
			(width 0.508)
			(type default)
		)
		(layer "In4.Cu")
	)
	(gr_line
		(start 349.922846 -8.292338)
		(end 348.906846 -8.292338)
		(stroke
			(width 0.1778)
			(type default)
		)
		(layer "In4.Cu")
	)
	(gr_line
		(start 349.922846 -8.063738)
		(end 349.795846 -8.063738)
		(stroke
			(width 0.508)
			(type default)
		)
		(layer "In4.Cu")
	)
	(gr_line
		(start 349.922846 -5.879338)
		(end 349.922846 -8.063738)
		(stroke
			(width 0.508)
			(type default)
		)
		(layer "In4.Cu")
	)
	(gr_line
		(start 349.948246 -12.263628)
		(end 349.795846 -12.263628)
		(stroke
			(width 0.381)
			(type default)
		)
		(layer "In4.Cu")
	)
	(gr_line
		(start 349.948246 -10.079228)
		(end 349.948246 -12.263628)
		(stroke
			(width 0.381)
			(type default)
		)
		(layer "In4.Cu")
	)
	(gr_line
		(start 349.948246 -8.063738)
		(end 349.795846 -8.063738)
		(stroke
			(width 0.381)
			(type default)
		)
		(layer "In4.Cu")
	)
	(gr_line
		(start 349.948246 -5.879338)
		(end 349.948246 -8.063738)
		(stroke
			(width 0.381)
			(type default)
		)
		(layer "In4.Cu")
	)
	(gr_line
		(start 349.999046 -12.339828)
		(end 349.135446 -12.339828)
		(stroke
			(width 0.381)
			(type default)
		)
		(layer "In4.Cu")
	)
	(gr_line
		(start 349.999046 -10.028428)
		(end 349.999046 -12.339828)
		(stroke
			(width 0.381)
			(type default)
		)
		(layer "In4.Cu")
	)
	(gr_line
		(start 349.999046 -8.139938)
		(end 349.135446 -8.139938)
		(stroke
			(width 0.381)
			(type default)
		)
		(layer "In4.Cu")
	)
	(gr_line
		(start 349.999046 -5.828538)
		(end 349.999046 -8.139938)
		(stroke
			(width 0.381)
			(type default)
		)
		(layer "In4.Cu")
	)
	(gr_line
		(start 350.049846 -12.390628)
		(end 349.846646 -12.390628)
		(stroke
			(width 0.3556)
			(type default)
		)
		(layer "In4.Cu")
	)
	(gr_line
		(start 350.049846 -9.977628)
		(end 350.049846 -12.390628)
		(stroke
			(width 0.3556)
			(type default)
		)
		(layer "In4.Cu")
	)
	(gr_line
		(start 350.049846 -8.190738)
		(end 349.846646 -8.190738)
		(stroke
			(width 0.3556)
			(type default)
		)
		(layer "In4.Cu")
	)
	(gr_line
		(start 350.049846 -5.777738)
		(end 350.049846 -8.190738)
		(stroke
			(width 0.3556)
			(type default)
		)
		(layer "In4.Cu")
	)
	(gr_line
		(start 350.075246 -12.517628)
		(end 348.881446 -12.517628)
		(stroke
			(width 0.127)
			(type default)
		)
		(layer "In4.Cu")
	)
	(gr_line
		(start 350.075246 -8.317738)
		(end 348.881446 -8.317738)
		(stroke
			(width 0.127)
			(type default)
		)
		(layer "In4.Cu")
	)
	(gr_line
		(start 350.100646 -12.416028)
		(end 349.846646 -12.416028)
		(stroke
			(width 0.254)
			(type default)
		)
		(layer "In4.Cu")
	)
	(gr_line
		(start 350.100646 -9.952228)
		(end 350.100646 -12.416028)
		(stroke
			(width 0.254)
			(type default)
		)
		(layer "In4.Cu")
	)
	(gr_line
		(start 350.100646 -8.216138)
		(end 349.846646 -8.216138)
		(stroke
			(width 0.254)
			(type default)
		)
		(layer "In4.Cu")
	)
	(gr_line
		(start 350.100646 -5.752338)
		(end 350.100646 -8.216138)
		(stroke
			(width 0.254)
			(type default)
		)
		(layer "In4.Cu")
	)
	(gr_line
		(start 350.126046 -12.466828)
		(end 348.983046 -12.466828)
		(stroke
			(width 0.254)
			(type default)
		)
		(layer "In4.Cu")
	)
	(gr_line
		(start 350.126046 -12.466828)
		(end 349.897446 -12.466828)
		(stroke
			(width 0.1778)
			(type default)
		)
		(layer "In4.Cu")
	)
	(gr_line
		(start 350.126046 -9.926828)
		(end 350.126046 -12.466828)
		(stroke
			(width 0.254)
			(type default)
		)
		(layer "In4.Cu")
	)
	(gr_line
		(start 350.126046 -9.901428)
		(end 350.126046 -12.466828)
		(stroke
			(width 0.1778)
			(type default)
		)
		(layer "In4.Cu")
	)
	(gr_line
		(start 350.126046 -8.266938)
		(end 348.983046 -8.266938)
		(stroke
			(width 0.254)
			(type default)
		)
		(layer "In4.Cu")
	)
	(gr_line
		(start 350.126046 -8.266938)
		(end 349.897446 -8.266938)
		(stroke
			(width 0.1778)
			(type default)
		)
		(layer "In4.Cu")
	)
	(gr_line
		(start 350.126046 -5.726938)
		(end 350.126046 -8.266938)
		(stroke
			(width 0.254)
			(type default)
		)
		(layer "In4.Cu")
	)
	(gr_line
		(start 350.126046 -5.701538)
		(end 350.126046 -8.266938)
		(stroke
			(width 0.1778)
			(type default)
		)
		(layer "In4.Cu")
	)
	(gr_line
		(start 350.151446 -12.492228)
		(end 348.932246 -12.492228)
		(stroke
			(width 0.1778)
			(type default)
		)
		(layer "In4.Cu")
	)
	(gr_line
		(start 350.151446 -12.492228)
		(end 349.922846 -12.492228)
		(stroke
			(width 0.127)
			(type default)
		)
		(layer "In4.Cu")
	)
	(gr_line
		(start 350.151446 -9.876028)
		(end 350.151446 -12.492228)
		(stroke
			(width 0.127)
			(type default)
		)
		(layer "In4.Cu")
	)
	(gr_line
		(start 350.151446 -9.876028)
		(end 350.151446 -12.492228)
		(stroke
			(width 0.1778)
			(type default)
		)
		(layer "In4.Cu")
	)
	(gr_line
		(start 350.151446 -8.292338)
		(end 348.932246 -8.292338)
		(stroke
			(width 0.1778)
			(type default)
		)
		(layer "In4.Cu")
	)
	(gr_line
		(start 350.151446 -8.292338)
		(end 349.922846 -8.292338)
		(stroke
			(width 0.127)
			(type default)
		)
		(layer "In4.Cu")
	)
	(gr_line
		(start 350.151446 -5.676138)
		(end 350.151446 -8.292338)
		(stroke
			(width 0.127)
			(type default)
		)
		(layer "In4.Cu")
	)
	(gr_line
		(start 350.151446 -5.676138)
		(end 350.151446 -8.292338)
		(stroke
			(width 0.1778)
			(type default)
		)
		(layer "In4.Cu")
	)
	(gr_line
		(start 350.176846 -12.517628)
		(end 348.906846 -12.517628)
		(stroke
			(width 0.127)
			(type default)
		)
		(layer "In4.Cu")
	)
	(gr_line
		(start 350.176846 -9.850628)
		(end 350.176846 -12.517628)
		(stroke
			(width 0.127)
			(type default)
		)
		(layer "In4.Cu")
	)
	(gr_line
		(start 350.176846 -8.317738)
		(end 348.906846 -8.317738)
		(stroke
			(width 0.127)
			(type default)
		)
		(layer "In4.Cu")
	)
	(gr_line
		(start 350.176846 -5.650738)
		(end 350.176846 -8.317738)
		(stroke
			(width 0.127)
			(type default)
		)
		(layer "In4.Cu")
	)
	(gr_line
		(start 350.202246 -12.543028)
		(end 350.202246 -9.825228)
		(stroke
			(width 0.1016)
			(type default)
		)
		(layer "In4.Cu")
	)
	(gr_line
		(start 350.202246 -9.825228)
		(end 348.856046 -9.825228)
		(stroke
			(width 0.1016)
			(type default)
		)
		(layer "In4.Cu")
	)
	(gr_line
		(start 350.202246 -8.343138)
		(end 350.202246 -5.625338)
		(stroke
			(width 0.1016)
			(type default)
		)
		(layer "In4.Cu")
	)
	(gr_line
		(start 350.202246 -5.625338)
		(end 348.856046 -5.625338)
		(stroke
			(width 0.1016)
			(type default)
		)
		(layer "In4.Cu")
	)
	(gr_line
		(start 353.918266 -5.22732)
		(end 353.918266 -3.95732)
		(stroke
			(width 1.016)
			(type default)
		)
		(layer "In4.Cu")
	)
	(gr_line
		(start 353.989894 -52.319936)
		(end 335.069942 -52.319936)
		(stroke
			(width 2.032)
			(type default)
		)
		(layer "In4.Cu")
	)
	(gr_arc
		(start 353.989894 -52.319936)
		(mid 354.697017 -52.027048)
		(end 354.989892 -51.319938)
		(stroke
			(width 2.032)
			(type default)
		)
		(layer "In4.Cu")
	)
	(gr_line
		(start 354.989892 -50.8)
		(end 354.989892 -51.319938)
		(stroke
			(width 2.032)
			(type default)
		)
		(layer "In4.Cu")
	)
	(gr_arc
		(start 355.98989 -49.800002)
		(mid 355.282785 -50.092895)
		(end 354.989892 -50.8)
		(stroke
			(width 2.032)
			(type default)
		)
		(layer "In4.Cu")
	)
	(gr_line
		(start 360.496866 -11.378946)
		(end 360.496866 -9.194546)
		(stroke
			(width 0.254)
			(type default)
		)
		(layer "In4.Cu")
	)
	(gr_line
		(start 360.496866 -9.194546)
		(end 362.071666 -9.194546)
		(stroke
			(width 0.254)
			(type default)
		)
		(layer "In4.Cu")
	)
	(gr_line
		(start 360.522266 -11.378946)
		(end 360.522266 -9.245346)
		(stroke
			(width 0.254)
			(type default)
		)
		(layer "In4.Cu")
	)
	(gr_line
		(start 360.522266 -9.245346)
		(end 362.046266 -9.245346)
		(stroke
			(width 0.254)
			(type default)
		)
		(layer "In4.Cu")
	)
	(gr_line
		(start 360.573066 -11.353546)
		(end 360.573066 -9.372346)
		(stroke
			(width 0.254)
			(type default)
		)
		(layer "In4.Cu")
	)
	(gr_line
		(start 360.573066 -9.372346)
		(end 362.020866 -9.372346)
		(stroke
			(width 0.254)
			(type default)
		)
		(layer "In4.Cu")
	)
	(gr_line
		(start 360.627168 -11.302746)
		(end 360.931968 -11.302746)
		(stroke
			(width 0.1016)
			(type default)
		)
		(layer "In4.Cu")
	)
	(gr_line
		(start 360.627168 -9.296146)
		(end 360.627168 -11.302746)
		(stroke
			(width 0.1016)
			(type default)
		)
		(layer "In4.Cu")
	)
	(gr_line
		(start 360.677968 -11.226546)
		(end 361.770168 -11.226546)
		(stroke
			(width 0.2032)
			(type default)
		)
		(layer "In4.Cu")
	)
	(gr_line
		(start 360.677968 -9.372346)
		(end 360.677968 -11.226546)
		(stroke
			(width 0.2032)
			(type default)
		)
		(layer "In4.Cu")
	)
	(gr_line
		(start 360.703368 -11.226546)
		(end 361.871768 -11.226546)
		(stroke
			(width 0.2032)
			(type default)
		)
		(layer "In4.Cu")
	)
	(gr_line
		(start 360.703368 -9.423146)
		(end 360.703368 -11.226546)
		(stroke
			(width 0.2032)
			(type default)
		)
		(layer "In4.Cu")
	)
	(gr_line
		(start 360.750866 -11.124946)
		(end 360.750866 -9.575546)
		(stroke
			(width 0.762)
			(type default)
		)
		(layer "In4.Cu")
	)
	(gr_line
		(start 360.750866 -11.124946)
		(end 361.665266 -11.124946)
		(stroke
			(width 0.762)
			(type default)
		)
		(layer "In4.Cu")
	)
	(gr_line
		(start 360.750866 -11.099546)
		(end 360.750866 -9.550146)
		(stroke
			(width 0.762)
			(type default)
		)
		(layer "In4.Cu")
	)
	(gr_line
		(start 360.750866 -10.997946)
		(end 360.750866 -9.448546)
		(stroke
			(width 0.762)
			(type default)
		)
		(layer "In4.Cu")
	)
	(gr_line
		(start 360.750866 -9.448546)
		(end 361.665266 -9.448546)
		(stroke
			(width 0.762)
			(type default)
		)
		(layer "In4.Cu")
	)
	(gr_line
		(start 360.754168 -11.175746)
		(end 361.846368 -11.175746)
		(stroke
			(width 0.2032)
			(type default)
		)
		(layer "In4.Cu")
	)
	(gr_line
		(start 360.754168 -9.473946)
		(end 360.754168 -11.175746)
		(stroke
			(width 0.2032)
			(type default)
		)
		(layer "In4.Cu")
	)
	(gr_line
		(start 360.776266 -10.997946)
		(end 361.690666 -10.997946)
		(stroke
			(width 0.762)
			(type default)
		)
		(layer "In4.Cu")
	)
	(gr_line
		(start 360.776266 -9.575546)
		(end 361.690666 -9.575546)
		(stroke
			(width 0.762)
			(type default)
		)
		(layer "In4.Cu")
	)
	(gr_line
		(start 360.855768 -11.074146)
		(end 361.643168 -11.074146)
		(stroke
			(width 0.508)
			(type default)
		)
		(layer "In4.Cu")
	)
	(gr_line
		(start 360.855768 -11.048746)
		(end 360.855768 -9.524746)
		(stroke
			(width 0.508)
			(type default)
		)
		(layer "In4.Cu")
	)
	(gr_line
		(start 360.881168 -11.074146)
		(end 360.881168 -9.550146)
		(stroke
			(width 0.508)
			(type default)
		)
		(layer "In4.Cu")
	)
	(gr_line
		(start 360.903266 -11.124946)
		(end 361.817666 -11.124946)
		(stroke
			(width 0.762)
			(type default)
		)
		(layer "In4.Cu")
	)
	(gr_line
		(start 360.903266 -9.448546)
		(end 361.817666 -9.448546)
		(stroke
			(width 0.762)
			(type default)
		)
		(layer "In4.Cu")
	)
	(gr_line
		(start 360.906568 -9.524746)
		(end 361.643168 -9.524746)
		(stroke
			(width 0.508)
			(type default)
		)
		(layer "In4.Cu")
	)
	(gr_line
		(start 360.931968 -11.302746)
		(end 361.922568 -11.302746)
		(stroke
			(width 0.1016)
			(type default)
		)
		(layer "In4.Cu")
	)
	(gr_line
		(start 360.931968 -11.074146)
		(end 360.931968 -9.550146)
		(stroke
			(width 0.508)
			(type default)
		)
		(layer "In4.Cu")
	)
	(gr_line
		(start 360.957368 -11.074146)
		(end 360.957368 -9.550146)
		(stroke
			(width 0.508)
			(type default)
		)
		(layer "In4.Cu")
	)
	(gr_line
		(start 360.982768 -11.074146)
		(end 360.982768 -9.550146)
		(stroke
			(width 0.508)
			(type default)
		)
		(layer "In4.Cu")
	)
	(gr_line
		(start 361.008168 -11.074146)
		(end 361.008168 -9.550146)
		(stroke
			(width 0.508)
			(type default)
		)
		(layer "In4.Cu")
	)
	(gr_line
		(start 361.008168 -11.048746)
		(end 361.008168 -9.524746)
		(stroke
			(width 0.508)
			(type default)
		)
		(layer "In4.Cu")
	)
	(gr_line
		(start 361.033568 -11.074146)
		(end 361.033568 -9.550146)
		(stroke
			(width 0.508)
			(type default)
		)
		(layer "In4.Cu")
	)
	(gr_line
		(start 361.058968 -11.074146)
		(end 361.058968 -9.550146)
		(stroke
			(width 0.508)
			(type default)
		)
		(layer "In4.Cu")
	)
	(gr_line
		(start 361.109768 -11.074146)
		(end 361.109768 -9.550146)
		(stroke
			(width 0.508)
			(type default)
		)
		(layer "In4.Cu")
	)
	(gr_line
		(start 361.109768 -11.048746)
		(end 361.109768 -9.524746)
		(stroke
			(width 0.508)
			(type default)
		)
		(layer "In4.Cu")
	)
	(gr_line
		(start 361.135168 -11.074146)
		(end 361.135168 -9.550146)
		(stroke
			(width 0.508)
			(type default)
		)
		(layer "In4.Cu")
	)
	(gr_line
		(start 361.160568 -11.074146)
		(end 361.160568 -9.550146)
		(stroke
			(width 0.508)
			(type default)
		)
		(layer "In4.Cu")
	)
	(gr_line
		(start 361.185968 -11.074146)
		(end 361.185968 -9.550146)
		(stroke
			(width 0.508)
			(type default)
		)
		(layer "In4.Cu")
	)
	(gr_line
		(start 361.236768 -11.074146)
		(end 361.236768 -9.550146)
		(stroke
			(width 0.508)
			(type default)
		)
		(layer "In4.Cu")
	)
	(gr_line
		(start 361.262168 -11.074146)
		(end 361.262168 -9.550146)
		(stroke
			(width 0.508)
			(type default)
		)
		(layer "In4.Cu")
	)
	(gr_line
		(start 361.262168 -11.048746)
		(end 361.262168 -9.524746)
		(stroke
			(width 0.508)
			(type default)
		)
		(layer "In4.Cu")
	)
	(gr_line
		(start 361.287568 -11.074146)
		(end 361.287568 -9.550146)
		(stroke
			(width 0.508)
			(type default)
		)
		(layer "In4.Cu")
	)
	(gr_line
		(start 361.312968 -11.074146)
		(end 361.312968 -9.550146)
		(stroke
			(width 0.508)
			(type default)
		)
		(layer "In4.Cu")
	)
	(gr_line
		(start 361.338368 -11.074146)
		(end 361.338368 -9.550146)
		(stroke
			(width 0.508)
			(type default)
		)
		(layer "In4.Cu")
	)
	(gr_line
		(start 361.338368 -11.048746)
		(end 361.338368 -9.524746)
		(stroke
			(width 0.508)
			(type default)
		)
		(layer "In4.Cu")
	)
	(gr_line
		(start 361.363768 -11.074146)
		(end 361.363768 -9.550146)
		(stroke
			(width 0.508)
			(type default)
		)
		(layer "In4.Cu")
	)
	(gr_line
		(start 361.389168 -11.074146)
		(end 361.389168 -9.550146)
		(stroke
			(width 0.508)
			(type default)
		)
		(layer "In4.Cu")
	)
	(gr_line
		(start 361.389168 -11.048746)
		(end 361.389168 -9.524746)
		(stroke
			(width 0.508)
			(type default)
		)
		(layer "In4.Cu")
	)
	(gr_line
		(start 361.414568 -11.074146)
		(end 361.414568 -9.550146)
		(stroke
			(width 0.508)
			(type default)
		)
		(layer "In4.Cu")
	)
	(gr_line
		(start 361.414568 -11.048746)
		(end 361.414568 -9.524746)
		(stroke
			(width 0.508)
			(type default)
		)
		(layer "In4.Cu")
	)
	(gr_line
		(start 361.439968 -11.048746)
		(end 361.439968 -9.524746)
		(stroke
			(width 0.508)
			(type default)
		)
		(layer "In4.Cu")
	)
	(gr_line
		(start 361.465368 -11.074146)
		(end 361.465368 -9.550146)
		(stroke
			(width 0.508)
			(type default)
		)
		(layer "In4.Cu")
	)
	(gr_line
		(start 361.487466 -11.378946)
		(end 360.496866 -11.378946)
		(stroke
			(width 0.254)
			(type default)
		)
		(layer "In4.Cu")
	)
	(gr_line
		(start 361.490768 -11.048746)
		(end 361.490768 -9.524746)
		(stroke
			(width 0.508)
			(type default)
		)
		(layer "In4.Cu")
	)
	(gr_line
		(start 361.516168 -11.048746)
		(end 361.516168 -9.524746)
		(stroke
			(width 0.508)
			(type default)
		)
		(layer "In4.Cu")
	)
	(gr_line
		(start 361.541568 -11.074146)
		(end 361.541568 -9.550146)
		(stroke
			(width 0.508)
			(type default)
		)
		(layer "In4.Cu")
	)
	(gr_line
		(start 361.566968 -11.074146)
		(end 361.566968 -9.550146)
		(stroke
			(width 0.508)
			(type default)
		)
		(layer "In4.Cu")
	)
	(gr_line
		(start 361.566968 -11.048746)
		(end 361.566968 -9.524746)
		(stroke
			(width 0.508)
			(type default)
		)
		(layer "In4.Cu")
	)
	(gr_line
		(start 361.617768 -11.074146)
		(end 361.617768 -9.550146)
		(stroke
			(width 0.508)
			(type default)
		)
		(layer "In4.Cu")
	)
	(gr_line
		(start 361.617768 -11.048746)
		(end 361.617768 -9.524746)
		(stroke
			(width 0.508)
			(type default)
		)
		(layer "In4.Cu")
	)
	(gr_line
		(start 361.668568 -11.074146)
		(end 361.668568 -9.550146)
		(stroke
			(width 0.508)
			(type default)
		)
		(layer "In4.Cu")
	)
	(gr_line
		(start 361.668568 -11.048746)
		(end 361.668568 -9.524746)
		(stroke
			(width 0.508)
			(type default)
		)
		(layer "In4.Cu")
	)
	(gr_line
		(start 361.690666 -11.099546)
		(end 361.690666 -9.550146)
		(stroke
			(width 0.762)
			(type default)
		)
		(layer "In4.Cu")
	)
	(gr_line
		(start 361.693968 -11.074146)
		(end 361.693968 -9.550146)
		(stroke
			(width 0.508)
			(type default)
		)
		(layer "In4.Cu")
	)
	(gr_line
		(start 361.719368 -11.074146)
		(end 361.719368 -9.550146)
		(stroke
			(width 0.508)
			(type default)
		)
		(layer "In4.Cu")
	)
	(gr_line
		(start 361.770168 -11.226546)
		(end 361.795568 -11.226546)
		(stroke
			(width 0.2032)
			(type default)
		)
		(layer "In4.Cu")
	)
	(gr_line
		(start 361.795568 -11.226546)
		(end 361.795568 -9.473946)
		(stroke
			(width 0.2032)
			(type default)
		)
		(layer "In4.Cu")
	)
	(gr_line
		(start 361.795568 -9.473946)
		(end 360.754168 -9.473946)
		(stroke
			(width 0.2032)
			(type default)
		)
		(layer "In4.Cu")
	)
	(gr_line
		(start 361.817666 -11.124946)
		(end 361.817666 -9.575546)
		(stroke
			(width 0.762)
			(type default)
		)
		(layer "In4.Cu")
	)
	(gr_line
		(start 361.817666 -11.099546)
		(end 361.817666 -9.600946)
		(stroke
			(width 0.762)
			(type default)
		)
		(layer "In4.Cu")
	)
	(gr_line
		(start 361.817666 -10.997946)
		(end 361.817666 -9.448546)
		(stroke
			(width 0.762)
			(type default)
		)
		(layer "In4.Cu")
	)
	(gr_line
		(start 361.846368 -11.175746)
		(end 361.846368 -9.423146)
		(stroke
			(width 0.2032)
			(type default)
		)
		(layer "In4.Cu")
	)
	(gr_line
		(start 361.846368 -9.423146)
		(end 360.703368 -9.423146)
		(stroke
			(width 0.2032)
			(type default)
		)
		(layer "In4.Cu")
	)
	(gr_line
		(start 361.871768 -11.226546)
		(end 361.871768 -9.372346)
		(stroke
			(width 0.2032)
			(type default)
		)
		(layer "In4.Cu")
	)
	(gr_line
		(start 361.871768 -9.372346)
		(end 360.677968 -9.372346)
		(stroke
			(width 0.2032)
			(type default)
		)
		(layer "In4.Cu")
	)
	(gr_line
		(start 361.922568 -11.302746)
		(end 361.922568 -9.296146)
		(stroke
			(width 0.1016)
			(type default)
		)
		(layer "In4.Cu")
	)
	(gr_line
		(start 361.922568 -9.296146)
		(end 360.627168 -9.296146)
		(stroke
			(width 0.1016)
			(type default)
		)
		(layer "In4.Cu")
	)
	(gr_line
		(start 362.020866 -11.226546)
		(end 361.770168 -11.226546)
		(stroke
			(width 0.254)
			(type default)
		)
		(layer "In4.Cu")
	)
	(gr_line
		(start 362.020866 -9.372346)
		(end 362.020866 -11.226546)
		(stroke
			(width 0.254)
			(type default)
		)
		(layer "In4.Cu")
	)
	(gr_line
		(start 362.046266 -11.353546)
		(end 360.573066 -11.353546)
		(stroke
			(width 0.254)
			(type default)
		)
		(layer "In4.Cu")
	)
	(gr_line
		(start 362.046266 -9.245346)
		(end 362.046266 -11.353546)
		(stroke
			(width 0.254)
			(type default)
		)
		(layer "In4.Cu")
	)
	(gr_line
		(start 362.071666 -11.378946)
		(end 360.522266 -11.378946)
		(stroke
			(width 0.254)
			(type default)
		)
		(layer "In4.Cu")
	)
	(gr_line
		(start 362.071666 -9.194546)
		(end 362.071666 -11.378946)
		(stroke
			(width 0.254)
			(type default)
		)
		(layer "In4.Cu")
	)
	(gr_line
		(start 365.296958 -11.378946)
		(end 365.296958 -9.194546)
		(stroke
			(width 0.254)
			(type default)
		)
		(layer "In4.Cu")
	)
	(gr_line
		(start 365.296958 -9.194546)
		(end 366.871758 -9.194546)
		(stroke
			(width 0.254)
			(type default)
		)
		(layer "In4.Cu")
	)
	(gr_line
		(start 365.322358 -11.378946)
		(end 365.322358 -9.245346)
		(stroke
			(width 0.254)
			(type default)
		)
		(layer "In4.Cu")
	)
	(gr_line
		(start 365.322358 -9.245346)
		(end 366.846358 -9.245346)
		(stroke
			(width 0.254)
			(type default)
		)
		(layer "In4.Cu")
	)
	(gr_line
		(start 365.373158 -11.353546)
		(end 365.373158 -9.372346)
		(stroke
			(width 0.254)
			(type default)
		)
		(layer "In4.Cu")
	)
	(gr_line
		(start 365.373158 -9.372346)
		(end 366.820958 -9.372346)
		(stroke
			(width 0.254)
			(type default)
		)
		(layer "In4.Cu")
	)
	(gr_line
		(start 365.42726 -11.302746)
		(end 365.73206 -11.302746)
		(stroke
			(width 0.1016)
			(type default)
		)
		(layer "In4.Cu")
	)
	(gr_line
		(start 365.42726 -9.296146)
		(end 365.42726 -11.302746)
		(stroke
			(width 0.1016)
			(type default)
		)
		(layer "In4.Cu")
	)
	(gr_line
		(start 365.47806 -11.226546)
		(end 366.57026 -11.226546)
		(stroke
			(width 0.2032)
			(type default)
		)
		(layer "In4.Cu")
	)
	(gr_line
		(start 365.47806 -9.372346)
		(end 365.47806 -11.226546)
		(stroke
			(width 0.2032)
			(type default)
		)
		(layer "In4.Cu")
	)
	(gr_line
		(start 365.50346 -11.226546)
		(end 366.67186 -11.226546)
		(stroke
			(width 0.2032)
			(type default)
		)
		(layer "In4.Cu")
	)
	(gr_line
		(start 365.50346 -9.423146)
		(end 365.50346 -11.226546)
		(stroke
			(width 0.2032)
			(type default)
		)
		(layer "In4.Cu")
	)
	(gr_line
		(start 365.550958 -11.124946)
		(end 365.550958 -9.575546)
		(stroke
			(width 0.762)
			(type default)
		)
		(layer "In4.Cu")
	)
	(gr_line
		(start 365.550958 -11.124946)
		(end 366.465358 -11.124946)
		(stroke
			(width 0.762)
			(type default)
		)
		(layer "In4.Cu")
	)
	(gr_line
		(start 365.550958 -11.099546)
		(end 365.550958 -9.550146)
		(stroke
			(width 0.762)
			(type default)
		)
		(layer "In4.Cu")
	)
	(gr_line
		(start 365.550958 -10.997946)
		(end 365.550958 -9.448546)
		(stroke
			(width 0.762)
			(type default)
		)
		(layer "In4.Cu")
	)
	(gr_line
		(start 365.550958 -9.448546)
		(end 366.465358 -9.448546)
		(stroke
			(width 0.762)
			(type default)
		)
		(layer "In4.Cu")
	)
	(gr_line
		(start 365.55426 -11.175746)
		(end 366.64646 -11.175746)
		(stroke
			(width 0.2032)
			(type default)
		)
		(layer "In4.Cu")
	)
	(gr_line
		(start 365.55426 -9.473946)
		(end 365.55426 -11.175746)
		(stroke
			(width 0.2032)
			(type default)
		)
		(layer "In4.Cu")
	)
	(gr_line
		(start 365.576358 -10.997946)
		(end 366.490758 -10.997946)
		(stroke
			(width 0.762)
			(type default)
		)
		(layer "In4.Cu")
	)
	(gr_line
		(start 365.576358 -9.575546)
		(end 366.490758 -9.575546)
		(stroke
			(width 0.762)
			(type default)
		)
		(layer "In4.Cu")
	)
	(gr_line
		(start 365.65586 -11.074146)
		(end 366.44326 -11.074146)
		(stroke
			(width 0.508)
			(type default)
		)
		(layer "In4.Cu")
	)
	(gr_line
		(start 365.65586 -11.048746)
		(end 365.65586 -9.524746)
		(stroke
			(width 0.508)
			(type default)
		)
		(layer "In4.Cu")
	)
	(gr_line
		(start 365.68126 -11.074146)
		(end 365.68126 -9.550146)
		(stroke
			(width 0.508)
			(type default)
		)
		(layer "In4.Cu")
	)
	(gr_line
		(start 365.703358 -11.124946)
		(end 366.617758 -11.124946)
		(stroke
			(width 0.762)
			(type default)
		)
		(layer "In4.Cu")
	)
	(gr_line
		(start 365.703358 -9.448546)
		(end 366.617758 -9.448546)
		(stroke
			(width 0.762)
			(type default)
		)
		(layer "In4.Cu")
	)
	(gr_line
		(start 365.70666 -9.524746)
		(end 366.44326 -9.524746)
		(stroke
			(width 0.508)
			(type default)
		)
		(layer "In4.Cu")
	)
	(gr_line
		(start 365.73206 -11.302746)
		(end 366.72266 -11.302746)
		(stroke
			(width 0.1016)
			(type default)
		)
		(layer "In4.Cu")
	)
	(gr_line
		(start 365.73206 -11.074146)
		(end 365.73206 -9.550146)
		(stroke
			(width 0.508)
			(type default)
		)
		(layer "In4.Cu")
	)
	(gr_line
		(start 365.75746 -11.074146)
		(end 365.75746 -9.550146)
		(stroke
			(width 0.508)
			(type default)
		)
		(layer "In4.Cu")
	)
	(gr_line
		(start 365.78286 -11.074146)
		(end 365.78286 -9.550146)
		(stroke
			(width 0.508)
			(type default)
		)
		(layer "In4.Cu")
	)
	(gr_line
		(start 365.80826 -11.074146)
		(end 365.80826 -9.550146)
		(stroke
			(width 0.508)
			(type default)
		)
		(layer "In4.Cu")
	)
	(gr_line
		(start 365.80826 -11.048746)
		(end 365.80826 -9.524746)
		(stroke
			(width 0.508)
			(type default)
		)
		(layer "In4.Cu")
	)
	(gr_line
		(start 365.83366 -11.074146)
		(end 365.83366 -9.550146)
		(stroke
			(width 0.508)
			(type default)
		)
		(layer "In4.Cu")
	)
	(gr_line
		(start 365.85906 -11.074146)
		(end 365.85906 -9.550146)
		(stroke
			(width 0.508)
			(type default)
		)
		(layer "In4.Cu")
	)
	(gr_line
		(start 365.90986 -11.074146)
		(end 365.90986 -9.550146)
		(stroke
			(width 0.508)
			(type default)
		)
		(layer "In4.Cu")
	)
	(gr_line
		(start 365.90986 -11.048746)
		(end 365.90986 -9.524746)
		(stroke
			(width 0.508)
			(type default)
		)
		(layer "In4.Cu")
	)
	(gr_line
		(start 365.93526 -11.074146)
		(end 365.93526 -9.550146)
		(stroke
			(width 0.508)
			(type default)
		)
		(layer "In4.Cu")
	)
	(gr_line
		(start 365.96066 -11.074146)
		(end 365.96066 -9.550146)
		(stroke
			(width 0.508)
			(type default)
		)
		(layer "In4.Cu")
	)
	(gr_line
		(start 365.98606 -11.074146)
		(end 365.98606 -9.550146)
		(stroke
			(width 0.508)
			(type default)
		)
		(layer "In4.Cu")
	)
	(gr_line
		(start 366.03686 -11.074146)
		(end 366.03686 -9.550146)
		(stroke
			(width 0.508)
			(type default)
		)
		(layer "In4.Cu")
	)
	(gr_line
		(start 366.06226 -11.074146)
		(end 366.06226 -9.550146)
		(stroke
			(width 0.508)
			(type default)
		)
		(layer "In4.Cu")
	)
	(gr_line
		(start 366.06226 -11.048746)
		(end 366.06226 -9.524746)
		(stroke
			(width 0.508)
			(type default)
		)
		(layer "In4.Cu")
	)
	(gr_line
		(start 366.08766 -11.074146)
		(end 366.08766 -9.550146)
		(stroke
			(width 0.508)
			(type default)
		)
		(layer "In4.Cu")
	)
	(gr_line
		(start 366.11306 -11.074146)
		(end 366.11306 -9.550146)
		(stroke
			(width 0.508)
			(type default)
		)
		(layer "In4.Cu")
	)
	(gr_line
		(start 366.13846 -11.074146)
		(end 366.13846 -9.550146)
		(stroke
			(width 0.508)
			(type default)
		)
		(layer "In4.Cu")
	)
	(gr_line
		(start 366.13846 -11.048746)
		(end 366.13846 -9.524746)
		(stroke
			(width 0.508)
			(type default)
		)
		(layer "In4.Cu")
	)
	(gr_line
		(start 366.16386 -11.074146)
		(end 366.16386 -9.550146)
		(stroke
			(width 0.508)
			(type default)
		)
		(layer "In4.Cu")
	)
	(gr_line
		(start 366.18926 -11.074146)
		(end 366.18926 -9.550146)
		(stroke
			(width 0.508)
			(type default)
		)
		(layer "In4.Cu")
	)
	(gr_line
		(start 366.18926 -11.048746)
		(end 366.18926 -9.524746)
		(stroke
			(width 0.508)
			(type default)
		)
		(layer "In4.Cu")
	)
	(gr_line
		(start 366.21466 -11.074146)
		(end 366.21466 -9.550146)
		(stroke
			(width 0.508)
			(type default)
		)
		(layer "In4.Cu")
	)
	(gr_line
		(start 366.21466 -11.048746)
		(end 366.21466 -9.524746)
		(stroke
			(width 0.508)
			(type default)
		)
		(layer "In4.Cu")
	)
	(gr_line
		(start 366.24006 -11.048746)
		(end 366.24006 -9.524746)
		(stroke
			(width 0.508)
			(type default)
		)
		(layer "In4.Cu")
	)
	(gr_line
		(start 366.26546 -11.074146)
		(end 366.26546 -9.550146)
		(stroke
			(width 0.508)
			(type default)
		)
		(layer "In4.Cu")
	)
	(gr_line
		(start 366.287558 -11.378946)
		(end 365.296958 -11.378946)
		(stroke
			(width 0.254)
			(type default)
		)
		(layer "In4.Cu")
	)
	(gr_line
		(start 366.29086 -11.048746)
		(end 366.29086 -9.524746)
		(stroke
			(width 0.508)
			(type default)
		)
		(layer "In4.Cu")
	)
	(gr_line
		(start 366.31626 -11.048746)
		(end 366.31626 -9.524746)
		(stroke
			(width 0.508)
			(type default)
		)
		(layer "In4.Cu")
	)
	(gr_line
		(start 366.34166 -11.074146)
		(end 366.34166 -9.550146)
		(stroke
			(width 0.508)
			(type default)
		)
		(layer "In4.Cu")
	)
	(gr_line
		(start 366.36706 -11.074146)
		(end 366.36706 -9.550146)
		(stroke
			(width 0.508)
			(type default)
		)
		(layer "In4.Cu")
	)
	(gr_line
		(start 366.36706 -11.048746)
		(end 366.36706 -9.524746)
		(stroke
			(width 0.508)
			(type default)
		)
		(layer "In4.Cu")
	)
	(gr_line
		(start 366.41786 -11.074146)
		(end 366.41786 -9.550146)
		(stroke
			(width 0.508)
			(type default)
		)
		(layer "In4.Cu")
	)
	(gr_line
		(start 366.41786 -11.048746)
		(end 366.41786 -9.524746)
		(stroke
			(width 0.508)
			(type default)
		)
		(layer "In4.Cu")
	)
	(gr_line
		(start 366.46866 -11.074146)
		(end 366.46866 -9.550146)
		(stroke
			(width 0.508)
			(type default)
		)
		(layer "In4.Cu")
	)
	(gr_line
		(start 366.46866 -11.048746)
		(end 366.46866 -9.524746)
		(stroke
			(width 0.508)
			(type default)
		)
		(layer "In4.Cu")
	)
	(gr_line
		(start 366.490758 -11.099546)
		(end 366.490758 -9.550146)
		(stroke
			(width 0.762)
			(type default)
		)
		(layer "In4.Cu")
	)
	(gr_line
		(start 366.49406 -11.074146)
		(end 366.49406 -9.550146)
		(stroke
			(width 0.508)
			(type default)
		)
		(layer "In4.Cu")
	)
	(gr_line
		(start 366.51946 -11.074146)
		(end 366.51946 -9.550146)
		(stroke
			(width 0.508)
			(type default)
		)
		(layer "In4.Cu")
	)
	(gr_line
		(start 366.57026 -11.226546)
		(end 366.59566 -11.226546)
		(stroke
			(width 0.2032)
			(type default)
		)
		(layer "In4.Cu")
	)
	(gr_line
		(start 366.59566 -11.226546)
		(end 366.59566 -9.473946)
		(stroke
			(width 0.2032)
			(type default)
		)
		(layer "In4.Cu")
	)
	(gr_line
		(start 366.59566 -9.473946)
		(end 365.55426 -9.473946)
		(stroke
			(width 0.2032)
			(type default)
		)
		(layer "In4.Cu")
	)
	(gr_line
		(start 366.617758 -11.124946)
		(end 366.617758 -9.575546)
		(stroke
			(width 0.762)
			(type default)
		)
		(layer "In4.Cu")
	)
	(gr_line
		(start 366.617758 -11.099546)
		(end 366.617758 -9.600946)
		(stroke
			(width 0.762)
			(type default)
		)
		(layer "In4.Cu")
	)
	(gr_line
		(start 366.617758 -10.997946)
		(end 366.617758 -9.448546)
		(stroke
			(width 0.762)
			(type default)
		)
		(layer "In4.Cu")
	)
	(gr_line
		(start 366.64646 -11.175746)
		(end 366.64646 -9.423146)
		(stroke
			(width 0.2032)
			(type default)
		)
		(layer "In4.Cu")
	)
	(gr_line
		(start 366.64646 -9.423146)
		(end 365.50346 -9.423146)
		(stroke
			(width 0.2032)
			(type default)
		)
		(layer "In4.Cu")
	)
	(gr_line
		(start 366.67186 -11.226546)
		(end 366.67186 -9.372346)
		(stroke
			(width 0.2032)
			(type default)
		)
		(layer "In4.Cu")
	)
	(gr_line
		(start 366.67186 -9.372346)
		(end 365.47806 -9.372346)
		(stroke
			(width 0.2032)
			(type default)
		)
		(layer "In4.Cu")
	)
	(gr_line
		(start 366.72266 -11.302746)
		(end 366.72266 -9.296146)
		(stroke
			(width 0.1016)
			(type default)
		)
		(layer "In4.Cu")
	)
	(gr_line
		(start 366.72266 -9.296146)
		(end 365.42726 -9.296146)
		(stroke
			(width 0.1016)
			(type default)
		)
		(layer "In4.Cu")
	)
	(gr_line
		(start 366.7252 -5.715)
		(end 365.4552 -5.715)
		(stroke
			(width 1.016)
			(type default)
		)
		(layer "In4.Cu")
	)
	(gr_line
		(start 366.820958 -11.226546)
		(end 366.57026 -11.226546)
		(stroke
			(width 0.254)
			(type default)
		)
		(layer "In4.Cu")
	)
	(gr_line
		(start 366.820958 -9.372346)
		(end 366.820958 -11.226546)
		(stroke
			(width 0.254)
			(type default)
		)
		(layer "In4.Cu")
	)
	(gr_line
		(start 366.846358 -11.353546)
		(end 365.373158 -11.353546)
		(stroke
			(width 0.254)
			(type default)
		)
		(layer "In4.Cu")
	)
	(gr_line
		(start 366.846358 -9.245346)
		(end 366.846358 -11.353546)
		(stroke
			(width 0.254)
			(type default)
		)
		(layer "In4.Cu")
	)
	(gr_line
		(start 366.871758 -11.378946)
		(end 365.322358 -11.378946)
		(stroke
			(width 0.254)
			(type default)
		)
		(layer "In4.Cu")
	)
	(gr_line
		(start 366.871758 -9.194546)
		(end 366.871758 -11.378946)
		(stroke
			(width 0.254)
			(type default)
		)
		(layer "In4.Cu")
	)
	(gr_line
		(start 370.98986 -49.800002)
		(end 355.98989 -49.800002)
		(stroke
			(width 2.032)
			(type default)
		)
		(layer "In4.Cu")
	)
	(gr_line
		(start 371.989858 -51.319938)
		(end 371.989858 -50.8)
		(stroke
			(width 2.032)
			(type default)
		)
		(layer "In4.Cu")
	)
	(gr_arc
		(start 371.989858 -51.319938)
		(mid 372.282761 -52.027034)
		(end 372.989856 -52.319936)
		(stroke
			(width 2.032)
			(type default)
		)
		(layer "In4.Cu")
	)
	(gr_arc
		(start 371.989858 -50.8)
		(mid 371.696965 -50.092895)
		(end 370.98986 -49.800002)
		(stroke
			(width 2.032)
			(type default)
		)
		(layer "In4.Cu")
	)
	(gr_line
		(start 379.990096 -52.319936)
		(end 372.989856 -52.319936)
		(stroke
			(width 2.032)
			(type default)
		)
		(layer "In4.Cu")
	)
	(gr_line
		(start 380.37262 -52.24399)
		(end 379.990096 -52.319936)
		(stroke
			(width 2.032)
			(type default)
		)
		(layer "In4.Cu")
	)
	(gr_line
		(start 380.697232 -52.027074)
		(end 380.37262 -52.24399)
		(stroke
			(width 2.032)
			(type default)
		)
		(layer "In4.Cu")
	)
	(gr_line
		(start 380.913894 -51.702716)
		(end 380.697232 -52.027074)
		(stroke
			(width 2.032)
			(type default)
		)
		(layer "In4.Cu")
	)
	(gr_line
		(start 380.98222 -51.376072)
		(end 380.913894 -51.702716)
		(stroke
			(width 2.032)
			(type default)
		)
		(layer "In4.Cu")
	)
	(gr_line
		(start 381.070866 -50.996088)
		(end 380.98222 -51.376072)
		(stroke
			(width 2.032)
			(type default)
		)
		(layer "In4.Cu")
	)
	(gr_line
		(start 381.288798 -50.677064)
		(end 381.070866 -50.996088)
		(stroke
			(width 2.032)
			(type default)
		)
		(layer "In4.Cu")
	)
	(gr_line
		(start 381.611124 -50.464466)
		(end 381.288798 -50.677064)
		(stroke
			(width 2.032)
			(type default)
		)
		(layer "In4.Cu")
	)
	(gr_line
		(start 381.990092 -50.390044)
		(end 381.611124 -50.464466)
		(stroke
			(width 2.032)
			(type default)
		)
		(layer "In4.Cu")
	)
	(gr_line
		(start 385.287266 -13.8176)
		(end 386.074666 -13.8176)
		(stroke
			(width 0.1016)
			(type default)
		)
		(layer "In4.Cu")
	)
	(gr_line
		(start 385.287266 -13.7668)
		(end 385.287266 -11.1506)
		(stroke
			(width 0.1016)
			(type default)
		)
		(layer "In4.Cu")
	)
	(gr_line
		(start 385.287266 -11.1506)
		(end 385.287266 -13.8176)
		(stroke
			(width 0.1016)
			(type default)
		)
		(layer "In4.Cu")
	)
	(gr_line
		(start 385.287266 -11.1506)
		(end 386.481066 -11.1506)
		(stroke
			(width 0.1016)
			(type default)
		)
		(layer "In4.Cu")
	)
	(gr_line
		(start 385.287266 -9.617456)
		(end 386.074666 -9.617456)
		(stroke
			(width 0.1016)
			(type default)
		)
		(layer "In4.Cu")
	)
	(gr_line
		(start 385.287266 -9.566656)
		(end 385.287266 -6.950456)
		(stroke
			(width 0.1016)
			(type default)
		)
		(layer "In4.Cu")
	)
	(gr_line
		(start 385.287266 -6.950456)
		(end 385.287266 -9.617456)
		(stroke
			(width 0.1016)
			(type default)
		)
		(layer "In4.Cu")
	)
	(gr_line
		(start 385.287266 -6.950456)
		(end 386.481066 -6.950456)
		(stroke
			(width 0.1016)
			(type default)
		)
		(layer "In4.Cu")
	)
	(gr_line
		(start 385.287266 -5.417312)
		(end 386.074666 -5.417312)
		(stroke
			(width 0.1016)
			(type default)
		)
		(layer "In4.Cu")
	)
	(gr_line
		(start 385.287266 -5.366512)
		(end 385.287266 -2.750312)
		(stroke
			(width 0.1016)
			(type default)
		)
		(layer "In4.Cu")
	)
	(gr_line
		(start 385.287266 -2.750312)
		(end 385.287266 -5.417312)
		(stroke
			(width 0.1016)
			(type default)
		)
		(layer "In4.Cu")
	)
	(gr_line
		(start 385.287266 -2.750312)
		(end 386.481066 -2.750312)
		(stroke
			(width 0.1016)
			(type default)
		)
		(layer "In4.Cu")
	)
	(gr_line
		(start 385.312666 -13.7668)
		(end 385.312666 -11.176)
		(stroke
			(width 0.1016)
			(type default)
		)
		(layer "In4.Cu")
	)
	(gr_line
		(start 385.312666 -11.176)
		(end 386.455666 -11.176)
		(stroke
			(width 0.1016)
			(type default)
		)
		(layer "In4.Cu")
	)
	(gr_line
		(start 385.312666 -9.566656)
		(end 385.312666 -6.975856)
		(stroke
			(width 0.1016)
			(type default)
		)
		(layer "In4.Cu")
	)
	(gr_line
		(start 385.312666 -6.975856)
		(end 386.455666 -6.975856)
		(stroke
			(width 0.1016)
			(type default)
		)
		(layer "In4.Cu")
	)
	(gr_line
		(start 385.312666 -5.366512)
		(end 385.312666 -2.775712)
		(stroke
			(width 0.1016)
			(type default)
		)
		(layer "In4.Cu")
	)
	(gr_line
		(start 385.312666 -2.775712)
		(end 386.455666 -2.775712)
		(stroke
			(width 0.1016)
			(type default)
		)
		(layer "In4.Cu")
	)
	(gr_line
		(start 385.338066 -13.7668)
		(end 385.338066 -11.2014)
		(stroke
			(width 0.1016)
			(type default)
		)
		(layer "In4.Cu")
	)
	(gr_line
		(start 385.338066 -11.2014)
		(end 385.592066 -11.2014)
		(stroke
			(width 0.1016)
			(type default)
		)
		(layer "In4.Cu")
	)
	(gr_line
		(start 385.338066 -9.566656)
		(end 385.338066 -7.001256)
		(stroke
			(width 0.1016)
			(type default)
		)
		(layer "In4.Cu")
	)
	(gr_line
		(start 385.338066 -7.001256)
		(end 385.592066 -7.001256)
		(stroke
			(width 0.1016)
			(type default)
		)
		(layer "In4.Cu")
	)
	(gr_line
		(start 385.338066 -5.366512)
		(end 385.338066 -2.801112)
		(stroke
			(width 0.1016)
			(type default)
		)
		(layer "In4.Cu")
	)
	(gr_line
		(start 385.338066 -2.801112)
		(end 385.592066 -2.801112)
		(stroke
			(width 0.1016)
			(type default)
		)
		(layer "In4.Cu")
	)
	(gr_line
		(start 385.363466 -13.7668)
		(end 385.363466 -11.2014)
		(stroke
			(width 0.2032)
			(type default)
		)
		(layer "In4.Cu")
	)
	(gr_line
		(start 385.363466 -11.2014)
		(end 386.379466 -11.2014)
		(stroke
			(width 0.2032)
			(type default)
		)
		(layer "In4.Cu")
	)
	(gr_line
		(start 385.363466 -9.566656)
		(end 385.363466 -7.001256)
		(stroke
			(width 0.2032)
			(type default)
		)
		(layer "In4.Cu")
	)
	(gr_line
		(start 385.363466 -7.001256)
		(end 386.379466 -7.001256)
		(stroke
			(width 0.2032)
			(type default)
		)
		(layer "In4.Cu")
	)
	(gr_line
		(start 385.363466 -5.366512)
		(end 385.363466 -2.801112)
		(stroke
			(width 0.2032)
			(type default)
		)
		(layer "In4.Cu")
	)
	(gr_line
		(start 385.363466 -2.801112)
		(end 386.379466 -2.801112)
		(stroke
			(width 0.2032)
			(type default)
		)
		(layer "In4.Cu")
	)
	(gr_line
		(start 385.414266 -13.7414)
		(end 385.414266 -11.2522)
		(stroke
			(width 0.2032)
			(type default)
		)
		(layer "In4.Cu")
	)
	(gr_line
		(start 385.414266 -13.7414)
		(end 385.414266 -11.2522)
		(stroke
			(width 0.254)
			(type default)
		)
		(layer "In4.Cu")
	)
	(gr_line
		(start 385.414266 -11.2522)
		(end 385.617466 -11.2522)
		(stroke
			(width 0.2032)
			(type default)
		)
		(layer "In4.Cu")
	)
	(gr_line
		(start 385.414266 -11.2522)
		(end 386.303266 -11.2522)
		(stroke
			(width 0.254)
			(type default)
		)
		(layer "In4.Cu")
	)
	(gr_line
		(start 385.414266 -9.541256)
		(end 385.414266 -7.052056)
		(stroke
			(width 0.2032)
			(type default)
		)
		(layer "In4.Cu")
	)
	(gr_line
		(start 385.414266 -9.541256)
		(end 385.414266 -7.052056)
		(stroke
			(width 0.254)
			(type default)
		)
		(layer "In4.Cu")
	)
	(gr_line
		(start 385.414266 -7.052056)
		(end 385.617466 -7.052056)
		(stroke
			(width 0.2032)
			(type default)
		)
		(layer "In4.Cu")
	)
	(gr_line
		(start 385.414266 -7.052056)
		(end 386.303266 -7.052056)
		(stroke
			(width 0.254)
			(type default)
		)
		(layer "In4.Cu")
	)
	(gr_line
		(start 385.414266 -5.341112)
		(end 385.414266 -2.851912)
		(stroke
			(width 0.2032)
			(type default)
		)
		(layer "In4.Cu")
	)
	(gr_line
		(start 385.414266 -5.341112)
		(end 385.414266 -2.851912)
		(stroke
			(width 0.254)
			(type default)
		)
		(layer "In4.Cu")
	)
	(gr_line
		(start 385.414266 -2.851912)
		(end 385.617466 -2.851912)
		(stroke
			(width 0.2032)
			(type default)
		)
		(layer "In4.Cu")
	)
	(gr_line
		(start 385.414266 -2.851912)
		(end 386.303266 -2.851912)
		(stroke
			(width 0.254)
			(type default)
		)
		(layer "In4.Cu")
	)
	(gr_line
		(start 385.439666 -13.716)
		(end 385.439666 -11.2776)
		(stroke
			(width 0.254)
			(type default)
		)
		(layer "In4.Cu")
	)
	(gr_line
		(start 385.439666 -11.2776)
		(end 386.277866 -11.2776)
		(stroke
			(width 0.254)
			(type default)
		)
		(layer "In4.Cu")
	)
	(gr_line
		(start 385.439666 -9.515856)
		(end 385.439666 -7.077456)
		(stroke
			(width 0.254)
			(type default)
		)
		(layer "In4.Cu")
	)
	(gr_line
		(start 385.439666 -7.077456)
		(end 386.277866 -7.077456)
		(stroke
			(width 0.254)
			(type default)
		)
		(layer "In4.Cu")
	)
	(gr_line
		(start 385.439666 -5.315712)
		(end 385.439666 -2.877312)
		(stroke
			(width 0.254)
			(type default)
		)
		(layer "In4.Cu")
	)
	(gr_line
		(start 385.439666 -2.877312)
		(end 386.277866 -2.877312)
		(stroke
			(width 0.254)
			(type default)
		)
		(layer "In4.Cu")
	)
	(gr_line
		(start 385.465066 -13.6906)
		(end 385.465066 -11.303)
		(stroke
			(width 0.254)
			(type default)
		)
		(layer "In4.Cu")
	)
	(gr_line
		(start 385.465066 -11.303)
		(end 386.252466 -11.303)
		(stroke
			(width 0.254)
			(type default)
		)
		(layer "In4.Cu")
	)
	(gr_line
		(start 385.465066 -9.490456)
		(end 385.465066 -7.102856)
		(stroke
			(width 0.254)
			(type default)
		)
		(layer "In4.Cu")
	)
	(gr_line
		(start 385.465066 -7.102856)
		(end 386.252466 -7.102856)
		(stroke
			(width 0.254)
			(type default)
		)
		(layer "In4.Cu")
	)
	(gr_line
		(start 385.465066 -5.290312)
		(end 385.465066 -2.902712)
		(stroke
			(width 0.254)
			(type default)
		)
		(layer "In4.Cu")
	)
	(gr_line
		(start 385.465066 -2.902712)
		(end 386.252466 -2.902712)
		(stroke
			(width 0.254)
			(type default)
		)
		(layer "In4.Cu")
	)
	(gr_line
		(start 385.490466 -13.6144)
		(end 386.125466 -13.6144)
		(stroke
			(width 0.508)
			(type default)
		)
		(layer "In4.Cu")
	)
	(gr_line
		(start 385.490466 -11.43)
		(end 386.125466 -11.43)
		(stroke
			(width 0.508)
			(type default)
		)
		(layer "In4.Cu")
	)
	(gr_line
		(start 385.490466 -11.3792)
		(end 386.125466 -11.3792)
		(stroke
			(width 0.508)
			(type default)
		)
		(layer "In4.Cu")
	)
	(gr_line
		(start 385.490466 -9.414256)
		(end 386.125466 -9.414256)
		(stroke
			(width 0.508)
			(type default)
		)
		(layer "In4.Cu")
	)
	(gr_line
		(start 385.490466 -7.229856)
		(end 386.125466 -7.229856)
		(stroke
			(width 0.508)
			(type default)
		)
		(layer "In4.Cu")
	)
	(gr_line
		(start 385.490466 -7.179056)
		(end 386.125466 -7.179056)
		(stroke
			(width 0.508)
			(type default)
		)
		(layer "In4.Cu")
	)
	(gr_line
		(start 385.490466 -5.214112)
		(end 386.125466 -5.214112)
		(stroke
			(width 0.508)
			(type default)
		)
		(layer "In4.Cu")
	)
	(gr_line
		(start 385.490466 -3.029712)
		(end 386.125466 -3.029712)
		(stroke
			(width 0.508)
			(type default)
		)
		(layer "In4.Cu")
	)
	(gr_line
		(start 385.490466 -2.978912)
		(end 386.125466 -2.978912)
		(stroke
			(width 0.508)
			(type default)
		)
		(layer "In4.Cu")
	)
	(gr_line
		(start 385.515866 -11.684)
		(end 386.150866 -11.684)
		(stroke
			(width 0.508)
			(type default)
		)
		(layer "In4.Cu")
	)
	(gr_line
		(start 385.515866 -7.483856)
		(end 386.150866 -7.483856)
		(stroke
			(width 0.508)
			(type default)
		)
		(layer "In4.Cu")
	)
	(gr_line
		(start 385.515866 -3.283712)
		(end 386.150866 -3.283712)
		(stroke
			(width 0.508)
			(type default)
		)
		(layer "In4.Cu")
	)
	(gr_line
		(start 385.541266 -13.6398)
		(end 385.541266 -11.3792)
		(stroke
			(width 0.254)
			(type default)
		)
		(layer "In4.Cu")
	)
	(gr_line
		(start 385.541266 -13.4874)
		(end 386.176266 -13.4874)
		(stroke
			(width 0.508)
			(type default)
		)
		(layer "In4.Cu")
	)
	(gr_line
		(start 385.541266 -11.3792)
		(end 386.176266 -11.3792)
		(stroke
			(width 0.254)
			(type default)
		)
		(layer "In4.Cu")
	)
	(gr_line
		(start 385.541266 -9.439656)
		(end 385.541266 -7.179056)
		(stroke
			(width 0.254)
			(type default)
		)
		(layer "In4.Cu")
	)
	(gr_line
		(start 385.541266 -9.287256)
		(end 386.176266 -9.287256)
		(stroke
			(width 0.508)
			(type default)
		)
		(layer "In4.Cu")
	)
	(gr_line
		(start 385.541266 -7.179056)
		(end 386.176266 -7.179056)
		(stroke
			(width 0.254)
			(type default)
		)
		(layer "In4.Cu")
	)
	(gr_line
		(start 385.541266 -5.239512)
		(end 385.541266 -2.978912)
		(stroke
			(width 0.254)
			(type default)
		)
		(layer "In4.Cu")
	)
	(gr_line
		(start 385.541266 -5.087112)
		(end 386.176266 -5.087112)
		(stroke
			(width 0.508)
			(type default)
		)
		(layer "In4.Cu")
	)
	(gr_line
		(start 385.541266 -2.978912)
		(end 386.176266 -2.978912)
		(stroke
			(width 0.254)
			(type default)
		)
		(layer "In4.Cu")
	)
	(gr_line
		(start 385.566666 -13.335)
		(end 386.201666 -13.335)
		(stroke
			(width 0.508)
			(type default)
		)
		(layer "In4.Cu")
	)
	(gr_line
		(start 385.566666 -9.134856)
		(end 386.201666 -9.134856)
		(stroke
			(width 0.508)
			(type default)
		)
		(layer "In4.Cu")
	)
	(gr_line
		(start 385.566666 -4.934712)
		(end 386.201666 -4.934712)
		(stroke
			(width 0.508)
			(type default)
		)
		(layer "In4.Cu")
	)
	(gr_line
		(start 385.592066 -13.6144)
		(end 386.227066 -13.6144)
		(stroke
			(width 0.508)
			(type default)
		)
		(layer "In4.Cu")
	)
	(gr_line
		(start 385.592066 -11.2014)
		(end 386.430266 -11.2014)
		(stroke
			(width 0.2032)
			(type default)
		)
		(layer "In4.Cu")
	)
	(gr_line
		(start 385.592066 -9.414256)
		(end 386.227066 -9.414256)
		(stroke
			(width 0.508)
			(type default)
		)
		(layer "In4.Cu")
	)
	(gr_line
		(start 385.592066 -7.001256)
		(end 386.430266 -7.001256)
		(stroke
			(width 0.2032)
			(type default)
		)
		(layer "In4.Cu")
	)
	(gr_line
		(start 385.592066 -5.214112)
		(end 386.227066 -5.214112)
		(stroke
			(width 0.508)
			(type default)
		)
		(layer "In4.Cu")
	)
	(gr_line
		(start 385.592066 -2.801112)
		(end 386.430266 -2.801112)
		(stroke
			(width 0.2032)
			(type default)
		)
		(layer "In4.Cu")
	)
	(gr_line
		(start 385.617466 -13.6144)
		(end 385.617466 -11.43)
		(stroke
			(width 0.254)
			(type default)
		)
		(layer "In4.Cu")
	)
	(gr_line
		(start 385.617466 -11.43)
		(end 386.100066 -11.43)
		(stroke
			(width 0.254)
			(type default)
		)
		(layer "In4.Cu")
	)
	(gr_line
		(start 385.617466 -11.2522)
		(end 386.354066 -11.2522)
		(stroke
			(width 0.254)
			(type default)
		)
		(layer "In4.Cu")
	)
	(gr_line
		(start 385.617466 -9.414256)
		(end 385.617466 -7.229856)
		(stroke
			(width 0.254)
			(type default)
		)
		(layer "In4.Cu")
	)
	(gr_line
		(start 385.617466 -7.229856)
		(end 386.100066 -7.229856)
		(stroke
			(width 0.254)
			(type default)
		)
		(layer "In4.Cu")
	)
	(gr_line
		(start 385.617466 -7.052056)
		(end 386.354066 -7.052056)
		(stroke
			(width 0.254)
			(type default)
		)
		(layer "In4.Cu")
	)
	(gr_line
		(start 385.617466 -5.214112)
		(end 385.617466 -3.029712)
		(stroke
			(width 0.254)
			(type default)
		)
		(layer "In4.Cu")
	)
	(gr_line
		(start 385.617466 -3.029712)
		(end 386.100066 -3.029712)
		(stroke
			(width 0.254)
			(type default)
		)
		(layer "In4.Cu")
	)
	(gr_line
		(start 385.617466 -2.851912)
		(end 386.354066 -2.851912)
		(stroke
			(width 0.254)
			(type default)
		)
		(layer "In4.Cu")
	)
	(gr_line
		(start 385.636008 -11.36523)
		(end 386.271008 -11.36523)
		(stroke
			(width 0.508)
			(type default)
		)
		(layer "In4.Cu")
	)
	(gr_line
		(start 385.636008 -7.165086)
		(end 386.271008 -7.165086)
		(stroke
			(width 0.508)
			(type default)
		)
		(layer "In4.Cu")
	)
	(gr_line
		(start 385.636008 -2.964942)
		(end 386.271008 -2.964942)
		(stroke
			(width 0.508)
			(type default)
		)
		(layer "In4.Cu")
	)
	(gr_line
		(start 385.642866 -13.6144)
		(end 386.277866 -13.6144)
		(stroke
			(width 0.508)
			(type default)
		)
		(layer "In4.Cu")
	)
	(gr_line
		(start 385.642866 -13.4874)
		(end 385.642866 -11.5062)
		(stroke
			(width 0.762)
			(type default)
		)
		(layer "In4.Cu")
	)
	(gr_line
		(start 385.642866 -11.5062)
		(end 386.277866 -11.5062)
		(stroke
			(width 0.508)
			(type default)
		)
		(layer "In4.Cu")
	)
	(gr_line
		(start 385.642866 -9.414256)
		(end 386.277866 -9.414256)
		(stroke
			(width 0.508)
			(type default)
		)
		(layer "In4.Cu")
	)
	(gr_line
		(start 385.642866 -9.287256)
		(end 385.642866 -7.306056)
		(stroke
			(width 0.762)
			(type default)
		)
		(layer "In4.Cu")
	)
	(gr_line
		(start 385.642866 -7.306056)
		(end 386.277866 -7.306056)
		(stroke
			(width 0.508)
			(type default)
		)
		(layer "In4.Cu")
	)
	(gr_line
		(start 385.642866 -5.214112)
		(end 386.277866 -5.214112)
		(stroke
			(width 0.508)
			(type default)
		)
		(layer "In4.Cu")
	)
	(gr_line
		(start 385.642866 -5.087112)
		(end 385.642866 -3.105912)
		(stroke
			(width 0.762)
			(type default)
		)
		(layer "In4.Cu")
	)
	(gr_line
		(start 385.642866 -3.105912)
		(end 386.277866 -3.105912)
		(stroke
			(width 0.508)
			(type default)
		)
		(layer "In4.Cu")
	)
	(gr_line
		(start 385.693666 -13.5382)
		(end 385.693666 -11.5062)
		(stroke
			(width 0.254)
			(type default)
		)
		(layer "In4.Cu")
	)
	(gr_line
		(start 385.693666 -11.5062)
		(end 386.023866 -11.5062)
		(stroke
			(width 0.254)
			(type default)
		)
		(layer "In4.Cu")
	)
	(gr_line
		(start 385.693666 -9.338056)
		(end 385.693666 -7.306056)
		(stroke
			(width 0.254)
			(type default)
		)
		(layer "In4.Cu")
	)
	(gr_line
		(start 385.693666 -7.306056)
		(end 386.023866 -7.306056)
		(stroke
			(width 0.254)
			(type default)
		)
		(layer "In4.Cu")
	)
	(gr_line
		(start 385.693666 -5.137912)
		(end 385.693666 -3.105912)
		(stroke
			(width 0.254)
			(type default)
		)
		(layer "In4.Cu")
	)
	(gr_line
		(start 385.693666 -3.105912)
		(end 386.023866 -3.105912)
		(stroke
			(width 0.254)
			(type default)
		)
		(layer "In4.Cu")
	)
	(gr_line
		(start 385.795266 -13.462)
		(end 385.795266 -11.6586)
		(stroke
			(width 0.254)
			(type default)
		)
		(layer "In4.Cu")
	)
	(gr_line
		(start 385.795266 -13.462)
		(end 385.795266 -11.4808)
		(stroke
			(width 0.762)
			(type default)
		)
		(layer "In4.Cu")
	)
	(gr_line
		(start 385.795266 -11.6586)
		(end 385.896866 -11.6586)
		(stroke
			(width 0.254)
			(type default)
		)
		(layer "In4.Cu")
	)
	(gr_line
		(start 385.795266 -9.261856)
		(end 385.795266 -7.458456)
		(stroke
			(width 0.254)
			(type default)
		)
		(layer "In4.Cu")
	)
	(gr_line
		(start 385.795266 -9.261856)
		(end 385.795266 -7.280656)
		(stroke
			(width 0.762)
			(type default)
		)
		(layer "In4.Cu")
	)
	(gr_line
		(start 385.795266 -7.458456)
		(end 385.896866 -7.458456)
		(stroke
			(width 0.254)
			(type default)
		)
		(layer "In4.Cu")
	)
	(gr_line
		(start 385.795266 -5.061712)
		(end 385.795266 -3.258312)
		(stroke
			(width 0.254)
			(type default)
		)
		(layer "In4.Cu")
	)
	(gr_line
		(start 385.795266 -5.061712)
		(end 385.795266 -3.080512)
		(stroke
			(width 0.762)
			(type default)
		)
		(layer "In4.Cu")
	)
	(gr_line
		(start 385.795266 -3.258312)
		(end 385.896866 -3.258312)
		(stroke
			(width 0.254)
			(type default)
		)
		(layer "In4.Cu")
	)
	(gr_line
		(start 385.896866 -13.5636)
		(end 385.846066 -13.5636)
		(stroke
			(width 0.254)
			(type default)
		)
		(layer "In4.Cu")
	)
	(gr_line
		(start 385.896866 -11.6586)
		(end 385.896866 -13.5636)
		(stroke
			(width 0.254)
			(type default)
		)
		(layer "In4.Cu")
	)
	(gr_line
		(start 385.896866 -9.363456)
		(end 385.846066 -9.363456)
		(stroke
			(width 0.254)
			(type default)
		)
		(layer "In4.Cu")
	)
	(gr_line
		(start 385.896866 -7.458456)
		(end 385.896866 -9.363456)
		(stroke
			(width 0.254)
			(type default)
		)
		(layer "In4.Cu")
	)
	(gr_line
		(start 385.896866 -5.163312)
		(end 385.846066 -5.163312)
		(stroke
			(width 0.254)
			(type default)
		)
		(layer "In4.Cu")
	)
	(gr_line
		(start 385.896866 -3.258312)
		(end 385.896866 -5.163312)
		(stroke
			(width 0.254)
			(type default)
		)
		(layer "In4.Cu")
	)
	(gr_line
		(start 385.947666 -13.4874)
		(end 385.947666 -11.5062)
		(stroke
			(width 0.762)
			(type default)
		)
		(layer "In4.Cu")
	)
	(gr_line
		(start 385.947666 -9.287256)
		(end 385.947666 -7.306056)
		(stroke
			(width 0.762)
			(type default)
		)
		(layer "In4.Cu")
	)
	(gr_line
		(start 385.947666 -5.087112)
		(end 385.947666 -3.105912)
		(stroke
			(width 0.762)
			(type default)
		)
		(layer "In4.Cu")
	)
	(gr_line
		(start 386.023866 -13.462)
		(end 385.795266 -13.462)
		(stroke
			(width 0.254)
			(type default)
		)
		(layer "In4.Cu")
	)
	(gr_line
		(start 386.023866 -11.5062)
		(end 386.023866 -13.462)
		(stroke
			(width 0.254)
			(type default)
		)
		(layer "In4.Cu")
	)
	(gr_line
		(start 386.023866 -9.261856)
		(end 385.795266 -9.261856)
		(stroke
			(width 0.254)
			(type default)
		)
		(layer "In4.Cu")
	)
	(gr_line
		(start 386.023866 -7.306056)
		(end 386.023866 -9.261856)
		(stroke
			(width 0.254)
			(type default)
		)
		(layer "In4.Cu")
	)
	(gr_line
		(start 386.023866 -5.061712)
		(end 385.795266 -5.061712)
		(stroke
			(width 0.254)
			(type default)
		)
		(layer "In4.Cu")
	)
	(gr_line
		(start 386.023866 -3.105912)
		(end 386.023866 -5.061712)
		(stroke
			(width 0.254)
			(type default)
		)
		(layer "In4.Cu")
	)
	(gr_line
		(start 386.074666 -13.8176)
		(end 386.074666 -13.7668)
		(stroke
			(width 0.1016)
			(type default)
		)
		(layer "In4.Cu")
	)
	(gr_line
		(start 386.074666 -13.8176)
		(end 386.481066 -13.8176)
		(stroke
			(width 0.1016)
			(type default)
		)
		(layer "In4.Cu")
	)
	(gr_line
		(start 386.074666 -13.7668)
		(end 385.312666 -13.7668)
		(stroke
			(width 0.1016)
			(type default)
		)
		(layer "In4.Cu")
	)
	(gr_line
		(start 386.074666 -13.4874)
		(end 386.074666 -11.5062)
		(stroke
			(width 0.762)
			(type default)
		)
		(layer "In4.Cu")
	)
	(gr_line
		(start 386.074666 -9.617456)
		(end 386.074666 -9.566656)
		(stroke
			(width 0.1016)
			(type default)
		)
		(layer "In4.Cu")
	)
	(gr_line
		(start 386.074666 -9.617456)
		(end 386.481066 -9.617456)
		(stroke
			(width 0.1016)
			(type default)
		)
		(layer "In4.Cu")
	)
	(gr_line
		(start 386.074666 -9.566656)
		(end 385.312666 -9.566656)
		(stroke
			(width 0.1016)
			(type default)
		)
		(layer "In4.Cu")
	)
	(gr_line
		(start 386.074666 -9.287256)
		(end 386.074666 -7.306056)
		(stroke
			(width 0.762)
			(type default)
		)
		(layer "In4.Cu")
	)
	(gr_line
		(start 386.074666 -5.417312)
		(end 386.074666 -5.366512)
		(stroke
			(width 0.1016)
			(type default)
		)
		(layer "In4.Cu")
	)
	(gr_line
		(start 386.074666 -5.417312)
		(end 386.481066 -5.417312)
		(stroke
			(width 0.1016)
			(type default)
		)
		(layer "In4.Cu")
	)
	(gr_line
		(start 386.074666 -5.366512)
		(end 385.312666 -5.366512)
		(stroke
			(width 0.1016)
			(type default)
		)
		(layer "In4.Cu")
	)
	(gr_line
		(start 386.074666 -5.087112)
		(end 386.074666 -3.105912)
		(stroke
			(width 0.762)
			(type default)
		)
		(layer "In4.Cu")
	)
	(gr_line
		(start 386.100066 -13.5382)
		(end 385.693666 -13.5382)
		(stroke
			(width 0.254)
			(type default)
		)
		(layer "In4.Cu")
	)
	(gr_line
		(start 386.100066 -11.43)
		(end 386.100066 -13.5382)
		(stroke
			(width 0.254)
			(type default)
		)
		(layer "In4.Cu")
	)
	(gr_line
		(start 386.100066 -9.338056)
		(end 385.693666 -9.338056)
		(stroke
			(width 0.254)
			(type default)
		)
		(layer "In4.Cu")
	)
	(gr_line
		(start 386.100066 -7.229856)
		(end 386.100066 -9.338056)
		(stroke
			(width 0.254)
			(type default)
		)
		(layer "In4.Cu")
	)
	(gr_line
		(start 386.100066 -5.137912)
		(end 385.693666 -5.137912)
		(stroke
			(width 0.254)
			(type default)
		)
		(layer "In4.Cu")
	)
	(gr_line
		(start 386.100066 -3.029712)
		(end 386.100066 -5.137912)
		(stroke
			(width 0.254)
			(type default)
		)
		(layer "In4.Cu")
	)
	(gr_line
		(start 386.150866 -13.4874)
		(end 386.150866 -11.5062)
		(stroke
			(width 0.762)
			(type default)
		)
		(layer "In4.Cu")
	)
	(gr_line
		(start 386.150866 -9.287256)
		(end 386.150866 -7.306056)
		(stroke
			(width 0.762)
			(type default)
		)
		(layer "In4.Cu")
	)
	(gr_line
		(start 386.150866 -5.087112)
		(end 386.150866 -3.105912)
		(stroke
			(width 0.762)
			(type default)
		)
		(layer "In4.Cu")
	)
	(gr_line
		(start 386.176266 -13.6144)
		(end 385.617466 -13.6144)
		(stroke
			(width 0.254)
			(type default)
		)
		(layer "In4.Cu")
	)
	(gr_line
		(start 386.176266 -11.3792)
		(end 386.176266 -13.6144)
		(stroke
			(width 0.254)
			(type default)
		)
		(layer "In4.Cu")
	)
	(gr_line
		(start 386.176266 -9.414256)
		(end 385.617466 -9.414256)
		(stroke
			(width 0.254)
			(type default)
		)
		(layer "In4.Cu")
	)
	(gr_line
		(start 386.176266 -7.179056)
		(end 386.176266 -9.414256)
		(stroke
			(width 0.254)
			(type default)
		)
		(layer "In4.Cu")
	)
	(gr_line
		(start 386.176266 -5.214112)
		(end 385.617466 -5.214112)
		(stroke
			(width 0.254)
			(type default)
		)
		(layer "In4.Cu")
	)
	(gr_line
		(start 386.176266 -2.978912)
		(end 386.176266 -5.214112)
		(stroke
			(width 0.254)
			(type default)
		)
		(layer "In4.Cu")
	)
	(gr_line
		(start 386.252466 -13.6398)
		(end 385.541266 -13.6398)
		(stroke
			(width 0.254)
			(type default)
		)
		(layer "In4.Cu")
	)
	(gr_line
		(start 386.252466 -11.303)
		(end 386.252466 -13.6398)
		(stroke
			(width 0.254)
			(type default)
		)
		(layer "In4.Cu")
	)
	(gr_line
		(start 386.252466 -9.439656)
		(end 385.541266 -9.439656)
		(stroke
			(width 0.254)
			(type default)
		)
		(layer "In4.Cu")
	)
	(gr_line
		(start 386.252466 -7.102856)
		(end 386.252466 -9.439656)
		(stroke
			(width 0.254)
			(type default)
		)
		(layer "In4.Cu")
	)
	(gr_line
		(start 386.252466 -5.239512)
		(end 385.541266 -5.239512)
		(stroke
			(width 0.254)
			(type default)
		)
		(layer "In4.Cu")
	)
	(gr_line
		(start 386.252466 -2.902712)
		(end 386.252466 -5.239512)
		(stroke
			(width 0.254)
			(type default)
		)
		(layer "In4.Cu")
	)
	(gr_line
		(start 386.277866 -13.7668)
		(end 385.287266 -13.7668)
		(stroke
			(width 0.1016)
			(type default)
		)
		(layer "In4.Cu")
	)
	(gr_line
		(start 386.277866 -13.6906)
		(end 385.465066 -13.6906)
		(stroke
			(width 0.254)
			(type default)
		)
		(layer "In4.Cu")
	)
	(gr_line
		(start 386.277866 -11.2776)
		(end 386.277866 -13.6906)
		(stroke
			(width 0.254)
			(type default)
		)
		(layer "In4.Cu")
	)
	(gr_line
		(start 386.277866 -9.566656)
		(end 385.287266 -9.566656)
		(stroke
			(width 0.1016)
			(type default)
		)
		(layer "In4.Cu")
	)
	(gr_line
		(start 386.277866 -9.490456)
		(end 385.465066 -9.490456)
		(stroke
			(width 0.254)
			(type default)
		)
		(layer "In4.Cu")
	)
	(gr_line
		(start 386.277866 -7.077456)
		(end 386.277866 -9.490456)
		(stroke
			(width 0.254)
			(type default)
		)
		(layer "In4.Cu")
	)
	(gr_line
		(start 386.277866 -5.366512)
		(end 385.287266 -5.366512)
		(stroke
			(width 0.1016)
			(type default)
		)
		(layer "In4.Cu")
	)
	(gr_line
		(start 386.277866 -5.290312)
		(end 385.465066 -5.290312)
		(stroke
			(width 0.254)
			(type default)
		)
		(layer "In4.Cu")
	)
	(gr_line
		(start 386.277866 -2.877312)
		(end 386.277866 -5.290312)
		(stroke
			(width 0.254)
			(type default)
		)
		(layer "In4.Cu")
	)
	(gr_line
		(start 386.303266 -13.716)
		(end 385.439666 -13.716)
		(stroke
			(width 0.254)
			(type default)
		)
		(layer "In4.Cu")
	)
	(gr_line
		(start 386.303266 -11.2522)
		(end 386.303266 -13.716)
		(stroke
			(width 0.254)
			(type default)
		)
		(layer "In4.Cu")
	)
	(gr_line
		(start 386.303266 -9.515856)
		(end 385.439666 -9.515856)
		(stroke
			(width 0.254)
			(type default)
		)
		(layer "In4.Cu")
	)
	(gr_line
		(start 386.303266 -7.052056)
		(end 386.303266 -9.515856)
		(stroke
			(width 0.254)
			(type default)
		)
		(layer "In4.Cu")
	)
	(gr_line
		(start 386.303266 -5.315712)
		(end 385.439666 -5.315712)
		(stroke
			(width 0.254)
			(type default)
		)
		(layer "In4.Cu")
	)
	(gr_line
		(start 386.303266 -2.851912)
		(end 386.303266 -5.315712)
		(stroke
			(width 0.254)
			(type default)
		)
		(layer "In4.Cu")
	)
	(gr_line
		(start 386.354066 -13.7414)
		(end 385.414266 -13.7414)
		(stroke
			(width 0.254)
			(type default)
		)
		(layer "In4.Cu")
	)
	(gr_line
		(start 386.354066 -11.2522)
		(end 386.354066 -13.7414)
		(stroke
			(width 0.254)
			(type default)
		)
		(layer "In4.Cu")
	)
	(gr_line
		(start 386.354066 -9.541256)
		(end 385.414266 -9.541256)
		(stroke
			(width 0.254)
			(type default)
		)
		(layer "In4.Cu")
	)
	(gr_line
		(start 386.354066 -7.052056)
		(end 386.354066 -9.541256)
		(stroke
			(width 0.254)
			(type default)
		)
		(layer "In4.Cu")
	)
	(gr_line
		(start 386.354066 -5.341112)
		(end 385.414266 -5.341112)
		(stroke
			(width 0.254)
			(type default)
		)
		(layer "In4.Cu")
	)
	(gr_line
		(start 386.354066 -2.851912)
		(end 386.354066 -5.341112)
		(stroke
			(width 0.254)
			(type default)
		)
		(layer "In4.Cu")
	)
	(gr_line
		(start 386.379466 -13.7414)
		(end 385.414266 -13.7414)
		(stroke
			(width 0.2032)
			(type default)
		)
		(layer "In4.Cu")
	)
	(gr_line
		(start 386.379466 -11.2014)
		(end 386.379466 -13.7414)
		(stroke
			(width 0.2032)
			(type default)
		)
		(layer "In4.Cu")
	)
	(gr_line
		(start 386.379466 -9.541256)
		(end 385.414266 -9.541256)
		(stroke
			(width 0.2032)
			(type default)
		)
		(layer "In4.Cu")
	)
	(gr_line
		(start 386.379466 -7.001256)
		(end 386.379466 -9.541256)
		(stroke
			(width 0.2032)
			(type default)
		)
		(layer "In4.Cu")
	)
	(gr_line
		(start 386.379466 -5.341112)
		(end 385.414266 -5.341112)
		(stroke
			(width 0.2032)
			(type default)
		)
		(layer "In4.Cu")
	)
	(gr_line
		(start 386.379466 -2.801112)
		(end 386.379466 -5.341112)
		(stroke
			(width 0.2032)
			(type default)
		)
		(layer "In4.Cu")
	)
	(gr_line
		(start 386.430266 -13.7668)
		(end 385.363466 -13.7668)
		(stroke
			(width 0.2032)
			(type default)
		)
		(layer "In4.Cu")
	)
	(gr_line
		(start 386.430266 -11.2014)
		(end 386.430266 -13.7668)
		(stroke
			(width 0.2032)
			(type default)
		)
		(layer "In4.Cu")
	)
	(gr_line
		(start 386.430266 -9.566656)
		(end 385.363466 -9.566656)
		(stroke
			(width 0.2032)
			(type default)
		)
		(layer "In4.Cu")
	)
	(gr_line
		(start 386.430266 -7.001256)
		(end 386.430266 -9.566656)
		(stroke
			(width 0.2032)
			(type default)
		)
		(layer "In4.Cu")
	)
	(gr_line
		(start 386.430266 -5.366512)
		(end 385.363466 -5.366512)
		(stroke
			(width 0.2032)
			(type default)
		)
		(layer "In4.Cu")
	)
	(gr_line
		(start 386.430266 -2.801112)
		(end 386.430266 -5.366512)
		(stroke
			(width 0.2032)
			(type default)
		)
		(layer "In4.Cu")
	)
	(gr_line
		(start 386.455666 -13.7668)
		(end 385.338066 -13.7668)
		(stroke
			(width 0.1016)
			(type default)
		)
		(layer "In4.Cu")
	)
	(gr_line
		(start 386.455666 -11.176)
		(end 386.455666 -13.7668)
		(stroke
			(width 0.1016)
			(type default)
		)
		(layer "In4.Cu")
	)
	(gr_line
		(start 386.455666 -9.566656)
		(end 385.338066 -9.566656)
		(stroke
			(width 0.1016)
			(type default)
		)
		(layer "In4.Cu")
	)
	(gr_line
		(start 386.455666 -6.975856)
		(end 386.455666 -9.566656)
		(stroke
			(width 0.1016)
			(type default)
		)
		(layer "In4.Cu")
	)
	(gr_line
		(start 386.455666 -5.366512)
		(end 385.338066 -5.366512)
		(stroke
			(width 0.1016)
			(type default)
		)
		(layer "In4.Cu")
	)
	(gr_line
		(start 386.455666 -2.775712)
		(end 386.455666 -5.366512)
		(stroke
			(width 0.1016)
			(type default)
		)
		(layer "In4.Cu")
	)
	(gr_line
		(start 386.481066 -13.8176)
		(end 386.074666 -13.8176)
		(stroke
			(width 0.1016)
			(type default)
		)
		(layer "In4.Cu")
	)
	(gr_line
		(start 386.481066 -13.8176)
		(end 386.481066 -11.1506)
		(stroke
			(width 0.1016)
			(type default)
		)
		(layer "In4.Cu")
	)
	(gr_line
		(start 386.481066 -11.1506)
		(end 385.287266 -11.1506)
		(stroke
			(width 0.1016)
			(type default)
		)
		(layer "In4.Cu")
	)
	(gr_line
		(start 386.481066 -11.1506)
		(end 386.481066 -13.8176)
		(stroke
			(width 0.1016)
			(type default)
		)
		(layer "In4.Cu")
	)
	(gr_line
		(start 386.481066 -9.617456)
		(end 386.074666 -9.617456)
		(stroke
			(width 0.1016)
			(type default)
		)
		(layer "In4.Cu")
	)
	(gr_line
		(start 386.481066 -9.617456)
		(end 386.481066 -6.950456)
		(stroke
			(width 0.1016)
			(type default)
		)
		(layer "In4.Cu")
	)
	(gr_line
		(start 386.481066 -6.950456)
		(end 385.287266 -6.950456)
		(stroke
			(width 0.1016)
			(type default)
		)
		(layer "In4.Cu")
	)
	(gr_line
		(start 386.481066 -6.950456)
		(end 386.481066 -9.617456)
		(stroke
			(width 0.1016)
			(type default)
		)
		(layer "In4.Cu")
	)
	(gr_line
		(start 386.481066 -5.417312)
		(end 386.074666 -5.417312)
		(stroke
			(width 0.1016)
			(type default)
		)
		(layer "In4.Cu")
	)
	(gr_line
		(start 386.481066 -5.417312)
		(end 386.481066 -2.750312)
		(stroke
			(width 0.1016)
			(type default)
		)
		(layer "In4.Cu")
	)
	(gr_line
		(start 386.481066 -2.750312)
		(end 385.287266 -2.750312)
		(stroke
			(width 0.1016)
			(type default)
		)
		(layer "In4.Cu")
	)
	(gr_line
		(start 386.481066 -2.750312)
		(end 386.481066 -5.417312)
		(stroke
			(width 0.1016)
			(type default)
		)
		(layer "In4.Cu")
	)
	(gr_line
		(start 387.217666 -24.6634)
		(end 387.217666 -23.3934)
		(stroke
			(width 0.7874)
			(type default)
		)
		(layer "In4.Cu")
	)
	(gr_line
		(start 387.287262 -12.563348)
		(end 388.074662 -12.563348)
		(stroke
			(width 0.1016)
			(type default)
		)
		(layer "In4.Cu")
	)
	(gr_line
		(start 387.287262 -12.512548)
		(end 387.287262 -9.896348)
		(stroke
			(width 0.1016)
			(type default)
		)
		(layer "In4.Cu")
	)
	(gr_line
		(start 387.287262 -12.463272)
		(end 388.074662 -12.463272)
		(stroke
			(width 0.1016)
			(type default)
		)
		(layer "In4.Cu")
	)
	(gr_line
		(start 387.287262 -12.412472)
		(end 387.287262 -9.796272)
		(stroke
			(width 0.1016)
			(type default)
		)
		(layer "In4.Cu")
	)
	(gr_line
		(start 387.287262 -9.896348)
		(end 387.287262 -12.563348)
		(stroke
			(width 0.1016)
			(type default)
		)
		(layer "In4.Cu")
	)
	(gr_line
		(start 387.287262 -9.896348)
		(end 388.481062 -9.896348)
		(stroke
			(width 0.1016)
			(type default)
		)
		(layer "In4.Cu")
	)
	(gr_line
		(start 387.287262 -9.796272)
		(end 387.287262 -12.463272)
		(stroke
			(width 0.1016)
			(type default)
		)
		(layer "In4.Cu")
	)
	(gr_line
		(start 387.287262 -9.796272)
		(end 388.481062 -9.796272)
		(stroke
			(width 0.1016)
			(type default)
		)
		(layer "In4.Cu")
	)
	(gr_line
		(start 387.287262 -8.363204)
		(end 388.074662 -8.363204)
		(stroke
			(width 0.1016)
			(type default)
		)
		(layer "In4.Cu")
	)
	(gr_line
		(start 387.287262 -8.312404)
		(end 387.287262 -5.696204)
		(stroke
			(width 0.1016)
			(type default)
		)
		(layer "In4.Cu")
	)
	(gr_line
		(start 387.287262 -8.263128)
		(end 388.074662 -8.263128)
		(stroke
			(width 0.1016)
			(type default)
		)
		(layer "In4.Cu")
	)
	(gr_line
		(start 387.287262 -8.212328)
		(end 387.287262 -5.596128)
		(stroke
			(width 0.1016)
			(type default)
		)
		(layer "In4.Cu")
	)
	(gr_line
		(start 387.287262 -5.696204)
		(end 387.287262 -8.363204)
		(stroke
			(width 0.1016)
			(type default)
		)
		(layer "In4.Cu")
	)
	(gr_line
		(start 387.287262 -5.696204)
		(end 388.481062 -5.696204)
		(stroke
			(width 0.1016)
			(type default)
		)
		(layer "In4.Cu")
	)
	(gr_line
		(start 387.287262 -5.596128)
		(end 387.287262 -8.263128)
		(stroke
			(width 0.1016)
			(type default)
		)
		(layer "In4.Cu")
	)
	(gr_line
		(start 387.287262 -5.596128)
		(end 388.481062 -5.596128)
		(stroke
			(width 0.1016)
			(type default)
		)
		(layer "In4.Cu")
	)
	(gr_line
		(start 387.287262 -4.16306)
		(end 388.074662 -4.16306)
		(stroke
			(width 0.1016)
			(type default)
		)
		(layer "In4.Cu")
	)
	(gr_line
		(start 387.287262 -4.11226)
		(end 387.287262 -1.49606)
		(stroke
			(width 0.1016)
			(type default)
		)
		(layer "In4.Cu")
	)
	(gr_line
		(start 387.287262 -4.062984)
		(end 388.074662 -4.062984)
		(stroke
			(width 0.1016)
			(type default)
		)
		(layer "In4.Cu")
	)
	(gr_line
		(start 387.287262 -4.012184)
		(end 387.287262 -1.395984)
		(stroke
			(width 0.1016)
			(type default)
		)
		(layer "In4.Cu")
	)
	(gr_line
		(start 387.287262 -1.49606)
		(end 387.287262 -4.16306)
		(stroke
			(width 0.1016)
			(type default)
		)
		(layer "In4.Cu")
	)
	(gr_line
		(start 387.287262 -1.49606)
		(end 388.481062 -1.49606)
		(stroke
			(width 0.1016)
			(type default)
		)
		(layer "In4.Cu")
	)
	(gr_line
		(start 387.287262 -1.395984)
		(end 387.287262 -4.062984)
		(stroke
			(width 0.1016)
			(type default)
		)
		(layer "In4.Cu")
	)
	(gr_line
		(start 387.287262 -1.395984)
		(end 388.481062 -1.395984)
		(stroke
			(width 0.1016)
			(type default)
		)
		(layer "In4.Cu")
	)
	(gr_line
		(start 387.312662 -12.512548)
		(end 387.312662 -9.921748)
		(stroke
			(width 0.1016)
			(type default)
		)
		(layer "In4.Cu")
	)
	(gr_line
		(start 387.312662 -12.412472)
		(end 387.312662 -9.821672)
		(stroke
			(width 0.1016)
			(type default)
		)
		(layer "In4.Cu")
	)
	(gr_line
		(start 387.312662 -9.921748)
		(end 388.455662 -9.921748)
		(stroke
			(width 0.1016)
			(type default)
		)
		(layer "In4.Cu")
	)
	(gr_line
		(start 387.312662 -9.821672)
		(end 388.455662 -9.821672)
		(stroke
			(width 0.1016)
			(type default)
		)
		(layer "In4.Cu")
	)
	(gr_line
		(start 387.312662 -8.312404)
		(end 387.312662 -5.721604)
		(stroke
			(width 0.1016)
			(type default)
		)
		(layer "In4.Cu")
	)
	(gr_line
		(start 387.312662 -8.212328)
		(end 387.312662 -5.621528)
		(stroke
			(width 0.1016)
			(type default)
		)
		(layer "In4.Cu")
	)
	(gr_line
		(start 387.312662 -5.721604)
		(end 388.455662 -5.721604)
		(stroke
			(width 0.1016)
			(type default)
		)
		(layer "In4.Cu")
	)
	(gr_line
		(start 387.312662 -5.621528)
		(end 388.455662 -5.621528)
		(stroke
			(width 0.1016)
			(type default)
		)
		(layer "In4.Cu")
	)
	(gr_line
		(start 387.312662 -4.11226)
		(end 387.312662 -1.52146)
		(stroke
			(width 0.1016)
			(type default)
		)
		(layer "In4.Cu")
	)
	(gr_line
		(start 387.312662 -4.012184)
		(end 387.312662 -1.421384)
		(stroke
			(width 0.1016)
			(type default)
		)
		(layer "In4.Cu")
	)
	(gr_line
		(start 387.312662 -1.52146)
		(end 388.455662 -1.52146)
		(stroke
			(width 0.1016)
			(type default)
		)
		(layer "In4.Cu")
	)
	(gr_line
		(start 387.312662 -1.421384)
		(end 388.455662 -1.421384)
		(stroke
			(width 0.1016)
			(type default)
		)
		(layer "In4.Cu")
	)
	(gr_line
		(start 387.338062 -12.512548)
		(end 387.338062 -9.947148)
		(stroke
			(width 0.1016)
			(type default)
		)
		(layer "In4.Cu")
	)
	(gr_line
		(start 387.338062 -12.412472)
		(end 387.338062 -9.847072)
		(stroke
			(width 0.1016)
			(type default)
		)
		(layer "In4.Cu")
	)
	(gr_line
		(start 387.338062 -9.947148)
		(end 387.592062 -9.947148)
		(stroke
			(width 0.1016)
			(type default)
		)
		(layer "In4.Cu")
	)
	(gr_line
		(start 387.338062 -9.847072)
		(end 387.592062 -9.847072)
		(stroke
			(width 0.1016)
			(type default)
		)
		(layer "In4.Cu")
	)
	(gr_line
		(start 387.338062 -8.312404)
		(end 387.338062 -5.747004)
		(stroke
			(width 0.1016)
			(type default)
		)
		(layer "In4.Cu")
	)
	(gr_line
		(start 387.338062 -8.212328)
		(end 387.338062 -5.646928)
		(stroke
			(width 0.1016)
			(type default)
		)
		(layer "In4.Cu")
	)
	(gr_line
		(start 387.338062 -5.747004)
		(end 387.592062 -5.747004)
		(stroke
			(width 0.1016)
			(type default)
		)
		(layer "In4.Cu")
	)
	(gr_line
		(start 387.338062 -5.646928)
		(end 387.592062 -5.646928)
		(stroke
			(width 0.1016)
			(type default)
		)
		(layer "In4.Cu")
	)
	(gr_line
		(start 387.338062 -4.11226)
		(end 387.338062 -1.54686)
		(stroke
			(width 0.1016)
			(type default)
		)
		(layer "In4.Cu")
	)
	(gr_line
		(start 387.338062 -4.012184)
		(end 387.338062 -1.446784)
		(stroke
			(width 0.1016)
			(type default)
		)
		(layer "In4.Cu")
	)
	(gr_line
		(start 387.338062 -1.54686)
		(end 387.592062 -1.54686)
		(stroke
			(width 0.1016)
			(type default)
		)
		(layer "In4.Cu")
	)
	(gr_line
		(start 387.338062 -1.446784)
		(end 387.592062 -1.446784)
		(stroke
			(width 0.1016)
			(type default)
		)
		(layer "In4.Cu")
	)
	(gr_line
		(start 387.363462 -12.512548)
		(end 387.363462 -9.947148)
		(stroke
			(width 0.2032)
			(type default)
		)
		(layer "In4.Cu")
	)
	(gr_line
		(start 387.363462 -12.412472)
		(end 387.363462 -9.847072)
		(stroke
			(width 0.2032)
			(type default)
		)
		(layer "In4.Cu")
	)
	(gr_line
		(start 387.363462 -9.947148)
		(end 388.379462 -9.947148)
		(stroke
			(width 0.2032)
			(type default)
		)
		(layer "In4.Cu")
	)
	(gr_line
		(start 387.363462 -9.847072)
		(end 388.379462 -9.847072)
		(stroke
			(width 0.2032)
			(type default)
		)
		(layer "In4.Cu")
	)
	(gr_line
		(start 387.363462 -8.312404)
		(end 387.363462 -5.747004)
		(stroke
			(width 0.2032)
			(type default)
		)
		(layer "In4.Cu")
	)
	(gr_line
		(start 387.363462 -8.212328)
		(end 387.363462 -5.646928)
		(stroke
			(width 0.2032)
			(type default)
		)
		(layer "In4.Cu")
	)
	(gr_line
		(start 387.363462 -5.747004)
		(end 388.379462 -5.747004)
		(stroke
			(width 0.2032)
			(type default)
		)
		(layer "In4.Cu")
	)
	(gr_line
		(start 387.363462 -5.646928)
		(end 388.379462 -5.646928)
		(stroke
			(width 0.2032)
			(type default)
		)
		(layer "In4.Cu")
	)
	(gr_line
		(start 387.363462 -4.11226)
		(end 387.363462 -1.54686)
		(stroke
			(width 0.2032)
			(type default)
		)
		(layer "In4.Cu")
	)
	(gr_line
		(start 387.363462 -4.012184)
		(end 387.363462 -1.446784)
		(stroke
			(width 0.2032)
			(type default)
		)
		(layer "In4.Cu")
	)
	(gr_line
		(start 387.363462 -1.54686)
		(end 388.379462 -1.54686)
		(stroke
			(width 0.2032)
			(type default)
		)
		(layer "In4.Cu")
	)
	(gr_line
		(start 387.363462 -1.446784)
		(end 388.379462 -1.446784)
		(stroke
			(width 0.2032)
			(type default)
		)
		(layer "In4.Cu")
	)
	(gr_line
		(start 387.414262 -12.487148)
		(end 387.414262 -9.997948)
		(stroke
			(width 0.2032)
			(type default)
		)
		(layer "In4.Cu")
	)
	(gr_line
		(start 387.414262 -12.487148)
		(end 387.414262 -9.997948)
		(stroke
			(width 0.254)
			(type default)
		)
		(layer "In4.Cu")
	)
	(gr_line
		(start 387.414262 -12.387072)
		(end 387.414262 -9.897872)
		(stroke
			(width 0.2032)
			(type default)
		)
		(layer "In4.Cu")
	)
	(gr_line
		(start 387.414262 -12.387072)
		(end 387.414262 -9.897872)
		(stroke
			(width 0.254)
			(type default)
		)
		(layer "In4.Cu")
	)
	(gr_line
		(start 387.414262 -9.997948)
		(end 387.617462 -9.997948)
		(stroke
			(width 0.2032)
			(type default)
		)
		(layer "In4.Cu")
	)
	(gr_line
		(start 387.414262 -9.997948)
		(end 388.303262 -9.997948)
		(stroke
			(width 0.254)
			(type default)
		)
		(layer "In4.Cu")
	)
	(gr_line
		(start 387.414262 -9.897872)
		(end 387.617462 -9.897872)
		(stroke
			(width 0.2032)
			(type default)
		)
		(layer "In4.Cu")
	)
	(gr_line
		(start 387.414262 -9.897872)
		(end 388.303262 -9.897872)
		(stroke
			(width 0.254)
			(type default)
		)
		(layer "In4.Cu")
	)
	(gr_line
		(start 387.414262 -8.287004)
		(end 387.414262 -5.797804)
		(stroke
			(width 0.2032)
			(type default)
		)
		(layer "In4.Cu")
	)
	(gr_line
		(start 387.414262 -8.287004)
		(end 387.414262 -5.797804)
		(stroke
			(width 0.254)
			(type default)
		)
		(layer "In4.Cu")
	)
	(gr_line
		(start 387.414262 -8.186928)
		(end 387.414262 -5.697728)
		(stroke
			(width 0.2032)
			(type default)
		)
		(layer "In4.Cu")
	)
	(gr_line
		(start 387.414262 -8.186928)
		(end 387.414262 -5.697728)
		(stroke
			(width 0.254)
			(type default)
		)
		(layer "In4.Cu")
	)
	(gr_line
		(start 387.414262 -5.797804)
		(end 387.617462 -5.797804)
		(stroke
			(width 0.2032)
			(type default)
		)
		(layer "In4.Cu")
	)
	(gr_line
		(start 387.414262 -5.797804)
		(end 388.303262 -5.797804)
		(stroke
			(width 0.254)
			(type default)
		)
		(layer "In4.Cu")
	)
	(gr_line
		(start 387.414262 -5.697728)
		(end 387.617462 -5.697728)
		(stroke
			(width 0.2032)
			(type default)
		)
		(layer "In4.Cu")
	)
	(gr_line
		(start 387.414262 -5.697728)
		(end 388.303262 -5.697728)
		(stroke
			(width 0.254)
			(type default)
		)
		(layer "In4.Cu")
	)
	(gr_line
		(start 387.414262 -4.08686)
		(end 387.414262 -1.59766)
		(stroke
			(width 0.2032)
			(type default)
		)
		(layer "In4.Cu")
	)
	(gr_line
		(start 387.414262 -4.08686)
		(end 387.414262 -1.59766)
		(stroke
			(width 0.254)
			(type default)
		)
		(layer "In4.Cu")
	)
	(gr_line
		(start 387.414262 -3.986784)
		(end 387.414262 -1.497584)
		(stroke
			(width 0.2032)
			(type default)
		)
		(layer "In4.Cu")
	)
	(gr_line
		(start 387.414262 -3.986784)
		(end 387.414262 -1.497584)
		(stroke
			(width 0.254)
			(type default)
		)
		(layer "In4.Cu")
	)
	(gr_line
		(start 387.414262 -1.59766)
		(end 387.617462 -1.59766)
		(stroke
			(width 0.2032)
			(type default)
		)
		(layer "In4.Cu")
	)
	(gr_line
		(start 387.414262 -1.59766)
		(end 388.303262 -1.59766)
		(stroke
			(width 0.254)
			(type default)
		)
		(layer "In4.Cu")
	)
	(gr_line
		(start 387.414262 -1.497584)
		(end 387.617462 -1.497584)
		(stroke
			(width 0.2032)
			(type default)
		)
		(layer "In4.Cu")
	)
	(gr_line
		(start 387.414262 -1.497584)
		(end 388.303262 -1.497584)
		(stroke
			(width 0.254)
			(type default)
		)
		(layer "In4.Cu")
	)
	(gr_line
		(start 387.439662 -12.461748)
		(end 387.439662 -10.023348)
		(stroke
			(width 0.254)
			(type default)
		)
		(layer "In4.Cu")
	)
	(gr_line
		(start 387.439662 -12.361672)
		(end 387.439662 -9.923272)
		(stroke
			(width 0.254)
			(type default)
		)
		(layer "In4.Cu")
	)
	(gr_line
		(start 387.439662 -10.023348)
		(end 388.277862 -10.023348)
		(stroke
			(width 0.254)
			(type default)
		)
		(layer "In4.Cu")
	)
	(gr_line
		(start 387.439662 -9.923272)
		(end 388.277862 -9.923272)
		(stroke
			(width 0.254)
			(type default)
		)
		(layer "In4.Cu")
	)
	(gr_line
		(start 387.439662 -8.261604)
		(end 387.439662 -5.823204)
		(stroke
			(width 0.254)
			(type default)
		)
		(layer "In4.Cu")
	)
	(gr_line
		(start 387.439662 -8.161528)
		(end 387.439662 -5.723128)
		(stroke
			(width 0.254)
			(type default)
		)
		(layer "In4.Cu")
	)
	(gr_line
		(start 387.439662 -5.823204)
		(end 388.277862 -5.823204)
		(stroke
			(width 0.254)
			(type default)
		)
		(layer "In4.Cu")
	)
	(gr_line
		(start 387.439662 -5.723128)
		(end 388.277862 -5.723128)
		(stroke
			(width 0.254)
			(type default)
		)
		(layer "In4.Cu")
	)
	(gr_line
		(start 387.439662 -4.06146)
		(end 387.439662 -1.62306)
		(stroke
			(width 0.254)
			(type default)
		)
		(layer "In4.Cu")
	)
	(gr_line
		(start 387.439662 -3.961384)
		(end 387.439662 -1.522984)
		(stroke
			(width 0.254)
			(type default)
		)
		(layer "In4.Cu")
	)
	(gr_line
		(start 387.439662 -1.62306)
		(end 388.277862 -1.62306)
		(stroke
			(width 0.254)
			(type default)
		)
		(layer "In4.Cu")
	)
	(gr_line
		(start 387.439662 -1.522984)
		(end 388.277862 -1.522984)
		(stroke
			(width 0.254)
			(type default)
		)
		(layer "In4.Cu")
	)
	(gr_line
		(start 387.465062 -12.436348)
		(end 387.465062 -10.048748)
		(stroke
			(width 0.254)
			(type default)
		)
		(layer "In4.Cu")
	)
	(gr_line
		(start 387.465062 -12.336272)
		(end 387.465062 -9.948672)
		(stroke
			(width 0.254)
			(type default)
		)
		(layer "In4.Cu")
	)
	(gr_line
		(start 387.465062 -10.048748)
		(end 388.252462 -10.048748)
		(stroke
			(width 0.254)
			(type default)
		)
		(layer "In4.Cu")
	)
	(gr_line
		(start 387.465062 -9.948672)
		(end 388.252462 -9.948672)
		(stroke
			(width 0.254)
			(type default)
		)
		(layer "In4.Cu")
	)
	(gr_line
		(start 387.465062 -8.236204)
		(end 387.465062 -5.848604)
		(stroke
			(width 0.254)
			(type default)
		)
		(layer "In4.Cu")
	)
	(gr_line
		(start 387.465062 -8.136128)
		(end 387.465062 -5.748528)
		(stroke
			(width 0.254)
			(type default)
		)
		(layer "In4.Cu")
	)
	(gr_line
		(start 387.465062 -5.848604)
		(end 388.252462 -5.848604)
		(stroke
			(width 0.254)
			(type default)
		)
		(layer "In4.Cu")
	)
	(gr_line
		(start 387.465062 -5.748528)
		(end 388.252462 -5.748528)
		(stroke
			(width 0.254)
			(type default)
		)
		(layer "In4.Cu")
	)
	(gr_line
		(start 387.465062 -4.03606)
		(end 387.465062 -1.64846)
		(stroke
			(width 0.254)
			(type default)
		)
		(layer "In4.Cu")
	)
	(gr_line
		(start 387.465062 -3.935984)
		(end 387.465062 -1.548384)
		(stroke
			(width 0.254)
			(type default)
		)
		(layer "In4.Cu")
	)
	(gr_line
		(start 387.465062 -1.64846)
		(end 388.252462 -1.64846)
		(stroke
			(width 0.254)
			(type default)
		)
		(layer "In4.Cu")
	)
	(gr_line
		(start 387.465062 -1.548384)
		(end 388.252462 -1.548384)
		(stroke
			(width 0.254)
			(type default)
		)
		(layer "In4.Cu")
	)
	(gr_line
		(start 387.490462 -12.360148)
		(end 388.125462 -12.360148)
		(stroke
			(width 0.508)
			(type default)
		)
		(layer "In4.Cu")
	)
	(gr_line
		(start 387.490462 -12.260072)
		(end 388.125462 -12.260072)
		(stroke
			(width 0.508)
			(type default)
		)
		(layer "In4.Cu")
	)
	(gr_line
		(start 387.490462 -10.175748)
		(end 388.125462 -10.175748)
		(stroke
			(width 0.508)
			(type default)
		)
		(layer "In4.Cu")
	)
	(gr_line
		(start 387.490462 -10.124948)
		(end 388.125462 -10.124948)
		(stroke
			(width 0.508)
			(type default)
		)
		(layer "In4.Cu")
	)
	(gr_line
		(start 387.490462 -10.075672)
		(end 388.125462 -10.075672)
		(stroke
			(width 0.508)
			(type default)
		)
		(layer "In4.Cu")
	)
	(gr_line
		(start 387.490462 -10.024872)
		(end 388.125462 -10.024872)
		(stroke
			(width 0.508)
			(type default)
		)
		(layer "In4.Cu")
	)
	(gr_line
		(start 387.490462 -8.160004)
		(end 388.125462 -8.160004)
		(stroke
			(width 0.508)
			(type default)
		)
		(layer "In4.Cu")
	)
	(gr_line
		(start 387.490462 -8.059928)
		(end 388.125462 -8.059928)
		(stroke
			(width 0.508)
			(type default)
		)
		(layer "In4.Cu")
	)
	(gr_line
		(start 387.490462 -5.975604)
		(end 388.125462 -5.975604)
		(stroke
			(width 0.508)
			(type default)
		)
		(layer "In4.Cu")
	)
	(gr_line
		(start 387.490462 -5.924804)
		(end 388.125462 -5.924804)
		(stroke
			(width 0.508)
			(type default)
		)
		(layer "In4.Cu")
	)
	(gr_line
		(start 387.490462 -5.875528)
		(end 388.125462 -5.875528)
		(stroke
			(width 0.508)
			(type default)
		)
		(layer "In4.Cu")
	)
	(gr_line
		(start 387.490462 -5.824728)
		(end 388.125462 -5.824728)
		(stroke
			(width 0.508)
			(type default)
		)
		(layer "In4.Cu")
	)
	(gr_line
		(start 387.490462 -3.95986)
		(end 388.125462 -3.95986)
		(stroke
			(width 0.508)
			(type default)
		)
		(layer "In4.Cu")
	)
	(gr_line
		(start 387.490462 -3.859784)
		(end 388.125462 -3.859784)
		(stroke
			(width 0.508)
			(type default)
		)
		(layer "In4.Cu")
	)
	(gr_line
		(start 387.490462 -1.77546)
		(end 388.125462 -1.77546)
		(stroke
			(width 0.508)
			(type default)
		)
		(layer "In4.Cu")
	)
	(gr_line
		(start 387.490462 -1.72466)
		(end 388.125462 -1.72466)
		(stroke
			(width 0.508)
			(type default)
		)
		(layer "In4.Cu")
	)
	(gr_line
		(start 387.490462 -1.675384)
		(end 388.125462 -1.675384)
		(stroke
			(width 0.508)
			(type default)
		)
		(layer "In4.Cu")
	)
	(gr_line
		(start 387.490462 -1.624584)
		(end 388.125462 -1.624584)
		(stroke
			(width 0.508)
			(type default)
		)
		(layer "In4.Cu")
	)
	(gr_line
		(start 387.515862 -10.429748)
		(end 388.150862 -10.429748)
		(stroke
			(width 0.508)
			(type default)
		)
		(layer "In4.Cu")
	)
	(gr_line
		(start 387.515862 -10.329672)
		(end 388.150862 -10.329672)
		(stroke
			(width 0.508)
			(type default)
		)
		(layer "In4.Cu")
	)
	(gr_line
		(start 387.515862 -6.229604)
		(end 388.150862 -6.229604)
		(stroke
			(width 0.508)
			(type default)
		)
		(layer "In4.Cu")
	)
	(gr_line
		(start 387.515862 -6.129528)
		(end 388.150862 -6.129528)
		(stroke
			(width 0.508)
			(type default)
		)
		(layer "In4.Cu")
	)
	(gr_line
		(start 387.515862 -2.02946)
		(end 388.150862 -2.02946)
		(stroke
			(width 0.508)
			(type default)
		)
		(layer "In4.Cu")
	)
	(gr_line
		(start 387.515862 -1.929384)
		(end 388.150862 -1.929384)
		(stroke
			(width 0.508)
			(type default)
		)
		(layer "In4.Cu")
	)
	(gr_line
		(start 387.541262 -12.385548)
		(end 387.541262 -10.124948)
		(stroke
			(width 0.254)
			(type default)
		)
		(layer "In4.Cu")
	)
	(gr_line
		(start 387.541262 -12.285472)
		(end 387.541262 -10.024872)
		(stroke
			(width 0.254)
			(type default)
		)
		(layer "In4.Cu")
	)
	(gr_line
		(start 387.541262 -12.233148)
		(end 388.176262 -12.233148)
		(stroke
			(width 0.508)
			(type default)
		)
		(layer "In4.Cu")
	)
	(gr_line
		(start 387.541262 -12.133072)
		(end 388.176262 -12.133072)
		(stroke
			(width 0.508)
			(type default)
		)
		(layer "In4.Cu")
	)
	(gr_line
		(start 387.541262 -10.124948)
		(end 388.176262 -10.124948)
		(stroke
			(width 0.254)
			(type default)
		)
		(layer "In4.Cu")
	)
	(gr_line
		(start 387.541262 -10.024872)
		(end 388.176262 -10.024872)
		(stroke
			(width 0.254)
			(type default)
		)
		(layer "In4.Cu")
	)
	(gr_line
		(start 387.541262 -8.185404)
		(end 387.541262 -5.924804)
		(stroke
			(width 0.254)
			(type default)
		)
		(layer "In4.Cu")
	)
	(gr_line
		(start 387.541262 -8.085328)
		(end 387.541262 -5.824728)
		(stroke
			(width 0.254)
			(type default)
		)
		(layer "In4.Cu")
	)
	(gr_line
		(start 387.541262 -8.033004)
		(end 388.176262 -8.033004)
		(stroke
			(width 0.508)
			(type default)
		)
		(layer "In4.Cu")
	)
	(gr_line
		(start 387.541262 -7.932928)
		(end 388.176262 -7.932928)
		(stroke
			(width 0.508)
			(type default)
		)
		(layer "In4.Cu")
	)
	(gr_line
		(start 387.541262 -5.924804)
		(end 388.176262 -5.924804)
		(stroke
			(width 0.254)
			(type default)
		)
		(layer "In4.Cu")
	)
	(gr_line
		(start 387.541262 -5.824728)
		(end 388.176262 -5.824728)
		(stroke
			(width 0.254)
			(type default)
		)
		(layer "In4.Cu")
	)
	(gr_line
		(start 387.541262 -3.98526)
		(end 387.541262 -1.72466)
		(stroke
			(width 0.254)
			(type default)
		)
		(layer "In4.Cu")
	)
	(gr_line
		(start 387.541262 -3.885184)
		(end 387.541262 -1.624584)
		(stroke
			(width 0.254)
			(type default)
		)
		(layer "In4.Cu")
	)
	(gr_line
		(start 387.541262 -3.83286)
		(end 388.176262 -3.83286)
		(stroke
			(width 0.508)
			(type default)
		)
		(layer "In4.Cu")
	)
	(gr_line
		(start 387.541262 -3.732784)
		(end 388.176262 -3.732784)
		(stroke
			(width 0.508)
			(type default)
		)
		(layer "In4.Cu")
	)
	(gr_line
		(start 387.541262 -1.72466)
		(end 388.176262 -1.72466)
		(stroke
			(width 0.254)
			(type default)
		)
		(layer "In4.Cu")
	)
	(gr_line
		(start 387.541262 -1.624584)
		(end 388.176262 -1.624584)
		(stroke
			(width 0.254)
			(type default)
		)
		(layer "In4.Cu")
	)
	(gr_line
		(start 387.566662 -12.080748)
		(end 388.201662 -12.080748)
		(stroke
			(width 0.508)
			(type default)
		)
		(layer "In4.Cu")
	)
	(gr_line
		(start 387.566662 -11.980672)
		(end 388.201662 -11.980672)
		(stroke
			(width 0.508)
			(type default)
		)
		(layer "In4.Cu")
	)
	(gr_line
		(start 387.566662 -7.880604)
		(end 388.201662 -7.880604)
		(stroke
			(width 0.508)
			(type default)
		)
		(layer "In4.Cu")
	)
	(gr_line
		(start 387.566662 -7.780528)
		(end 388.201662 -7.780528)
		(stroke
			(width 0.508)
			(type default)
		)
		(layer "In4.Cu")
	)
	(gr_line
		(start 387.566662 -3.68046)
		(end 388.201662 -3.68046)
		(stroke
			(width 0.508)
			(type default)
		)
		(layer "In4.Cu")
	)
	(gr_line
		(start 387.566662 -3.580384)
		(end 388.201662 -3.580384)
		(stroke
			(width 0.508)
			(type default)
		)
		(layer "In4.Cu")
	)
	(gr_line
		(start 387.592062 -12.360148)
		(end 388.227062 -12.360148)
		(stroke
			(width 0.508)
			(type default)
		)
		(layer "In4.Cu")
	)
	(gr_line
		(start 387.592062 -12.260072)
		(end 388.227062 -12.260072)
		(stroke
			(width 0.508)
			(type default)
		)
		(layer "In4.Cu")
	)
	(gr_line
		(start 387.592062 -9.947148)
		(end 388.430262 -9.947148)
		(stroke
			(width 0.2032)
			(type default)
		)
		(layer "In4.Cu")
	)
	(gr_line
		(start 387.592062 -9.847072)
		(end 388.430262 -9.847072)
		(stroke
			(width 0.2032)
			(type default)
		)
		(layer "In4.Cu")
	)
	(gr_line
		(start 387.592062 -8.160004)
		(end 388.227062 -8.160004)
		(stroke
			(width 0.508)
			(type default)
		)
		(layer "In4.Cu")
	)
	(gr_line
		(start 387.592062 -8.059928)
		(end 388.227062 -8.059928)
		(stroke
			(width 0.508)
			(type default)
		)
		(layer "In4.Cu")
	)
	(gr_line
		(start 387.592062 -5.747004)
		(end 388.430262 -5.747004)
		(stroke
			(width 0.2032)
			(type default)
		)
		(layer "In4.Cu")
	)
	(gr_line
		(start 387.592062 -5.646928)
		(end 388.430262 -5.646928)
		(stroke
			(width 0.2032)
			(type default)
		)
		(layer "In4.Cu")
	)
	(gr_line
		(start 387.592062 -3.95986)
		(end 388.227062 -3.95986)
		(stroke
			(width 0.508)
			(type default)
		)
		(layer "In4.Cu")
	)
	(gr_line
		(start 387.592062 -3.859784)
		(end 388.227062 -3.859784)
		(stroke
			(width 0.508)
			(type default)
		)
		(layer "In4.Cu")
	)
	(gr_line
		(start 387.592062 -1.54686)
		(end 388.430262 -1.54686)
		(stroke
			(width 0.2032)
			(type default)
		)
		(layer "In4.Cu")
	)
	(gr_line
		(start 387.592062 -1.446784)
		(end 388.430262 -1.446784)
		(stroke
			(width 0.2032)
			(type default)
		)
		(layer "In4.Cu")
	)
	(gr_line
		(start 387.617462 -12.360148)
		(end 387.617462 -10.175748)
		(stroke
			(width 0.254)
			(type default)
		)
		(layer "In4.Cu")
	)
	(gr_line
		(start 387.617462 -12.260072)
		(end 387.617462 -10.075672)
		(stroke
			(width 0.254)
			(type default)
		)
		(layer "In4.Cu")
	)
	(gr_line
		(start 387.617462 -10.175748)
		(end 388.100062 -10.175748)
		(stroke
			(width 0.254)
			(type default)
		)
		(layer "In4.Cu")
	)
	(gr_line
		(start 387.617462 -10.075672)
		(end 388.100062 -10.075672)
		(stroke
			(width 0.254)
			(type default)
		)
		(layer "In4.Cu")
	)
	(gr_line
		(start 387.617462 -9.997948)
		(end 388.354062 -9.997948)
		(stroke
			(width 0.254)
			(type default)
		)
		(layer "In4.Cu")
	)
	(gr_line
		(start 387.617462 -9.897872)
		(end 388.354062 -9.897872)
		(stroke
			(width 0.254)
			(type default)
		)
		(layer "In4.Cu")
	)
	(gr_line
		(start 387.617462 -8.160004)
		(end 387.617462 -5.975604)
		(stroke
			(width 0.254)
			(type default)
		)
		(layer "In4.Cu")
	)
	(gr_line
		(start 387.617462 -8.059928)
		(end 387.617462 -5.875528)
		(stroke
			(width 0.254)
			(type default)
		)
		(layer "In4.Cu")
	)
	(gr_line
		(start 387.617462 -5.975604)
		(end 388.100062 -5.975604)
		(stroke
			(width 0.254)
			(type default)
		)
		(layer "In4.Cu")
	)
	(gr_line
		(start 387.617462 -5.875528)
		(end 388.100062 -5.875528)
		(stroke
			(width 0.254)
			(type default)
		)
		(layer "In4.Cu")
	)
	(gr_line
		(start 387.617462 -5.797804)
		(end 388.354062 -5.797804)
		(stroke
			(width 0.254)
			(type default)
		)
		(layer "In4.Cu")
	)
	(gr_line
		(start 387.617462 -5.697728)
		(end 388.354062 -5.697728)
		(stroke
			(width 0.254)
			(type default)
		)
		(layer "In4.Cu")
	)
	(gr_line
		(start 387.617462 -3.95986)
		(end 387.617462 -1.77546)
		(stroke
			(width 0.254)
			(type default)
		)
		(layer "In4.Cu")
	)
	(gr_line
		(start 387.617462 -3.859784)
		(end 387.617462 -1.675384)
		(stroke
			(width 0.254)
			(type default)
		)
		(layer "In4.Cu")
	)
	(gr_line
		(start 387.617462 -1.77546)
		(end 388.100062 -1.77546)
		(stroke
			(width 0.254)
			(type default)
		)
		(layer "In4.Cu")
	)
	(gr_line
		(start 387.617462 -1.675384)
		(end 388.100062 -1.675384)
		(stroke
			(width 0.254)
			(type default)
		)
		(layer "In4.Cu")
	)
	(gr_line
		(start 387.617462 -1.59766)
		(end 388.354062 -1.59766)
		(stroke
			(width 0.254)
			(type default)
		)
		(layer "In4.Cu")
	)
	(gr_line
		(start 387.617462 -1.497584)
		(end 388.354062 -1.497584)
		(stroke
			(width 0.254)
			(type default)
		)
		(layer "In4.Cu")
	)
	(gr_line
		(start 387.636004 -10.110978)
		(end 388.271004 -10.110978)
		(stroke
			(width 0.508)
			(type default)
		)
		(layer "In4.Cu")
	)
	(gr_line
		(start 387.636004 -10.010902)
		(end 388.271004 -10.010902)
		(stroke
			(width 0.508)
			(type default)
		)
		(layer "In4.Cu")
	)
	(gr_line
		(start 387.636004 -5.910834)
		(end 388.271004 -5.910834)
		(stroke
			(width 0.508)
			(type default)
		)
		(layer "In4.Cu")
	)
	(gr_line
		(start 387.636004 -5.810758)
		(end 388.271004 -5.810758)
		(stroke
			(width 0.508)
			(type default)
		)
		(layer "In4.Cu")
	)
	(gr_line
		(start 387.636004 -1.71069)
		(end 388.271004 -1.71069)
		(stroke
			(width 0.508)
			(type default)
		)
		(layer "In4.Cu")
	)
	(gr_line
		(start 387.636004 -1.610614)
		(end 388.271004 -1.610614)
		(stroke
			(width 0.508)
			(type default)
		)
		(layer "In4.Cu")
	)
	(gr_line
		(start 387.642862 -12.360148)
		(end 388.277862 -12.360148)
		(stroke
			(width 0.508)
			(type default)
		)
		(layer "In4.Cu")
	)
	(gr_line
		(start 387.642862 -12.260072)
		(end 388.277862 -12.260072)
		(stroke
			(width 0.508)
			(type default)
		)
		(layer "In4.Cu")
	)
	(gr_line
		(start 387.642862 -12.233148)
		(end 387.642862 -10.251948)
		(stroke
			(width 0.762)
			(type default)
		)
		(layer "In4.Cu")
	)
	(gr_line
		(start 387.642862 -12.133072)
		(end 387.642862 -10.151872)
		(stroke
			(width 0.762)
			(type default)
		)
		(layer "In4.Cu")
	)
	(gr_line
		(start 387.642862 -10.251948)
		(end 388.277862 -10.251948)
		(stroke
			(width 0.508)
			(type default)
		)
		(layer "In4.Cu")
	)
	(gr_line
		(start 387.642862 -10.151872)
		(end 388.277862 -10.151872)
		(stroke
			(width 0.508)
			(type default)
		)
		(layer "In4.Cu")
	)
	(gr_line
		(start 387.642862 -8.160004)
		(end 388.277862 -8.160004)
		(stroke
			(width 0.508)
			(type default)
		)
		(layer "In4.Cu")
	)
	(gr_line
		(start 387.642862 -8.059928)
		(end 388.277862 -8.059928)
		(stroke
			(width 0.508)
			(type default)
		)
		(layer "In4.Cu")
	)
	(gr_line
		(start 387.642862 -8.033004)
		(end 387.642862 -6.051804)
		(stroke
			(width 0.762)
			(type default)
		)
		(layer "In4.Cu")
	)
	(gr_line
		(start 387.642862 -7.932928)
		(end 387.642862 -5.951728)
		(stroke
			(width 0.762)
			(type default)
		)
		(layer "In4.Cu")
	)
	(gr_line
		(start 387.642862 -6.051804)
		(end 388.277862 -6.051804)
		(stroke
			(width 0.508)
			(type default)
		)
		(layer "In4.Cu")
	)
	(gr_line
		(start 387.642862 -5.951728)
		(end 388.277862 -5.951728)
		(stroke
			(width 0.508)
			(type default)
		)
		(layer "In4.Cu")
	)
	(gr_line
		(start 387.642862 -3.95986)
		(end 388.277862 -3.95986)
		(stroke
			(width 0.508)
			(type default)
		)
		(layer "In4.Cu")
	)
	(gr_line
		(start 387.642862 -3.859784)
		(end 388.277862 -3.859784)
		(stroke
			(width 0.508)
			(type default)
		)
		(layer "In4.Cu")
	)
	(gr_line
		(start 387.642862 -3.83286)
		(end 387.642862 -1.85166)
		(stroke
			(width 0.762)
			(type default)
		)
		(layer "In4.Cu")
	)
	(gr_line
		(start 387.642862 -3.732784)
		(end 387.642862 -1.751584)
		(stroke
			(width 0.762)
			(type default)
		)
		(layer "In4.Cu")
	)
	(gr_line
		(start 387.642862 -1.85166)
		(end 388.277862 -1.85166)
		(stroke
			(width 0.508)
			(type default)
		)
		(layer "In4.Cu")
	)
	(gr_line
		(start 387.642862 -1.751584)
		(end 388.277862 -1.751584)
		(stroke
			(width 0.508)
			(type default)
		)
		(layer "In4.Cu")
	)
	(gr_line
		(start 387.693662 -12.283948)
		(end 387.693662 -10.251948)
		(stroke
			(width 0.254)
			(type default)
		)
		(layer "In4.Cu")
	)
	(gr_line
		(start 387.693662 -12.183872)
		(end 387.693662 -10.151872)
		(stroke
			(width 0.254)
			(type default)
		)
		(layer "In4.Cu")
	)
	(gr_line
		(start 387.693662 -10.251948)
		(end 388.023862 -10.251948)
		(stroke
			(width 0.254)
			(type default)
		)
		(layer "In4.Cu")
	)
	(gr_line
		(start 387.693662 -10.151872)
		(end 388.023862 -10.151872)
		(stroke
			(width 0.254)
			(type default)
		)
		(layer "In4.Cu")
	)
	(gr_line
		(start 387.693662 -8.083804)
		(end 387.693662 -6.051804)
		(stroke
			(width 0.254)
			(type default)
		)
		(layer "In4.Cu")
	)
	(gr_line
		(start 387.693662 -7.983728)
		(end 387.693662 -5.951728)
		(stroke
			(width 0.254)
			(type default)
		)
		(layer "In4.Cu")
	)
	(gr_line
		(start 387.693662 -6.051804)
		(end 388.023862 -6.051804)
		(stroke
			(width 0.254)
			(type default)
		)
		(layer "In4.Cu")
	)
	(gr_line
		(start 387.693662 -5.951728)
		(end 388.023862 -5.951728)
		(stroke
			(width 0.254)
			(type default)
		)
		(layer "In4.Cu")
	)
	(gr_line
		(start 387.693662 -3.88366)
		(end 387.693662 -1.85166)
		(stroke
			(width 0.254)
			(type default)
		)
		(layer "In4.Cu")
	)
	(gr_line
		(start 387.693662 -3.783584)
		(end 387.693662 -1.751584)
		(stroke
			(width 0.254)
			(type default)
		)
		(layer "In4.Cu")
	)
	(gr_line
		(start 387.693662 -1.85166)
		(end 388.023862 -1.85166)
		(stroke
			(width 0.254)
			(type default)
		)
		(layer "In4.Cu")
	)
	(gr_line
		(start 387.693662 -1.751584)
		(end 388.023862 -1.751584)
		(stroke
			(width 0.254)
			(type default)
		)
		(layer "In4.Cu")
	)
	(gr_line
		(start 387.795262 -12.207748)
		(end 387.795262 -10.404348)
		(stroke
			(width 0.254)
			(type default)
		)
		(layer "In4.Cu")
	)
	(gr_line
		(start 387.795262 -12.207748)
		(end 387.795262 -10.226548)
		(stroke
			(width 0.762)
			(type default)
		)
		(layer "In4.Cu")
	)
	(gr_line
		(start 387.795262 -12.107672)
		(end 387.795262 -10.304272)
		(stroke
			(width 0.254)
			(type default)
		)
		(layer "In4.Cu")
	)
	(gr_line
		(start 387.795262 -12.107672)
		(end 387.795262 -10.126472)
		(stroke
			(width 0.762)
			(type default)
		)
		(layer "In4.Cu")
	)
	(gr_line
		(start 387.795262 -10.404348)
		(end 387.896862 -10.404348)
		(stroke
			(width 0.254)
			(type default)
		)
		(layer "In4.Cu")
	)
	(gr_line
		(start 387.795262 -10.304272)
		(end 387.896862 -10.304272)
		(stroke
			(width 0.254)
			(type default)
		)
		(layer "In4.Cu")
	)
	(gr_line
		(start 387.795262 -8.007604)
		(end 387.795262 -6.204204)
		(stroke
			(width 0.254)
			(type default)
		)
		(layer "In4.Cu")
	)
	(gr_line
		(start 387.795262 -8.007604)
		(end 387.795262 -6.026404)
		(stroke
			(width 0.762)
			(type default)
		)
		(layer "In4.Cu")
	)
	(gr_line
		(start 387.795262 -7.907528)
		(end 387.795262 -6.104128)
		(stroke
			(width 0.254)
			(type default)
		)
		(layer "In4.Cu")
	)
	(gr_line
		(start 387.795262 -7.907528)
		(end 387.795262 -5.926328)
		(stroke
			(width 0.762)
			(type default)
		)
		(layer "In4.Cu")
	)
	(gr_line
		(start 387.795262 -6.204204)
		(end 387.896862 -6.204204)
		(stroke
			(width 0.254)
			(type default)
		)
		(layer "In4.Cu")
	)
	(gr_line
		(start 387.795262 -6.104128)
		(end 387.896862 -6.104128)
		(stroke
			(width 0.254)
			(type default)
		)
		(layer "In4.Cu")
	)
	(gr_line
		(start 387.795262 -3.80746)
		(end 387.795262 -2.00406)
		(stroke
			(width 0.254)
			(type default)
		)
		(layer "In4.Cu")
	)
	(gr_line
		(start 387.795262 -3.80746)
		(end 387.795262 -1.82626)
		(stroke
			(width 0.762)
			(type default)
		)
		(layer "In4.Cu")
	)
	(gr_line
		(start 387.795262 -3.707384)
		(end 387.795262 -1.903984)
		(stroke
			(width 0.254)
			(type default)
		)
		(layer "In4.Cu")
	)
	(gr_line
		(start 387.795262 -3.707384)
		(end 387.795262 -1.726184)
		(stroke
			(width 0.762)
			(type default)
		)
		(layer "In4.Cu")
	)
	(gr_line
		(start 387.795262 -2.00406)
		(end 387.896862 -2.00406)
		(stroke
			(width 0.254)
			(type default)
		)
		(layer "In4.Cu")
	)
	(gr_line
		(start 387.795262 -1.903984)
		(end 387.896862 -1.903984)
		(stroke
			(width 0.254)
			(type default)
		)
		(layer "In4.Cu")
	)
	(gr_line
		(start 387.896862 -12.309348)
		(end 387.846062 -12.309348)
		(stroke
			(width 0.254)
			(type default)
		)
		(layer "In4.Cu")
	)
	(gr_line
		(start 387.896862 -12.209272)
		(end 387.846062 -12.209272)
		(stroke
			(width 0.254)
			(type default)
		)
		(layer "In4.Cu")
	)
	(gr_line
		(start 387.896862 -10.404348)
		(end 387.896862 -12.309348)
		(stroke
			(width 0.254)
			(type default)
		)
		(layer "In4.Cu")
	)
	(gr_line
		(start 387.896862 -10.304272)
		(end 387.896862 -12.209272)
		(stroke
			(width 0.254)
			(type default)
		)
		(layer "In4.Cu")
	)
	(gr_line
		(start 387.896862 -8.109204)
		(end 387.846062 -8.109204)
		(stroke
			(width 0.254)
			(type default)
		)
		(layer "In4.Cu")
	)
	(gr_line
		(start 387.896862 -8.009128)
		(end 387.846062 -8.009128)
		(stroke
			(width 0.254)
			(type default)
		)
		(layer "In4.Cu")
	)
	(gr_line
		(start 387.896862 -6.204204)
		(end 387.896862 -8.109204)
		(stroke
			(width 0.254)
			(type default)
		)
		(layer "In4.Cu")
	)
	(gr_line
		(start 387.896862 -6.104128)
		(end 387.896862 -8.009128)
		(stroke
			(width 0.254)
			(type default)
		)
		(layer "In4.Cu")
	)
	(gr_line
		(start 387.896862 -3.90906)
		(end 387.846062 -3.90906)
		(stroke
			(width 0.254)
			(type default)
		)
		(layer "In4.Cu")
	)
	(gr_line
		(start 387.896862 -3.808984)
		(end 387.846062 -3.808984)
		(stroke
			(width 0.254)
			(type default)
		)
		(layer "In4.Cu")
	)
	(gr_line
		(start 387.896862 -2.00406)
		(end 387.896862 -3.90906)
		(stroke
			(width 0.254)
			(type default)
		)
		(layer "In4.Cu")
	)
	(gr_line
		(start 387.896862 -1.903984)
		(end 387.896862 -3.808984)
		(stroke
			(width 0.254)
			(type default)
		)
		(layer "In4.Cu")
	)
	(gr_line
		(start 387.947662 -12.233148)
		(end 387.947662 -10.251948)
		(stroke
			(width 0.762)
			(type default)
		)
		(layer "In4.Cu")
	)
	(gr_line
		(start 387.947662 -12.133072)
		(end 387.947662 -10.151872)
		(stroke
			(width 0.762)
			(type default)
		)
		(layer "In4.Cu")
	)
	(gr_line
		(start 387.947662 -8.033004)
		(end 387.947662 -6.051804)
		(stroke
			(width 0.762)
			(type default)
		)
		(layer "In4.Cu")
	)
	(gr_line
		(start 387.947662 -7.932928)
		(end 387.947662 -5.951728)
		(stroke
			(width 0.762)
			(type default)
		)
		(layer "In4.Cu")
	)
	(gr_line
		(start 387.947662 -3.83286)
		(end 387.947662 -1.85166)
		(stroke
			(width 0.762)
			(type default)
		)
		(layer "In4.Cu")
	)
	(gr_line
		(start 387.947662 -3.732784)
		(end 387.947662 -1.751584)
		(stroke
			(width 0.762)
			(type default)
		)
		(layer "In4.Cu")
	)
	(gr_line
		(start 388.023862 -12.207748)
		(end 387.795262 -12.207748)
		(stroke
			(width 0.254)
			(type default)
		)
		(layer "In4.Cu")
	)
	(gr_line
		(start 388.023862 -12.107672)
		(end 387.795262 -12.107672)
		(stroke
			(width 0.254)
			(type default)
		)
		(layer "In4.Cu")
	)
	(gr_line
		(start 388.023862 -10.251948)
		(end 388.023862 -12.207748)
		(stroke
			(width 0.254)
			(type default)
		)
		(layer "In4.Cu")
	)
	(gr_line
		(start 388.023862 -10.151872)
		(end 388.023862 -12.107672)
		(stroke
			(width 0.254)
			(type default)
		)
		(layer "In4.Cu")
	)
	(gr_line
		(start 388.023862 -8.007604)
		(end 387.795262 -8.007604)
		(stroke
			(width 0.254)
			(type default)
		)
		(layer "In4.Cu")
	)
	(gr_line
		(start 388.023862 -7.907528)
		(end 387.795262 -7.907528)
		(stroke
			(width 0.254)
			(type default)
		)
		(layer "In4.Cu")
	)
	(gr_line
		(start 388.023862 -6.051804)
		(end 388.023862 -8.007604)
		(stroke
			(width 0.254)
			(type default)
		)
		(layer "In4.Cu")
	)
	(gr_line
		(start 388.023862 -5.951728)
		(end 388.023862 -7.907528)
		(stroke
			(width 0.254)
			(type default)
		)
		(layer "In4.Cu")
	)
	(gr_line
		(start 388.023862 -3.80746)
		(end 387.795262 -3.80746)
		(stroke
			(width 0.254)
			(type default)
		)
		(layer "In4.Cu")
	)
	(gr_line
		(start 388.023862 -3.707384)
		(end 387.795262 -3.707384)
		(stroke
			(width 0.254)
			(type default)
		)
		(layer "In4.Cu")
	)
	(gr_line
		(start 388.023862 -1.85166)
		(end 388.023862 -3.80746)
		(stroke
			(width 0.254)
			(type default)
		)
		(layer "In4.Cu")
	)
	(gr_line
		(start 388.023862 -1.751584)
		(end 388.023862 -3.707384)
		(stroke
			(width 0.254)
			(type default)
		)
		(layer "In4.Cu")
	)
	(gr_line
		(start 388.074662 -12.563348)
		(end 388.074662 -12.512548)
		(stroke
			(width 0.1016)
			(type default)
		)
		(layer "In4.Cu")
	)
	(gr_line
		(start 388.074662 -12.563348)
		(end 388.481062 -12.563348)
		(stroke
			(width 0.1016)
			(type default)
		)
		(layer "In4.Cu")
	)
	(gr_line
		(start 388.074662 -12.512548)
		(end 387.312662 -12.512548)
		(stroke
			(width 0.1016)
			(type default)
		)
		(layer "In4.Cu")
	)
	(gr_line
		(start 388.074662 -12.463272)
		(end 388.074662 -12.412472)
		(stroke
			(width 0.1016)
			(type default)
		)
		(layer "In4.Cu")
	)
	(gr_line
		(start 388.074662 -12.463272)
		(end 388.481062 -12.463272)
		(stroke
			(width 0.1016)
			(type default)
		)
		(layer "In4.Cu")
	)
	(gr_line
		(start 388.074662 -12.412472)
		(end 387.312662 -12.412472)
		(stroke
			(width 0.1016)
			(type default)
		)
		(layer "In4.Cu")
	)
	(gr_line
		(start 388.074662 -12.233148)
		(end 388.074662 -10.251948)
		(stroke
			(width 0.762)
			(type default)
		)
		(layer "In4.Cu")
	)
	(gr_line
		(start 388.074662 -12.133072)
		(end 388.074662 -10.151872)
		(stroke
			(width 0.762)
			(type default)
		)
		(layer "In4.Cu")
	)
	(gr_line
		(start 388.074662 -8.363204)
		(end 388.074662 -8.312404)
		(stroke
			(width 0.1016)
			(type default)
		)
		(layer "In4.Cu")
	)
	(gr_line
		(start 388.074662 -8.363204)
		(end 388.481062 -8.363204)
		(stroke
			(width 0.1016)
			(type default)
		)
		(layer "In4.Cu")
	)
	(gr_line
		(start 388.074662 -8.312404)
		(end 387.312662 -8.312404)
		(stroke
			(width 0.1016)
			(type default)
		)
		(layer "In4.Cu")
	)
	(gr_line
		(start 388.074662 -8.263128)
		(end 388.074662 -8.212328)
		(stroke
			(width 0.1016)
			(type default)
		)
		(layer "In4.Cu")
	)
	(gr_line
		(start 388.074662 -8.263128)
		(end 388.481062 -8.263128)
		(stroke
			(width 0.1016)
			(type default)
		)
		(layer "In4.Cu")
	)
	(gr_line
		(start 388.074662 -8.212328)
		(end 387.312662 -8.212328)
		(stroke
			(width 0.1016)
			(type default)
		)
		(layer "In4.Cu")
	)
	(gr_line
		(start 388.074662 -8.033004)
		(end 388.074662 -6.051804)
		(stroke
			(width 0.762)
			(type default)
		)
		(layer "In4.Cu")
	)
	(gr_line
		(start 388.074662 -7.932928)
		(end 388.074662 -5.951728)
		(stroke
			(width 0.762)
			(type default)
		)
		(layer "In4.Cu")
	)
	(gr_line
		(start 388.074662 -4.16306)
		(end 388.074662 -4.11226)
		(stroke
			(width 0.1016)
			(type default)
		)
		(layer "In4.Cu")
	)
	(gr_line
		(start 388.074662 -4.16306)
		(end 388.481062 -4.16306)
		(stroke
			(width 0.1016)
			(type default)
		)
		(layer "In4.Cu")
	)
	(gr_line
		(start 388.074662 -4.11226)
		(end 387.312662 -4.11226)
		(stroke
			(width 0.1016)
			(type default)
		)
		(layer "In4.Cu")
	)
	(gr_line
		(start 388.074662 -4.062984)
		(end 388.074662 -4.012184)
		(stroke
			(width 0.1016)
			(type default)
		)
		(layer "In4.Cu")
	)
	(gr_line
		(start 388.074662 -4.062984)
		(end 388.481062 -4.062984)
		(stroke
			(width 0.1016)
			(type default)
		)
		(layer "In4.Cu")
	)
	(gr_line
		(start 388.074662 -4.012184)
		(end 387.312662 -4.012184)
		(stroke
			(width 0.1016)
			(type default)
		)
		(layer "In4.Cu")
	)
	(gr_line
		(start 388.074662 -3.83286)
		(end 388.074662 -1.85166)
		(stroke
			(width 0.762)
			(type default)
		)
		(layer "In4.Cu")
	)
	(gr_line
		(start 388.074662 -3.732784)
		(end 388.074662 -1.751584)
		(stroke
			(width 0.762)
			(type default)
		)
		(layer "In4.Cu")
	)
	(gr_line
		(start 388.100062 -12.283948)
		(end 387.693662 -12.283948)
		(stroke
			(width 0.254)
			(type default)
		)
		(layer "In4.Cu")
	)
	(gr_line
		(start 388.100062 -12.183872)
		(end 387.693662 -12.183872)
		(stroke
			(width 0.254)
			(type default)
		)
		(layer "In4.Cu")
	)
	(gr_line
		(start 388.100062 -10.175748)
		(end 388.100062 -12.283948)
		(stroke
			(width 0.254)
			(type default)
		)
		(layer "In4.Cu")
	)
	(gr_line
		(start 388.100062 -10.075672)
		(end 388.100062 -12.183872)
		(stroke
			(width 0.254)
			(type default)
		)
		(layer "In4.Cu")
	)
	(gr_line
		(start 388.100062 -8.083804)
		(end 387.693662 -8.083804)
		(stroke
			(width 0.254)
			(type default)
		)
		(layer "In4.Cu")
	)
	(gr_line
		(start 388.100062 -7.983728)
		(end 387.693662 -7.983728)
		(stroke
			(width 0.254)
			(type default)
		)
		(layer "In4.Cu")
	)
	(gr_line
		(start 388.100062 -5.975604)
		(end 388.100062 -8.083804)
		(stroke
			(width 0.254)
			(type default)
		)
		(layer "In4.Cu")
	)
	(gr_line
		(start 388.100062 -5.875528)
		(end 388.100062 -7.983728)
		(stroke
			(width 0.254)
			(type default)
		)
		(layer "In4.Cu")
	)
	(gr_line
		(start 388.100062 -3.88366)
		(end 387.693662 -3.88366)
		(stroke
			(width 0.254)
			(type default)
		)
		(layer "In4.Cu")
	)
	(gr_line
		(start 388.100062 -3.783584)
		(end 387.693662 -3.783584)
		(stroke
			(width 0.254)
			(type default)
		)
		(layer "In4.Cu")
	)
	(gr_line
		(start 388.100062 -1.77546)
		(end 388.100062 -3.88366)
		(stroke
			(width 0.254)
			(type default)
		)
		(layer "In4.Cu")
	)
	(gr_line
		(start 388.100062 -1.675384)
		(end 388.100062 -3.783584)
		(stroke
			(width 0.254)
			(type default)
		)
		(layer "In4.Cu")
	)
	(gr_line
		(start 388.150862 -12.233148)
		(end 388.150862 -10.251948)
		(stroke
			(width 0.762)
			(type default)
		)
		(layer "In4.Cu")
	)
	(gr_line
		(start 388.150862 -12.133072)
		(end 388.150862 -10.151872)
		(stroke
			(width 0.762)
			(type default)
		)
		(layer "In4.Cu")
	)
	(gr_line
		(start 388.150862 -8.033004)
		(end 388.150862 -6.051804)
		(stroke
			(width 0.762)
			(type default)
		)
		(layer "In4.Cu")
	)
	(gr_line
		(start 388.150862 -7.932928)
		(end 388.150862 -5.951728)
		(stroke
			(width 0.762)
			(type default)
		)
		(layer "In4.Cu")
	)
	(gr_line
		(start 388.150862 -3.83286)
		(end 388.150862 -1.85166)
		(stroke
			(width 0.762)
			(type default)
		)
		(layer "In4.Cu")
	)
	(gr_line
		(start 388.150862 -3.732784)
		(end 388.150862 -1.751584)
		(stroke
			(width 0.762)
			(type default)
		)
		(layer "In4.Cu")
	)
	(gr_line
		(start 388.176262 -12.360148)
		(end 387.617462 -12.360148)
		(stroke
			(width 0.254)
			(type default)
		)
		(layer "In4.Cu")
	)
	(gr_line
		(start 388.176262 -12.260072)
		(end 387.617462 -12.260072)
		(stroke
			(width 0.254)
			(type default)
		)
		(layer "In4.Cu")
	)
	(gr_line
		(start 388.176262 -10.124948)
		(end 388.176262 -12.360148)
		(stroke
			(width 0.254)
			(type default)
		)
		(layer "In4.Cu")
	)
	(gr_line
		(start 388.176262 -10.024872)
		(end 388.176262 -12.260072)
		(stroke
			(width 0.254)
			(type default)
		)
		(layer "In4.Cu")
	)
	(gr_line
		(start 388.176262 -8.160004)
		(end 387.617462 -8.160004)
		(stroke
			(width 0.254)
			(type default)
		)
		(layer "In4.Cu")
	)
	(gr_line
		(start 388.176262 -8.059928)
		(end 387.617462 -8.059928)
		(stroke
			(width 0.254)
			(type default)
		)
		(layer "In4.Cu")
	)
	(gr_line
		(start 388.176262 -5.924804)
		(end 388.176262 -8.160004)
		(stroke
			(width 0.254)
			(type default)
		)
		(layer "In4.Cu")
	)
	(gr_line
		(start 388.176262 -5.824728)
		(end 388.176262 -8.059928)
		(stroke
			(width 0.254)
			(type default)
		)
		(layer "In4.Cu")
	)
	(gr_line
		(start 388.176262 -3.95986)
		(end 387.617462 -3.95986)
		(stroke
			(width 0.254)
			(type default)
		)
		(layer "In4.Cu")
	)
	(gr_line
		(start 388.176262 -3.859784)
		(end 387.617462 -3.859784)
		(stroke
			(width 0.254)
			(type default)
		)
		(layer "In4.Cu")
	)
	(gr_line
		(start 388.176262 -1.72466)
		(end 388.176262 -3.95986)
		(stroke
			(width 0.254)
			(type default)
		)
		(layer "In4.Cu")
	)
	(gr_line
		(start 388.176262 -1.624584)
		(end 388.176262 -3.859784)
		(stroke
			(width 0.254)
			(type default)
		)
		(layer "In4.Cu")
	)
	(gr_line
		(start 388.252462 -12.385548)
		(end 387.541262 -12.385548)
		(stroke
			(width 0.254)
			(type default)
		)
		(layer "In4.Cu")
	)
	(gr_line
		(start 388.252462 -12.285472)
		(end 387.541262 -12.285472)
		(stroke
			(width 0.254)
			(type default)
		)
		(layer "In4.Cu")
	)
	(gr_line
		(start 388.252462 -10.048748)
		(end 388.252462 -12.385548)
		(stroke
			(width 0.254)
			(type default)
		)
		(layer "In4.Cu")
	)
	(gr_line
		(start 388.252462 -9.948672)
		(end 388.252462 -12.285472)
		(stroke
			(width 0.254)
			(type default)
		)
		(layer "In4.Cu")
	)
	(gr_line
		(start 388.252462 -8.185404)
		(end 387.541262 -8.185404)
		(stroke
			(width 0.254)
			(type default)
		)
		(layer "In4.Cu")
	)
	(gr_line
		(start 388.252462 -8.085328)
		(end 387.541262 -8.085328)
		(stroke
			(width 0.254)
			(type default)
		)
		(layer "In4.Cu")
	)
	(gr_line
		(start 388.252462 -5.848604)
		(end 388.252462 -8.185404)
		(stroke
			(width 0.254)
			(type default)
		)
		(layer "In4.Cu")
	)
	(gr_line
		(start 388.252462 -5.748528)
		(end 388.252462 -8.085328)
		(stroke
			(width 0.254)
			(type default)
		)
		(layer "In4.Cu")
	)
	(gr_line
		(start 388.252462 -3.98526)
		(end 387.541262 -3.98526)
		(stroke
			(width 0.254)
			(type default)
		)
		(layer "In4.Cu")
	)
	(gr_line
		(start 388.252462 -3.885184)
		(end 387.541262 -3.885184)
		(stroke
			(width 0.254)
			(type default)
		)
		(layer "In4.Cu")
	)
	(gr_line
		(start 388.252462 -1.64846)
		(end 388.252462 -3.98526)
		(stroke
			(width 0.254)
			(type default)
		)
		(layer "In4.Cu")
	)
	(gr_line
		(start 388.252462 -1.548384)
		(end 388.252462 -3.885184)
		(stroke
			(width 0.254)
			(type default)
		)
		(layer "In4.Cu")
	)
	(gr_line
		(start 388.277862 -12.512548)
		(end 387.287262 -12.512548)
		(stroke
			(width 0.1016)
			(type default)
		)
		(layer "In4.Cu")
	)
	(gr_line
		(start 388.277862 -12.436348)
		(end 387.465062 -12.436348)
		(stroke
			(width 0.254)
			(type default)
		)
		(layer "In4.Cu")
	)
	(gr_line
		(start 388.277862 -12.412472)
		(end 387.287262 -12.412472)
		(stroke
			(width 0.1016)
			(type default)
		)
		(layer "In4.Cu")
	)
	(gr_line
		(start 388.277862 -12.336272)
		(end 387.465062 -12.336272)
		(stroke
			(width 0.254)
			(type default)
		)
		(layer "In4.Cu")
	)
	(gr_line
		(start 388.277862 -10.023348)
		(end 388.277862 -12.436348)
		(stroke
			(width 0.254)
			(type default)
		)
		(layer "In4.Cu")
	)
	(gr_line
		(start 388.277862 -9.923272)
		(end 388.277862 -12.336272)
		(stroke
			(width 0.254)
			(type default)
		)
		(layer "In4.Cu")
	)
	(gr_line
		(start 388.277862 -8.312404)
		(end 387.287262 -8.312404)
		(stroke
			(width 0.1016)
			(type default)
		)
		(layer "In4.Cu")
	)
	(gr_line
		(start 388.277862 -8.236204)
		(end 387.465062 -8.236204)
		(stroke
			(width 0.254)
			(type default)
		)
		(layer "In4.Cu")
	)
	(gr_line
		(start 388.277862 -8.212328)
		(end 387.287262 -8.212328)
		(stroke
			(width 0.1016)
			(type default)
		)
		(layer "In4.Cu")
	)
	(gr_line
		(start 388.277862 -8.136128)
		(end 387.465062 -8.136128)
		(stroke
			(width 0.254)
			(type default)
		)
		(layer "In4.Cu")
	)
	(gr_line
		(start 388.277862 -5.823204)
		(end 388.277862 -8.236204)
		(stroke
			(width 0.254)
			(type default)
		)
		(layer "In4.Cu")
	)
	(gr_line
		(start 388.277862 -5.723128)
		(end 388.277862 -8.136128)
		(stroke
			(width 0.254)
			(type default)
		)
		(layer "In4.Cu")
	)
	(gr_line
		(start 388.277862 -4.11226)
		(end 387.287262 -4.11226)
		(stroke
			(width 0.1016)
			(type default)
		)
		(layer "In4.Cu")
	)
	(gr_line
		(start 388.277862 -4.03606)
		(end 387.465062 -4.03606)
		(stroke
			(width 0.254)
			(type default)
		)
		(layer "In4.Cu")
	)
	(gr_line
		(start 388.277862 -4.012184)
		(end 387.287262 -4.012184)
		(stroke
			(width 0.1016)
			(type default)
		)
		(layer "In4.Cu")
	)
	(gr_line
		(start 388.277862 -3.935984)
		(end 387.465062 -3.935984)
		(stroke
			(width 0.254)
			(type default)
		)
		(layer "In4.Cu")
	)
	(gr_line
		(start 388.277862 -1.62306)
		(end 388.277862 -4.03606)
		(stroke
			(width 0.254)
			(type default)
		)
		(layer "In4.Cu")
	)
	(gr_line
		(start 388.277862 -1.522984)
		(end 388.277862 -3.935984)
		(stroke
			(width 0.254)
			(type default)
		)
		(layer "In4.Cu")
	)
	(gr_line
		(start 388.303262 -12.461748)
		(end 387.439662 -12.461748)
		(stroke
			(width 0.254)
			(type default)
		)
		(layer "In4.Cu")
	)
	(gr_line
		(start 388.303262 -12.361672)
		(end 387.439662 -12.361672)
		(stroke
			(width 0.254)
			(type default)
		)
		(layer "In4.Cu")
	)
	(gr_line
		(start 388.303262 -9.997948)
		(end 388.303262 -12.461748)
		(stroke
			(width 0.254)
			(type default)
		)
		(layer "In4.Cu")
	)
	(gr_line
		(start 388.303262 -9.897872)
		(end 388.303262 -12.361672)
		(stroke
			(width 0.254)
			(type default)
		)
		(layer "In4.Cu")
	)
	(gr_line
		(start 388.303262 -8.261604)
		(end 387.439662 -8.261604)
		(stroke
			(width 0.254)
			(type default)
		)
		(layer "In4.Cu")
	)
	(gr_line
		(start 388.303262 -8.161528)
		(end 387.439662 -8.161528)
		(stroke
			(width 0.254)
			(type default)
		)
		(layer "In4.Cu")
	)
	(gr_line
		(start 388.303262 -5.797804)
		(end 388.303262 -8.261604)
		(stroke
			(width 0.254)
			(type default)
		)
		(layer "In4.Cu")
	)
	(gr_line
		(start 388.303262 -5.697728)
		(end 388.303262 -8.161528)
		(stroke
			(width 0.254)
			(type default)
		)
		(layer "In4.Cu")
	)
	(gr_line
		(start 388.303262 -4.06146)
		(end 387.439662 -4.06146)
		(stroke
			(width 0.254)
			(type default)
		)
		(layer "In4.Cu")
	)
	(gr_line
		(start 388.303262 -3.961384)
		(end 387.439662 -3.961384)
		(stroke
			(width 0.254)
			(type default)
		)
		(layer "In4.Cu")
	)
	(gr_line
		(start 388.303262 -1.59766)
		(end 388.303262 -4.06146)
		(stroke
			(width 0.254)
			(type default)
		)
		(layer "In4.Cu")
	)
	(gr_line
		(start 388.303262 -1.497584)
		(end 388.303262 -3.961384)
		(stroke
			(width 0.254)
			(type default)
		)
		(layer "In4.Cu")
	)
	(gr_line
		(start 388.354062 -12.487148)
		(end 387.414262 -12.487148)
		(stroke
			(width 0.254)
			(type default)
		)
		(layer "In4.Cu")
	)
	(gr_line
		(start 388.354062 -12.387072)
		(end 387.414262 -12.387072)
		(stroke
			(width 0.254)
			(type default)
		)
		(layer "In4.Cu")
	)
	(gr_line
		(start 388.354062 -9.997948)
		(end 388.354062 -12.487148)
		(stroke
			(width 0.254)
			(type default)
		)
		(layer "In4.Cu")
	)
	(gr_line
		(start 388.354062 -9.897872)
		(end 388.354062 -12.387072)
		(stroke
			(width 0.254)
			(type default)
		)
		(layer "In4.Cu")
	)
	(gr_line
		(start 388.354062 -8.287004)
		(end 387.414262 -8.287004)
		(stroke
			(width 0.254)
			(type default)
		)
		(layer "In4.Cu")
	)
	(gr_line
		(start 388.354062 -8.186928)
		(end 387.414262 -8.186928)
		(stroke
			(width 0.254)
			(type default)
		)
		(layer "In4.Cu")
	)
	(gr_line
		(start 388.354062 -5.797804)
		(end 388.354062 -8.287004)
		(stroke
			(width 0.254)
			(type default)
		)
		(layer "In4.Cu")
	)
	(gr_line
		(start 388.354062 -5.697728)
		(end 388.354062 -8.186928)
		(stroke
			(width 0.254)
			(type default)
		)
		(layer "In4.Cu")
	)
	(gr_line
		(start 388.354062 -4.08686)
		(end 387.414262 -4.08686)
		(stroke
			(width 0.254)
			(type default)
		)
		(layer "In4.Cu")
	)
	(gr_line
		(start 388.354062 -3.986784)
		(end 387.414262 -3.986784)
		(stroke
			(width 0.254)
			(type default)
		)
		(layer "In4.Cu")
	)
	(gr_line
		(start 388.354062 -1.59766)
		(end 388.354062 -4.08686)
		(stroke
			(width 0.254)
			(type default)
		)
		(layer "In4.Cu")
	)
	(gr_line
		(start 388.354062 -1.497584)
		(end 388.354062 -3.986784)
		(stroke
			(width 0.254)
			(type default)
		)
		(layer "In4.Cu")
	)
	(gr_line
		(start 388.379462 -12.487148)
		(end 387.414262 -12.487148)
		(stroke
			(width 0.2032)
			(type default)
		)
		(layer "In4.Cu")
	)
	(gr_line
		(start 388.379462 -12.387072)
		(end 387.414262 -12.387072)
		(stroke
			(width 0.2032)
			(type default)
		)
		(layer "In4.Cu")
	)
	(gr_line
		(start 388.379462 -9.947148)
		(end 388.379462 -12.487148)
		(stroke
			(width 0.2032)
			(type default)
		)
		(layer "In4.Cu")
	)
	(gr_line
		(start 388.379462 -9.847072)
		(end 388.379462 -12.387072)
		(stroke
			(width 0.2032)
			(type default)
		)
		(layer "In4.Cu")
	)
	(gr_line
		(start 388.379462 -8.287004)
		(end 387.414262 -8.287004)
		(stroke
			(width 0.2032)
			(type default)
		)
		(layer "In4.Cu")
	)
	(gr_line
		(start 388.379462 -8.186928)
		(end 387.414262 -8.186928)
		(stroke
			(width 0.2032)
			(type default)
		)
		(layer "In4.Cu")
	)
	(gr_line
		(start 388.379462 -5.747004)
		(end 388.379462 -8.287004)
		(stroke
			(width 0.2032)
			(type default)
		)
		(layer "In4.Cu")
	)
	(gr_line
		(start 388.379462 -5.646928)
		(end 388.379462 -8.186928)
		(stroke
			(width 0.2032)
			(type default)
		)
		(layer "In4.Cu")
	)
	(gr_line
		(start 388.379462 -4.08686)
		(end 387.414262 -4.08686)
		(stroke
			(width 0.2032)
			(type default)
		)
		(layer "In4.Cu")
	)
	(gr_line
		(start 388.379462 -3.986784)
		(end 387.414262 -3.986784)
		(stroke
			(width 0.2032)
			(type default)
		)
		(layer "In4.Cu")
	)
	(gr_line
		(start 388.379462 -1.54686)
		(end 388.379462 -4.08686)
		(stroke
			(width 0.2032)
			(type default)
		)
		(layer "In4.Cu")
	)
	(gr_line
		(start 388.379462 -1.446784)
		(end 388.379462 -3.986784)
		(stroke
			(width 0.2032)
			(type default)
		)
		(layer "In4.Cu")
	)
	(gr_line
		(start 388.430262 -12.512548)
		(end 387.363462 -12.512548)
		(stroke
			(width 0.2032)
			(type default)
		)
		(layer "In4.Cu")
	)
	(gr_line
		(start 388.430262 -12.412472)
		(end 387.363462 -12.412472)
		(stroke
			(width 0.2032)
			(type default)
		)
		(layer "In4.Cu")
	)
	(gr_line
		(start 388.430262 -9.947148)
		(end 388.430262 -12.512548)
		(stroke
			(width 0.2032)
			(type default)
		)
		(layer "In4.Cu")
	)
	(gr_line
		(start 388.430262 -9.847072)
		(end 388.430262 -12.412472)
		(stroke
			(width 0.2032)
			(type default)
		)
		(layer "In4.Cu")
	)
	(gr_line
		(start 388.430262 -8.312404)
		(end 387.363462 -8.312404)
		(stroke
			(width 0.2032)
			(type default)
		)
		(layer "In4.Cu")
	)
	(gr_line
		(start 388.430262 -8.212328)
		(end 387.363462 -8.212328)
		(stroke
			(width 0.2032)
			(type default)
		)
		(layer "In4.Cu")
	)
	(gr_line
		(start 388.430262 -5.747004)
		(end 388.430262 -8.312404)
		(stroke
			(width 0.2032)
			(type default)
		)
		(layer "In4.Cu")
	)
	(gr_line
		(start 388.430262 -5.646928)
		(end 388.430262 -8.212328)
		(stroke
			(width 0.2032)
			(type default)
		)
		(layer "In4.Cu")
	)
	(gr_line
		(start 388.430262 -4.11226)
		(end 387.363462 -4.11226)
		(stroke
			(width 0.2032)
			(type default)
		)
		(layer "In4.Cu")
	)
	(gr_line
		(start 388.430262 -4.012184)
		(end 387.363462 -4.012184)
		(stroke
			(width 0.2032)
			(type default)
		)
		(layer "In4.Cu")
	)
	(gr_line
		(start 388.430262 -1.54686)
		(end 388.430262 -4.11226)
		(stroke
			(width 0.2032)
			(type default)
		)
		(layer "In4.Cu")
	)
	(gr_line
		(start 388.430262 -1.446784)
		(end 388.430262 -4.012184)
		(stroke
			(width 0.2032)
			(type default)
		)
		(layer "In4.Cu")
	)
	(gr_line
		(start 388.455662 -12.512548)
		(end 387.338062 -12.512548)
		(stroke
			(width 0.1016)
			(type default)
		)
		(layer "In4.Cu")
	)
	(gr_line
		(start 388.455662 -12.412472)
		(end 387.338062 -12.412472)
		(stroke
			(width 0.1016)
			(type default)
		)
		(layer "In4.Cu")
	)
	(gr_line
		(start 388.455662 -9.921748)
		(end 388.455662 -12.512548)
		(stroke
			(width 0.1016)
			(type default)
		)
		(layer "In4.Cu")
	)
	(gr_line
		(start 388.455662 -9.821672)
		(end 388.455662 -12.412472)
		(stroke
			(width 0.1016)
			(type default)
		)
		(layer "In4.Cu")
	)
	(gr_line
		(start 388.455662 -8.312404)
		(end 387.338062 -8.312404)
		(stroke
			(width 0.1016)
			(type default)
		)
		(layer "In4.Cu")
	)
	(gr_line
		(start 388.455662 -8.212328)
		(end 387.338062 -8.212328)
		(stroke
			(width 0.1016)
			(type default)
		)
		(layer "In4.Cu")
	)
	(gr_line
		(start 388.455662 -5.721604)
		(end 388.455662 -8.312404)
		(stroke
			(width 0.1016)
			(type default)
		)
		(layer "In4.Cu")
	)
	(gr_line
		(start 388.455662 -5.621528)
		(end 388.455662 -8.212328)
		(stroke
			(width 0.1016)
			(type default)
		)
		(layer "In4.Cu")
	)
	(gr_line
		(start 388.455662 -4.11226)
		(end 387.338062 -4.11226)
		(stroke
			(width 0.1016)
			(type default)
		)
		(layer "In4.Cu")
	)
	(gr_line
		(start 388.455662 -4.012184)
		(end 387.338062 -4.012184)
		(stroke
			(width 0.1016)
			(type default)
		)
		(layer "In4.Cu")
	)
	(gr_line
		(start 388.455662 -1.52146)
		(end 388.455662 -4.11226)
		(stroke
			(width 0.1016)
			(type default)
		)
		(layer "In4.Cu")
	)
	(gr_line
		(start 388.455662 -1.421384)
		(end 388.455662 -4.012184)
		(stroke
			(width 0.1016)
			(type default)
		)
		(layer "In4.Cu")
	)
	(gr_line
		(start 388.464806 -18.5166)
		(end 389.734806 -18.5166)
		(stroke
			(width 0.7874)
			(type default)
		)
		(layer "In4.Cu")
	)
	(gr_line
		(start 388.481062 -12.563348)
		(end 388.074662 -12.563348)
		(stroke
			(width 0.1016)
			(type default)
		)
		(layer "In4.Cu")
	)
	(gr_line
		(start 388.481062 -12.563348)
		(end 388.481062 -9.896348)
		(stroke
			(width 0.1016)
			(type default)
		)
		(layer "In4.Cu")
	)
	(gr_line
		(start 388.481062 -12.463272)
		(end 388.074662 -12.463272)
		(stroke
			(width 0.1016)
			(type default)
		)
		(layer "In4.Cu")
	)
	(gr_line
		(start 388.481062 -12.463272)
		(end 388.481062 -9.796272)
		(stroke
			(width 0.1016)
			(type default)
		)
		(layer "In4.Cu")
	)
	(gr_line
		(start 388.481062 -9.896348)
		(end 387.287262 -9.896348)
		(stroke
			(width 0.1016)
			(type default)
		)
		(layer "In4.Cu")
	)
	(gr_line
		(start 388.481062 -9.896348)
		(end 388.481062 -12.563348)
		(stroke
			(width 0.1016)
			(type default)
		)
		(layer "In4.Cu")
	)
	(gr_line
		(start 388.481062 -9.796272)
		(end 387.287262 -9.796272)
		(stroke
			(width 0.1016)
			(type default)
		)
		(layer "In4.Cu")
	)
	(gr_line
		(start 388.481062 -9.796272)
		(end 388.481062 -12.463272)
		(stroke
			(width 0.1016)
			(type default)
		)
		(layer "In4.Cu")
	)
	(gr_line
		(start 388.481062 -8.363204)
		(end 388.074662 -8.363204)
		(stroke
			(width 0.1016)
			(type default)
		)
		(layer "In4.Cu")
	)
	(gr_line
		(start 388.481062 -8.363204)
		(end 388.481062 -5.696204)
		(stroke
			(width 0.1016)
			(type default)
		)
		(layer "In4.Cu")
	)
	(gr_line
		(start 388.481062 -8.263128)
		(end 388.074662 -8.263128)
		(stroke
			(width 0.1016)
			(type default)
		)
		(layer "In4.Cu")
	)
	(gr_line
		(start 388.481062 -8.263128)
		(end 388.481062 -5.596128)
		(stroke
			(width 0.1016)
			(type default)
		)
		(layer "In4.Cu")
	)
	(gr_line
		(start 388.481062 -5.696204)
		(end 387.287262 -5.696204)
		(stroke
			(width 0.1016)
			(type default)
		)
		(layer "In4.Cu")
	)
	(gr_line
		(start 388.481062 -5.696204)
		(end 388.481062 -8.363204)
		(stroke
			(width 0.1016)
			(type default)
		)
		(layer "In4.Cu")
	)
	(gr_line
		(start 388.481062 -5.596128)
		(end 387.287262 -5.596128)
		(stroke
			(width 0.1016)
			(type default)
		)
		(layer "In4.Cu")
	)
	(gr_line
		(start 388.481062 -5.596128)
		(end 388.481062 -8.263128)
		(stroke
			(width 0.1016)
			(type default)
		)
		(layer "In4.Cu")
	)
	(gr_line
		(start 388.481062 -4.16306)
		(end 388.074662 -4.16306)
		(stroke
			(width 0.1016)
			(type default)
		)
		(layer "In4.Cu")
	)
	(gr_line
		(start 388.481062 -4.16306)
		(end 388.481062 -1.49606)
		(stroke
			(width 0.1016)
			(type default)
		)
		(layer "In4.Cu")
	)
	(gr_line
		(start 388.481062 -4.062984)
		(end 388.074662 -4.062984)
		(stroke
			(width 0.1016)
			(type default)
		)
		(layer "In4.Cu")
	)
	(gr_line
		(start 388.481062 -4.062984)
		(end 388.481062 -1.395984)
		(stroke
			(width 0.1016)
			(type default)
		)
		(layer "In4.Cu")
	)
	(gr_line
		(start 388.481062 -1.49606)
		(end 387.287262 -1.49606)
		(stroke
			(width 0.1016)
			(type default)
		)
		(layer "In4.Cu")
	)
	(gr_line
		(start 388.481062 -1.49606)
		(end 388.481062 -4.16306)
		(stroke
			(width 0.1016)
			(type default)
		)
		(layer "In4.Cu")
	)
	(gr_line
		(start 388.481062 -1.494028)
		(end 387.261862 -1.494028)
		(stroke
			(width 0.1016)
			(type default)
		)
		(layer "In4.Cu")
	)
	(gr_line
		(start 388.481062 -1.494028)
		(end 387.287262 -1.494028)
		(stroke
			(width 0.1016)
			(type default)
		)
		(layer "In4.Cu")
	)
	(gr_line
		(start 388.481062 -1.395984)
		(end 387.287262 -1.395984)
		(stroke
			(width 0.1016)
			(type default)
		)
		(layer "In4.Cu")
	)
	(gr_line
		(start 388.481062 -1.395984)
		(end 388.481062 -4.062984)
		(stroke
			(width 0.1016)
			(type default)
		)
		(layer "In4.Cu")
	)
	(gr_line
		(start 388.506462 -1.468628)
		(end 387.261862 -1.468628)
		(stroke
			(width 0.1016)
			(type default)
		)
		(layer "In4.Cu")
	)
	(gr_line
		(start 389.287258 -13.8176)
		(end 390.074658 -13.8176)
		(stroke
			(width 0.1016)
			(type default)
		)
		(layer "In4.Cu")
	)
	(gr_line
		(start 389.287258 -13.7668)
		(end 389.287258 -11.1506)
		(stroke
			(width 0.1016)
			(type default)
		)
		(layer "In4.Cu")
	)
	(gr_line
		(start 389.287258 -11.1506)
		(end 389.287258 -13.8176)
		(stroke
			(width 0.1016)
			(type default)
		)
		(layer "In4.Cu")
	)
	(gr_line
		(start 389.287258 -11.1506)
		(end 390.481058 -11.1506)
		(stroke
			(width 0.1016)
			(type default)
		)
		(layer "In4.Cu")
	)
	(gr_line
		(start 389.287258 -9.617456)
		(end 390.074658 -9.617456)
		(stroke
			(width 0.1016)
			(type default)
		)
		(layer "In4.Cu")
	)
	(gr_line
		(start 389.287258 -9.566656)
		(end 389.287258 -6.950456)
		(stroke
			(width 0.1016)
			(type default)
		)
		(layer "In4.Cu")
	)
	(gr_line
		(start 389.287258 -6.950456)
		(end 389.287258 -9.617456)
		(stroke
			(width 0.1016)
			(type default)
		)
		(layer "In4.Cu")
	)
	(gr_line
		(start 389.287258 -6.950456)
		(end 390.481058 -6.950456)
		(stroke
			(width 0.1016)
			(type default)
		)
		(layer "In4.Cu")
	)
	(gr_line
		(start 389.312658 -13.7668)
		(end 389.312658 -11.176)
		(stroke
			(width 0.1016)
			(type default)
		)
		(layer "In4.Cu")
	)
	(gr_line
		(start 389.312658 -11.176)
		(end 390.455658 -11.176)
		(stroke
			(width 0.1016)
			(type default)
		)
		(layer "In4.Cu")
	)
	(gr_line
		(start 389.312658 -9.566656)
		(end 389.312658 -6.975856)
		(stroke
			(width 0.1016)
			(type default)
		)
		(layer "In4.Cu")
	)
	(gr_line
		(start 389.312658 -6.975856)
		(end 390.455658 -6.975856)
		(stroke
			(width 0.1016)
			(type default)
		)
		(layer "In4.Cu")
	)
	(gr_line
		(start 389.338058 -13.7668)
		(end 389.338058 -11.2014)
		(stroke
			(width 0.1016)
			(type default)
		)
		(layer "In4.Cu")
	)
	(gr_line
		(start 389.338058 -11.2014)
		(end 389.592058 -11.2014)
		(stroke
			(width 0.1016)
			(type default)
		)
		(layer "In4.Cu")
	)
	(gr_line
		(start 389.338058 -9.566656)
		(end 389.338058 -7.001256)
		(stroke
			(width 0.1016)
			(type default)
		)
		(layer "In4.Cu")
	)
	(gr_line
		(start 389.338058 -7.001256)
		(end 389.592058 -7.001256)
		(stroke
			(width 0.1016)
			(type default)
		)
		(layer "In4.Cu")
	)
	(gr_line
		(start 389.363458 -13.7668)
		(end 389.363458 -11.2014)
		(stroke
			(width 0.2032)
			(type default)
		)
		(layer "In4.Cu")
	)
	(gr_line
		(start 389.363458 -11.2014)
		(end 390.379458 -11.2014)
		(stroke
			(width 0.2032)
			(type default)
		)
		(layer "In4.Cu")
	)
	(gr_line
		(start 389.363458 -9.566656)
		(end 389.363458 -7.001256)
		(stroke
			(width 0.2032)
			(type default)
		)
		(layer "In4.Cu")
	)
	(gr_line
		(start 389.363458 -7.001256)
		(end 390.379458 -7.001256)
		(stroke
			(width 0.2032)
			(type default)
		)
		(layer "In4.Cu")
	)
	(gr_line
		(start 389.414258 -13.7414)
		(end 389.414258 -11.2522)
		(stroke
			(width 0.2032)
			(type default)
		)
		(layer "In4.Cu")
	)
	(gr_line
		(start 389.414258 -13.7414)
		(end 389.414258 -11.2522)
		(stroke
			(width 0.254)
			(type default)
		)
		(layer "In4.Cu")
	)
	(gr_line
		(start 389.414258 -11.2522)
		(end 389.617458 -11.2522)
		(stroke
			(width 0.2032)
			(type default)
		)
		(layer "In4.Cu")
	)
	(gr_line
		(start 389.414258 -11.2522)
		(end 390.303258 -11.2522)
		(stroke
			(width 0.254)
			(type default)
		)
		(layer "In4.Cu")
	)
	(gr_line
		(start 389.414258 -9.541256)
		(end 389.414258 -7.052056)
		(stroke
			(width 0.2032)
			(type default)
		)
		(layer "In4.Cu")
	)
	(gr_line
		(start 389.414258 -9.541256)
		(end 389.414258 -7.052056)
		(stroke
			(width 0.254)
			(type default)
		)
		(layer "In4.Cu")
	)
	(gr_line
		(start 389.414258 -7.052056)
		(end 389.617458 -7.052056)
		(stroke
			(width 0.2032)
			(type default)
		)
		(layer "In4.Cu")
	)
	(gr_line
		(start 389.414258 -7.052056)
		(end 390.303258 -7.052056)
		(stroke
			(width 0.254)
			(type default)
		)
		(layer "In4.Cu")
	)
	(gr_line
		(start 389.439658 -13.716)
		(end 389.439658 -11.2776)
		(stroke
			(width 0.254)
			(type default)
		)
		(layer "In4.Cu")
	)
	(gr_line
		(start 389.439658 -11.2776)
		(end 390.277858 -11.2776)
		(stroke
			(width 0.254)
			(type default)
		)
		(layer "In4.Cu")
	)
	(gr_line
		(start 389.439658 -9.515856)
		(end 389.439658 -7.077456)
		(stroke
			(width 0.254)
			(type default)
		)
		(layer "In4.Cu")
	)
	(gr_line
		(start 389.439658 -7.077456)
		(end 390.277858 -7.077456)
		(stroke
			(width 0.254)
			(type default)
		)
		(layer "In4.Cu")
	)
	(gr_line
		(start 389.465058 -13.6906)
		(end 389.465058 -11.303)
		(stroke
			(width 0.254)
			(type default)
		)
		(layer "In4.Cu")
	)
	(gr_line
		(start 389.465058 -11.303)
		(end 390.252458 -11.303)
		(stroke
			(width 0.254)
			(type default)
		)
		(layer "In4.Cu")
	)
	(gr_line
		(start 389.465058 -9.490456)
		(end 389.465058 -7.102856)
		(stroke
			(width 0.254)
			(type default)
		)
		(layer "In4.Cu")
	)
	(gr_line
		(start 389.465058 -7.102856)
		(end 390.252458 -7.102856)
		(stroke
			(width 0.254)
			(type default)
		)
		(layer "In4.Cu")
	)
	(gr_line
		(start 389.490458 -13.6144)
		(end 390.125458 -13.6144)
		(stroke
			(width 0.508)
			(type default)
		)
		(layer "In4.Cu")
	)
	(gr_line
		(start 389.490458 -11.43)
		(end 390.125458 -11.43)
		(stroke
			(width 0.508)
			(type default)
		)
		(layer "In4.Cu")
	)
	(gr_line
		(start 389.490458 -11.3792)
		(end 390.125458 -11.3792)
		(stroke
			(width 0.508)
			(type default)
		)
		(layer "In4.Cu")
	)
	(gr_line
		(start 389.490458 -9.414256)
		(end 390.125458 -9.414256)
		(stroke
			(width 0.508)
			(type default)
		)
		(layer "In4.Cu")
	)
	(gr_line
		(start 389.490458 -7.229856)
		(end 390.125458 -7.229856)
		(stroke
			(width 0.508)
			(type default)
		)
		(layer "In4.Cu")
	)
	(gr_line
		(start 389.490458 -7.179056)
		(end 390.125458 -7.179056)
		(stroke
			(width 0.508)
			(type default)
		)
		(layer "In4.Cu")
	)
	(gr_line
		(start 389.515858 -11.684)
		(end 390.150858 -11.684)
		(stroke
			(width 0.508)
			(type default)
		)
		(layer "In4.Cu")
	)
	(gr_line
		(start 389.515858 -7.483856)
		(end 390.150858 -7.483856)
		(stroke
			(width 0.508)
			(type default)
		)
		(layer "In4.Cu")
	)
	(gr_line
		(start 389.541258 -13.6398)
		(end 389.541258 -11.3792)
		(stroke
			(width 0.254)
			(type default)
		)
		(layer "In4.Cu")
	)
	(gr_line
		(start 389.541258 -13.4874)
		(end 390.176258 -13.4874)
		(stroke
			(width 0.508)
			(type default)
		)
		(layer "In4.Cu")
	)
	(gr_line
		(start 389.541258 -11.3792)
		(end 390.176258 -11.3792)
		(stroke
			(width 0.254)
			(type default)
		)
		(layer "In4.Cu")
	)
	(gr_line
		(start 389.541258 -9.439656)
		(end 389.541258 -7.179056)
		(stroke
			(width 0.254)
			(type default)
		)
		(layer "In4.Cu")
	)
	(gr_line
		(start 389.541258 -9.287256)
		(end 390.176258 -9.287256)
		(stroke
			(width 0.508)
			(type default)
		)
		(layer "In4.Cu")
	)
	(gr_line
		(start 389.541258 -7.179056)
		(end 390.176258 -7.179056)
		(stroke
			(width 0.254)
			(type default)
		)
		(layer "In4.Cu")
	)
	(gr_line
		(start 389.566658 -13.335)
		(end 390.201658 -13.335)
		(stroke
			(width 0.508)
			(type default)
		)
		(layer "In4.Cu")
	)
	(gr_line
		(start 389.566658 -9.134856)
		(end 390.201658 -9.134856)
		(stroke
			(width 0.508)
			(type default)
		)
		(layer "In4.Cu")
	)
	(gr_line
		(start 389.592058 -13.6144)
		(end 390.227058 -13.6144)
		(stroke
			(width 0.508)
			(type default)
		)
		(layer "In4.Cu")
	)
	(gr_line
		(start 389.592058 -11.2014)
		(end 390.430258 -11.2014)
		(stroke
			(width 0.2032)
			(type default)
		)
		(layer "In4.Cu")
	)
	(gr_line
		(start 389.592058 -9.414256)
		(end 390.227058 -9.414256)
		(stroke
			(width 0.508)
			(type default)
		)
		(layer "In4.Cu")
	)
	(gr_line
		(start 389.592058 -7.001256)
		(end 390.430258 -7.001256)
		(stroke
			(width 0.2032)
			(type default)
		)
		(layer "In4.Cu")
	)
	(gr_line
		(start 389.617458 -13.6144)
		(end 389.617458 -11.43)
		(stroke
			(width 0.254)
			(type default)
		)
		(layer "In4.Cu")
	)
	(gr_line
		(start 389.617458 -11.43)
		(end 390.100058 -11.43)
		(stroke
			(width 0.254)
			(type default)
		)
		(layer "In4.Cu")
	)
	(gr_line
		(start 389.617458 -11.2522)
		(end 390.354058 -11.2522)
		(stroke
			(width 0.254)
			(type default)
		)
		(layer "In4.Cu")
	)
	(gr_line
		(start 389.617458 -9.414256)
		(end 389.617458 -7.229856)
		(stroke
			(width 0.254)
			(type default)
		)
		(layer "In4.Cu")
	)
	(gr_line
		(start 389.617458 -7.229856)
		(end 390.100058 -7.229856)
		(stroke
			(width 0.254)
			(type default)
		)
		(layer "In4.Cu")
	)
	(gr_line
		(start 389.617458 -7.052056)
		(end 390.354058 -7.052056)
		(stroke
			(width 0.254)
			(type default)
		)
		(layer "In4.Cu")
	)
	(gr_line
		(start 389.636 -11.36523)
		(end 390.271 -11.36523)
		(stroke
			(width 0.508)
			(type default)
		)
		(layer "In4.Cu")
	)
	(gr_line
		(start 389.636 -7.165086)
		(end 390.271 -7.165086)
		(stroke
			(width 0.508)
			(type default)
		)
		(layer "In4.Cu")
	)
	(gr_line
		(start 389.642858 -13.6144)
		(end 390.277858 -13.6144)
		(stroke
			(width 0.508)
			(type default)
		)
		(layer "In4.Cu")
	)
	(gr_line
		(start 389.642858 -13.4874)
		(end 389.642858 -11.5062)
		(stroke
			(width 0.762)
			(type default)
		)
		(layer "In4.Cu")
	)
	(gr_line
		(start 389.642858 -11.5062)
		(end 390.277858 -11.5062)
		(stroke
			(width 0.508)
			(type default)
		)
		(layer "In4.Cu")
	)
	(gr_line
		(start 389.642858 -9.414256)
		(end 390.277858 -9.414256)
		(stroke
			(width 0.508)
			(type default)
		)
		(layer "In4.Cu")
	)
	(gr_line
		(start 389.642858 -9.287256)
		(end 389.642858 -7.306056)
		(stroke
			(width 0.762)
			(type default)
		)
		(layer "In4.Cu")
	)
	(gr_line
		(start 389.642858 -7.306056)
		(end 390.277858 -7.306056)
		(stroke
			(width 0.508)
			(type default)
		)
		(layer "In4.Cu")
	)
	(gr_line
		(start 389.693658 -13.5382)
		(end 389.693658 -11.5062)
		(stroke
			(width 0.254)
			(type default)
		)
		(layer "In4.Cu")
	)
	(gr_line
		(start 389.693658 -11.5062)
		(end 390.023858 -11.5062)
		(stroke
			(width 0.254)
			(type default)
		)
		(layer "In4.Cu")
	)
	(gr_line
		(start 389.693658 -9.338056)
		(end 389.693658 -7.306056)
		(stroke
			(width 0.254)
			(type default)
		)
		(layer "In4.Cu")
	)
	(gr_line
		(start 389.693658 -7.306056)
		(end 390.023858 -7.306056)
		(stroke
			(width 0.254)
			(type default)
		)
		(layer "In4.Cu")
	)
	(gr_line
		(start 389.795258 -13.462)
		(end 389.795258 -11.6586)
		(stroke
			(width 0.254)
			(type default)
		)
		(layer "In4.Cu")
	)
	(gr_line
		(start 389.795258 -13.462)
		(end 389.795258 -11.4808)
		(stroke
			(width 0.762)
			(type default)
		)
		(layer "In4.Cu")
	)
	(gr_line
		(start 389.795258 -11.6586)
		(end 389.896858 -11.6586)
		(stroke
			(width 0.254)
			(type default)
		)
		(layer "In4.Cu")
	)
	(gr_line
		(start 389.795258 -9.261856)
		(end 389.795258 -7.458456)
		(stroke
			(width 0.254)
			(type default)
		)
		(layer "In4.Cu")
	)
	(gr_line
		(start 389.795258 -9.261856)
		(end 389.795258 -7.280656)
		(stroke
			(width 0.762)
			(type default)
		)
		(layer "In4.Cu")
	)
	(gr_line
		(start 389.795258 -7.458456)
		(end 389.896858 -7.458456)
		(stroke
			(width 0.254)
			(type default)
		)
		(layer "In4.Cu")
	)
	(gr_line
		(start 389.896858 -13.5636)
		(end 389.846058 -13.5636)
		(stroke
			(width 0.254)
			(type default)
		)
		(layer "In4.Cu")
	)
	(gr_line
		(start 389.896858 -11.6586)
		(end 389.896858 -13.5636)
		(stroke
			(width 0.254)
			(type default)
		)
		(layer "In4.Cu")
	)
	(gr_line
		(start 389.896858 -9.363456)
		(end 389.846058 -9.363456)
		(stroke
			(width 0.254)
			(type default)
		)
		(layer "In4.Cu")
	)
	(gr_line
		(start 389.896858 -7.458456)
		(end 389.896858 -9.363456)
		(stroke
			(width 0.254)
			(type default)
		)
		(layer "In4.Cu")
	)
	(gr_line
		(start 389.947658 -13.4874)
		(end 389.947658 -11.5062)
		(stroke
			(width 0.762)
			(type default)
		)
		(layer "In4.Cu")
	)
	(gr_line
		(start 389.947658 -9.287256)
		(end 389.947658 -7.306056)
		(stroke
			(width 0.762)
			(type default)
		)
		(layer "In4.Cu")
	)
	(gr_line
		(start 390.023858 -13.462)
		(end 389.795258 -13.462)
		(stroke
			(width 0.254)
			(type default)
		)
		(layer "In4.Cu")
	)
	(gr_line
		(start 390.023858 -11.5062)
		(end 390.023858 -13.462)
		(stroke
			(width 0.254)
			(type default)
		)
		(layer "In4.Cu")
	)
	(gr_line
		(start 390.023858 -9.261856)
		(end 389.795258 -9.261856)
		(stroke
			(width 0.254)
			(type default)
		)
		(layer "In4.Cu")
	)
	(gr_line
		(start 390.023858 -7.306056)
		(end 390.023858 -9.261856)
		(stroke
			(width 0.254)
			(type default)
		)
		(layer "In4.Cu")
	)
	(gr_line
		(start 390.074658 -13.8176)
		(end 390.074658 -13.7668)
		(stroke
			(width 0.1016)
			(type default)
		)
		(layer "In4.Cu")
	)
	(gr_line
		(start 390.074658 -13.8176)
		(end 390.481058 -13.8176)
		(stroke
			(width 0.1016)
			(type default)
		)
		(layer "In4.Cu")
	)
	(gr_line
		(start 390.074658 -13.7668)
		(end 389.312658 -13.7668)
		(stroke
			(width 0.1016)
			(type default)
		)
		(layer "In4.Cu")
	)
	(gr_line
		(start 390.074658 -13.4874)
		(end 390.074658 -11.5062)
		(stroke
			(width 0.762)
			(type default)
		)
		(layer "In4.Cu")
	)
	(gr_line
		(start 390.074658 -9.617456)
		(end 390.074658 -9.566656)
		(stroke
			(width 0.1016)
			(type default)
		)
		(layer "In4.Cu")
	)
	(gr_line
		(start 390.074658 -9.617456)
		(end 390.481058 -9.617456)
		(stroke
			(width 0.1016)
			(type default)
		)
		(layer "In4.Cu")
	)
	(gr_line
		(start 390.074658 -9.566656)
		(end 389.312658 -9.566656)
		(stroke
			(width 0.1016)
			(type default)
		)
		(layer "In4.Cu")
	)
	(gr_line
		(start 390.074658 -9.287256)
		(end 390.074658 -7.306056)
		(stroke
			(width 0.762)
			(type default)
		)
		(layer "In4.Cu")
	)
	(gr_line
		(start 390.100058 -13.5382)
		(end 389.693658 -13.5382)
		(stroke
			(width 0.254)
			(type default)
		)
		(layer "In4.Cu")
	)
	(gr_line
		(start 390.100058 -11.43)
		(end 390.100058 -13.5382)
		(stroke
			(width 0.254)
			(type default)
		)
		(layer "In4.Cu")
	)
	(gr_line
		(start 390.100058 -9.338056)
		(end 389.693658 -9.338056)
		(stroke
			(width 0.254)
			(type default)
		)
		(layer "In4.Cu")
	)
	(gr_line
		(start 390.100058 -7.229856)
		(end 390.100058 -9.338056)
		(stroke
			(width 0.254)
			(type default)
		)
		(layer "In4.Cu")
	)
	(gr_line
		(start 390.150858 -13.4874)
		(end 390.150858 -11.5062)
		(stroke
			(width 0.762)
			(type default)
		)
		(layer "In4.Cu")
	)
	(gr_line
		(start 390.150858 -9.287256)
		(end 390.150858 -7.306056)
		(stroke
			(width 0.762)
			(type default)
		)
		(layer "In4.Cu")
	)
	(gr_line
		(start 390.176258 -13.6144)
		(end 389.617458 -13.6144)
		(stroke
			(width 0.254)
			(type default)
		)
		(layer "In4.Cu")
	)
	(gr_line
		(start 390.176258 -11.3792)
		(end 390.176258 -13.6144)
		(stroke
			(width 0.254)
			(type default)
		)
		(layer "In4.Cu")
	)
	(gr_line
		(start 390.176258 -9.414256)
		(end 389.617458 -9.414256)
		(stroke
			(width 0.254)
			(type default)
		)
		(layer "In4.Cu")
	)
	(gr_line
		(start 390.176258 -7.179056)
		(end 390.176258 -9.414256)
		(stroke
			(width 0.254)
			(type default)
		)
		(layer "In4.Cu")
	)
	(gr_line
		(start 390.252458 -13.6398)
		(end 389.541258 -13.6398)
		(stroke
			(width 0.254)
			(type default)
		)
		(layer "In4.Cu")
	)
	(gr_line
		(start 390.252458 -11.303)
		(end 390.252458 -13.6398)
		(stroke
			(width 0.254)
			(type default)
		)
		(layer "In4.Cu")
	)
	(gr_line
		(start 390.252458 -9.439656)
		(end 389.541258 -9.439656)
		(stroke
			(width 0.254)
			(type default)
		)
		(layer "In4.Cu")
	)
	(gr_line
		(start 390.252458 -7.102856)
		(end 390.252458 -9.439656)
		(stroke
			(width 0.254)
			(type default)
		)
		(layer "In4.Cu")
	)
	(gr_line
		(start 390.277858 -13.7668)
		(end 389.287258 -13.7668)
		(stroke
			(width 0.1016)
			(type default)
		)
		(layer "In4.Cu")
	)
	(gr_line
		(start 390.277858 -13.6906)
		(end 389.465058 -13.6906)
		(stroke
			(width 0.254)
			(type default)
		)
		(layer "In4.Cu")
	)
	(gr_line
		(start 390.277858 -11.2776)
		(end 390.277858 -13.6906)
		(stroke
			(width 0.254)
			(type default)
		)
		(layer "In4.Cu")
	)
	(gr_line
		(start 390.277858 -9.566656)
		(end 389.287258 -9.566656)
		(stroke
			(width 0.1016)
			(type default)
		)
		(layer "In4.Cu")
	)
	(gr_line
		(start 390.277858 -9.490456)
		(end 389.465058 -9.490456)
		(stroke
			(width 0.254)
			(type default)
		)
		(layer "In4.Cu")
	)
	(gr_line
		(start 390.277858 -7.077456)
		(end 390.277858 -9.490456)
		(stroke
			(width 0.254)
			(type default)
		)
		(layer "In4.Cu")
	)
	(gr_line
		(start 390.303258 -13.716)
		(end 389.439658 -13.716)
		(stroke
			(width 0.254)
			(type default)
		)
		(layer "In4.Cu")
	)
	(gr_line
		(start 390.303258 -11.2522)
		(end 390.303258 -13.716)
		(stroke
			(width 0.254)
			(type default)
		)
		(layer "In4.Cu")
	)
	(gr_line
		(start 390.303258 -9.515856)
		(end 389.439658 -9.515856)
		(stroke
			(width 0.254)
			(type default)
		)
		(layer "In4.Cu")
	)
	(gr_line
		(start 390.303258 -7.052056)
		(end 390.303258 -9.515856)
		(stroke
			(width 0.254)
			(type default)
		)
		(layer "In4.Cu")
	)
	(gr_line
		(start 390.319768 -30.734)
		(end 389.049768 -30.734)
		(stroke
			(width 0.7874)
			(type default)
		)
		(layer "In4.Cu")
	)
	(gr_line
		(start 390.354058 -13.7414)
		(end 389.414258 -13.7414)
		(stroke
			(width 0.254)
			(type default)
		)
		(layer "In4.Cu")
	)
	(gr_line
		(start 390.354058 -11.2522)
		(end 390.354058 -13.7414)
		(stroke
			(width 0.254)
			(type default)
		)
		(layer "In4.Cu")
	)
	(gr_line
		(start 390.354058 -9.541256)
		(end 389.414258 -9.541256)
		(stroke
			(width 0.254)
			(type default)
		)
		(layer "In4.Cu")
	)
	(gr_line
		(start 390.354058 -7.052056)
		(end 390.354058 -9.541256)
		(stroke
			(width 0.254)
			(type default)
		)
		(layer "In4.Cu")
	)
	(gr_line
		(start 390.379458 -13.7414)
		(end 389.414258 -13.7414)
		(stroke
			(width 0.2032)
			(type default)
		)
		(layer "In4.Cu")
	)
	(gr_line
		(start 390.379458 -11.2014)
		(end 390.379458 -13.7414)
		(stroke
			(width 0.2032)
			(type default)
		)
		(layer "In4.Cu")
	)
	(gr_line
		(start 390.379458 -9.541256)
		(end 389.414258 -9.541256)
		(stroke
			(width 0.2032)
			(type default)
		)
		(layer "In4.Cu")
	)
	(gr_line
		(start 390.379458 -7.001256)
		(end 390.379458 -9.541256)
		(stroke
			(width 0.2032)
			(type default)
		)
		(layer "In4.Cu")
	)
	(gr_line
		(start 390.430258 -13.7668)
		(end 389.363458 -13.7668)
		(stroke
			(width 0.2032)
			(type default)
		)
		(layer "In4.Cu")
	)
	(gr_line
		(start 390.430258 -11.2014)
		(end 390.430258 -13.7668)
		(stroke
			(width 0.2032)
			(type default)
		)
		(layer "In4.Cu")
	)
	(gr_line
		(start 390.430258 -9.566656)
		(end 389.363458 -9.566656)
		(stroke
			(width 0.2032)
			(type default)
		)
		(layer "In4.Cu")
	)
	(gr_line
		(start 390.430258 -7.001256)
		(end 390.430258 -9.566656)
		(stroke
			(width 0.2032)
			(type default)
		)
		(layer "In4.Cu")
	)
	(gr_line
		(start 390.455658 -13.7668)
		(end 389.338058 -13.7668)
		(stroke
			(width 0.1016)
			(type default)
		)
		(layer "In4.Cu")
	)
	(gr_line
		(start 390.455658 -11.176)
		(end 390.455658 -13.7668)
		(stroke
			(width 0.1016)
			(type default)
		)
		(layer "In4.Cu")
	)
	(gr_line
		(start 390.455658 -9.566656)
		(end 389.338058 -9.566656)
		(stroke
			(width 0.1016)
			(type default)
		)
		(layer "In4.Cu")
	)
	(gr_line
		(start 390.455658 -6.975856)
		(end 390.455658 -9.566656)
		(stroke
			(width 0.1016)
			(type default)
		)
		(layer "In4.Cu")
	)
	(gr_line
		(start 390.481058 -13.8176)
		(end 390.074658 -13.8176)
		(stroke
			(width 0.1016)
			(type default)
		)
		(layer "In4.Cu")
	)
	(gr_line
		(start 390.481058 -13.8176)
		(end 390.481058 -11.1506)
		(stroke
			(width 0.1016)
			(type default)
		)
		(layer "In4.Cu")
	)
	(gr_line
		(start 390.481058 -11.1506)
		(end 389.287258 -11.1506)
		(stroke
			(width 0.1016)
			(type default)
		)
		(layer "In4.Cu")
	)
	(gr_line
		(start 390.481058 -11.1506)
		(end 390.481058 -13.8176)
		(stroke
			(width 0.1016)
			(type default)
		)
		(layer "In4.Cu")
	)
	(gr_line
		(start 390.481058 -9.617456)
		(end 390.074658 -9.617456)
		(stroke
			(width 0.1016)
			(type default)
		)
		(layer "In4.Cu")
	)
	(gr_line
		(start 390.481058 -9.617456)
		(end 390.481058 -6.950456)
		(stroke
			(width 0.1016)
			(type default)
		)
		(layer "In4.Cu")
	)
	(gr_line
		(start 390.481058 -6.950456)
		(end 389.287258 -6.950456)
		(stroke
			(width 0.1016)
			(type default)
		)
		(layer "In4.Cu")
	)
	(gr_line
		(start 390.481058 -6.950456)
		(end 390.481058 -9.617456)
		(stroke
			(width 0.1016)
			(type default)
		)
		(layer "In4.Cu")
	)
	(gr_line
		(start 391.287254 -12.563348)
		(end 392.074654 -12.563348)
		(stroke
			(width 0.1016)
			(type default)
		)
		(layer "In4.Cu")
	)
	(gr_line
		(start 391.287254 -12.512548)
		(end 391.287254 -9.896348)
		(stroke
			(width 0.1016)
			(type default)
		)
		(layer "In4.Cu")
	)
	(gr_line
		(start 391.287254 -12.463272)
		(end 392.074654 -12.463272)
		(stroke
			(width 0.1016)
			(type default)
		)
		(layer "In4.Cu")
	)
	(gr_line
		(start 391.287254 -12.412472)
		(end 391.287254 -9.796272)
		(stroke
			(width 0.1016)
			(type default)
		)
		(layer "In4.Cu")
	)
	(gr_line
		(start 391.287254 -9.896348)
		(end 391.287254 -12.563348)
		(stroke
			(width 0.1016)
			(type default)
		)
		(layer "In4.Cu")
	)
	(gr_line
		(start 391.287254 -9.896348)
		(end 392.481054 -9.896348)
		(stroke
			(width 0.1016)
			(type default)
		)
		(layer "In4.Cu")
	)
	(gr_line
		(start 391.287254 -9.796272)
		(end 391.287254 -12.463272)
		(stroke
			(width 0.1016)
			(type default)
		)
		(layer "In4.Cu")
	)
	(gr_line
		(start 391.287254 -9.796272)
		(end 392.481054 -9.796272)
		(stroke
			(width 0.1016)
			(type default)
		)
		(layer "In4.Cu")
	)
	(gr_line
		(start 391.287254 -8.363204)
		(end 392.074654 -8.363204)
		(stroke
			(width 0.1016)
			(type default)
		)
		(layer "In4.Cu")
	)
	(gr_line
		(start 391.287254 -8.312404)
		(end 391.287254 -5.696204)
		(stroke
			(width 0.1016)
			(type default)
		)
		(layer "In4.Cu")
	)
	(gr_line
		(start 391.287254 -8.263128)
		(end 392.074654 -8.263128)
		(stroke
			(width 0.1016)
			(type default)
		)
		(layer "In4.Cu")
	)
	(gr_line
		(start 391.287254 -8.212328)
		(end 391.287254 -5.596128)
		(stroke
			(width 0.1016)
			(type default)
		)
		(layer "In4.Cu")
	)
	(gr_line
		(start 391.287254 -5.696204)
		(end 391.287254 -8.363204)
		(stroke
			(width 0.1016)
			(type default)
		)
		(layer "In4.Cu")
	)
	(gr_line
		(start 391.287254 -5.696204)
		(end 392.481054 -5.696204)
		(stroke
			(width 0.1016)
			(type default)
		)
		(layer "In4.Cu")
	)
	(gr_line
		(start 391.287254 -5.596128)
		(end 391.287254 -8.263128)
		(stroke
			(width 0.1016)
			(type default)
		)
		(layer "In4.Cu")
	)
	(gr_line
		(start 391.287254 -5.596128)
		(end 392.481054 -5.596128)
		(stroke
			(width 0.1016)
			(type default)
		)
		(layer "In4.Cu")
	)
	(gr_line
		(start 391.312654 -12.512548)
		(end 391.312654 -9.921748)
		(stroke
			(width 0.1016)
			(type default)
		)
		(layer "In4.Cu")
	)
	(gr_line
		(start 391.312654 -12.412472)
		(end 391.312654 -9.821672)
		(stroke
			(width 0.1016)
			(type default)
		)
		(layer "In4.Cu")
	)
	(gr_line
		(start 391.312654 -9.921748)
		(end 392.455654 -9.921748)
		(stroke
			(width 0.1016)
			(type default)
		)
		(layer "In4.Cu")
	)
	(gr_line
		(start 391.312654 -9.821672)
		(end 392.455654 -9.821672)
		(stroke
			(width 0.1016)
			(type default)
		)
		(layer "In4.Cu")
	)
	(gr_line
		(start 391.312654 -8.312404)
		(end 391.312654 -5.721604)
		(stroke
			(width 0.1016)
			(type default)
		)
		(layer "In4.Cu")
	)
	(gr_line
		(start 391.312654 -8.212328)
		(end 391.312654 -5.621528)
		(stroke
			(width 0.1016)
			(type default)
		)
		(layer "In4.Cu")
	)
	(gr_line
		(start 391.312654 -5.721604)
		(end 392.455654 -5.721604)
		(stroke
			(width 0.1016)
			(type default)
		)
		(layer "In4.Cu")
	)
	(gr_line
		(start 391.312654 -5.621528)
		(end 392.455654 -5.621528)
		(stroke
			(width 0.1016)
			(type default)
		)
		(layer "In4.Cu")
	)
	(gr_line
		(start 391.338054 -12.512548)
		(end 391.338054 -9.947148)
		(stroke
			(width 0.1016)
			(type default)
		)
		(layer "In4.Cu")
	)
	(gr_line
		(start 391.338054 -12.412472)
		(end 391.338054 -9.847072)
		(stroke
			(width 0.1016)
			(type default)
		)
		(layer "In4.Cu")
	)
	(gr_line
		(start 391.338054 -9.947148)
		(end 391.592054 -9.947148)
		(stroke
			(width 0.1016)
			(type default)
		)
		(layer "In4.Cu")
	)
	(gr_line
		(start 391.338054 -9.847072)
		(end 391.592054 -9.847072)
		(stroke
			(width 0.1016)
			(type default)
		)
		(layer "In4.Cu")
	)
	(gr_line
		(start 391.338054 -8.312404)
		(end 391.338054 -5.747004)
		(stroke
			(width 0.1016)
			(type default)
		)
		(layer "In4.Cu")
	)
	(gr_line
		(start 391.338054 -8.212328)
		(end 391.338054 -5.646928)
		(stroke
			(width 0.1016)
			(type default)
		)
		(layer "In4.Cu")
	)
	(gr_line
		(start 391.338054 -5.747004)
		(end 391.592054 -5.747004)
		(stroke
			(width 0.1016)
			(type default)
		)
		(layer "In4.Cu")
	)
	(gr_line
		(start 391.338054 -5.646928)
		(end 391.592054 -5.646928)
		(stroke
			(width 0.1016)
			(type default)
		)
		(layer "In4.Cu")
	)
	(gr_line
		(start 391.363454 -12.512548)
		(end 391.363454 -9.947148)
		(stroke
			(width 0.2032)
			(type default)
		)
		(layer "In4.Cu")
	)
	(gr_line
		(start 391.363454 -12.412472)
		(end 391.363454 -9.847072)
		(stroke
			(width 0.2032)
			(type default)
		)
		(layer "In4.Cu")
	)
	(gr_line
		(start 391.363454 -9.947148)
		(end 392.379454 -9.947148)
		(stroke
			(width 0.2032)
			(type default)
		)
		(layer "In4.Cu")
	)
	(gr_line
		(start 391.363454 -9.847072)
		(end 392.379454 -9.847072)
		(stroke
			(width 0.2032)
			(type default)
		)
		(layer "In4.Cu")
	)
	(gr_line
		(start 391.363454 -8.312404)
		(end 391.363454 -5.747004)
		(stroke
			(width 0.2032)
			(type default)
		)
		(layer "In4.Cu")
	)
	(gr_line
		(start 391.363454 -8.212328)
		(end 391.363454 -5.646928)
		(stroke
			(width 0.2032)
			(type default)
		)
		(layer "In4.Cu")
	)
	(gr_line
		(start 391.363454 -5.747004)
		(end 392.379454 -5.747004)
		(stroke
			(width 0.2032)
			(type default)
		)
		(layer "In4.Cu")
	)
	(gr_line
		(start 391.363454 -5.646928)
		(end 392.379454 -5.646928)
		(stroke
			(width 0.2032)
			(type default)
		)
		(layer "In4.Cu")
	)
	(gr_line
		(start 391.414254 -12.487148)
		(end 391.414254 -9.997948)
		(stroke
			(width 0.2032)
			(type default)
		)
		(layer "In4.Cu")
	)
	(gr_line
		(start 391.414254 -12.487148)
		(end 391.414254 -9.997948)
		(stroke
			(width 0.254)
			(type default)
		)
		(layer "In4.Cu")
	)
	(gr_line
		(start 391.414254 -12.387072)
		(end 391.414254 -9.897872)
		(stroke
			(width 0.2032)
			(type default)
		)
		(layer "In4.Cu")
	)
	(gr_line
		(start 391.414254 -12.387072)
		(end 391.414254 -9.897872)
		(stroke
			(width 0.254)
			(type default)
		)
		(layer "In4.Cu")
	)
	(gr_line
		(start 391.414254 -9.997948)
		(end 391.617454 -9.997948)
		(stroke
			(width 0.2032)
			(type default)
		)
		(layer "In4.Cu")
	)
	(gr_line
		(start 391.414254 -9.997948)
		(end 392.303254 -9.997948)
		(stroke
			(width 0.254)
			(type default)
		)
		(layer "In4.Cu")
	)
	(gr_line
		(start 391.414254 -9.897872)
		(end 391.617454 -9.897872)
		(stroke
			(width 0.2032)
			(type default)
		)
		(layer "In4.Cu")
	)
	(gr_line
		(start 391.414254 -9.897872)
		(end 392.303254 -9.897872)
		(stroke
			(width 0.254)
			(type default)
		)
		(layer "In4.Cu")
	)
	(gr_line
		(start 391.414254 -8.287004)
		(end 391.414254 -5.797804)
		(stroke
			(width 0.2032)
			(type default)
		)
		(layer "In4.Cu")
	)
	(gr_line
		(start 391.414254 -8.287004)
		(end 391.414254 -5.797804)
		(stroke
			(width 0.254)
			(type default)
		)
		(layer "In4.Cu")
	)
	(gr_line
		(start 391.414254 -8.186928)
		(end 391.414254 -5.697728)
		(stroke
			(width 0.2032)
			(type default)
		)
		(layer "In4.Cu")
	)
	(gr_line
		(start 391.414254 -8.186928)
		(end 391.414254 -5.697728)
		(stroke
			(width 0.254)
			(type default)
		)
		(layer "In4.Cu")
	)
	(gr_line
		(start 391.414254 -5.797804)
		(end 391.617454 -5.797804)
		(stroke
			(width 0.2032)
			(type default)
		)
		(layer "In4.Cu")
	)
	(gr_line
		(start 391.414254 -5.797804)
		(end 392.303254 -5.797804)
		(stroke
			(width 0.254)
			(type default)
		)
		(layer "In4.Cu")
	)
	(gr_line
		(start 391.414254 -5.697728)
		(end 391.617454 -5.697728)
		(stroke
			(width 0.2032)
			(type default)
		)
		(layer "In4.Cu")
	)
	(gr_line
		(start 391.414254 -5.697728)
		(end 392.303254 -5.697728)
		(stroke
			(width 0.254)
			(type default)
		)
		(layer "In4.Cu")
	)
	(gr_line
		(start 391.439654 -12.461748)
		(end 391.439654 -10.023348)
		(stroke
			(width 0.254)
			(type default)
		)
		(layer "In4.Cu")
	)
	(gr_line
		(start 391.439654 -12.361672)
		(end 391.439654 -9.923272)
		(stroke
			(width 0.254)
			(type default)
		)
		(layer "In4.Cu")
	)
	(gr_line
		(start 391.439654 -10.023348)
		(end 392.277854 -10.023348)
		(stroke
			(width 0.254)
			(type default)
		)
		(layer "In4.Cu")
	)
	(gr_line
		(start 391.439654 -9.923272)
		(end 392.277854 -9.923272)
		(stroke
			(width 0.254)
			(type default)
		)
		(layer "In4.Cu")
	)
	(gr_line
		(start 391.439654 -8.261604)
		(end 391.439654 -5.823204)
		(stroke
			(width 0.254)
			(type default)
		)
		(layer "In4.Cu")
	)
	(gr_line
		(start 391.439654 -8.161528)
		(end 391.439654 -5.723128)
		(stroke
			(width 0.254)
			(type default)
		)
		(layer "In4.Cu")
	)
	(gr_line
		(start 391.439654 -5.823204)
		(end 392.277854 -5.823204)
		(stroke
			(width 0.254)
			(type default)
		)
		(layer "In4.Cu")
	)
	(gr_line
		(start 391.439654 -5.723128)
		(end 392.277854 -5.723128)
		(stroke
			(width 0.254)
			(type default)
		)
		(layer "In4.Cu")
	)
	(gr_line
		(start 391.465054 -12.436348)
		(end 391.465054 -10.048748)
		(stroke
			(width 0.254)
			(type default)
		)
		(layer "In4.Cu")
	)
	(gr_line
		(start 391.465054 -12.336272)
		(end 391.465054 -9.948672)
		(stroke
			(width 0.254)
			(type default)
		)
		(layer "In4.Cu")
	)
	(gr_line
		(start 391.465054 -10.048748)
		(end 392.252454 -10.048748)
		(stroke
			(width 0.254)
			(type default)
		)
		(layer "In4.Cu")
	)
	(gr_line
		(start 391.465054 -9.948672)
		(end 392.252454 -9.948672)
		(stroke
			(width 0.254)
			(type default)
		)
		(layer "In4.Cu")
	)
	(gr_line
		(start 391.465054 -8.236204)
		(end 391.465054 -5.848604)
		(stroke
			(width 0.254)
			(type default)
		)
		(layer "In4.Cu")
	)
	(gr_line
		(start 391.465054 -8.136128)
		(end 391.465054 -5.748528)
		(stroke
			(width 0.254)
			(type default)
		)
		(layer "In4.Cu")
	)
	(gr_line
		(start 391.465054 -5.848604)
		(end 392.252454 -5.848604)
		(stroke
			(width 0.254)
			(type default)
		)
		(layer "In4.Cu")
	)
	(gr_line
		(start 391.465054 -5.748528)
		(end 392.252454 -5.748528)
		(stroke
			(width 0.254)
			(type default)
		)
		(layer "In4.Cu")
	)
	(gr_line
		(start 391.490454 -12.360148)
		(end 392.125454 -12.360148)
		(stroke
			(width 0.508)
			(type default)
		)
		(layer "In4.Cu")
	)
	(gr_line
		(start 391.490454 -12.260072)
		(end 392.125454 -12.260072)
		(stroke
			(width 0.508)
			(type default)
		)
		(layer "In4.Cu")
	)
	(gr_line
		(start 391.490454 -10.175748)
		(end 392.125454 -10.175748)
		(stroke
			(width 0.508)
			(type default)
		)
		(layer "In4.Cu")
	)
	(gr_line
		(start 391.490454 -10.124948)
		(end 392.125454 -10.124948)
		(stroke
			(width 0.508)
			(type default)
		)
		(layer "In4.Cu")
	)
	(gr_line
		(start 391.490454 -10.075672)
		(end 392.125454 -10.075672)
		(stroke
			(width 0.508)
			(type default)
		)
		(layer "In4.Cu")
	)
	(gr_line
		(start 391.490454 -10.024872)
		(end 392.125454 -10.024872)
		(stroke
			(width 0.508)
			(type default)
		)
		(layer "In4.Cu")
	)
	(gr_line
		(start 391.490454 -8.160004)
		(end 392.125454 -8.160004)
		(stroke
			(width 0.508)
			(type default)
		)
		(layer "In4.Cu")
	)
	(gr_line
		(start 391.490454 -8.059928)
		(end 392.125454 -8.059928)
		(stroke
			(width 0.508)
			(type default)
		)
		(layer "In4.Cu")
	)
	(gr_line
		(start 391.490454 -5.975604)
		(end 392.125454 -5.975604)
		(stroke
			(width 0.508)
			(type default)
		)
		(layer "In4.Cu")
	)
	(gr_line
		(start 391.490454 -5.924804)
		(end 392.125454 -5.924804)
		(stroke
			(width 0.508)
			(type default)
		)
		(layer "In4.Cu")
	)
	(gr_line
		(start 391.490454 -5.875528)
		(end 392.125454 -5.875528)
		(stroke
			(width 0.508)
			(type default)
		)
		(layer "In4.Cu")
	)
	(gr_line
		(start 391.490454 -5.824728)
		(end 392.125454 -5.824728)
		(stroke
			(width 0.508)
			(type default)
		)
		(layer "In4.Cu")
	)
	(gr_line
		(start 391.515854 -10.429748)
		(end 392.150854 -10.429748)
		(stroke
			(width 0.508)
			(type default)
		)
		(layer "In4.Cu")
	)
	(gr_line
		(start 391.515854 -10.329672)
		(end 392.150854 -10.329672)
		(stroke
			(width 0.508)
			(type default)
		)
		(layer "In4.Cu")
	)
	(gr_line
		(start 391.515854 -6.229604)
		(end 392.150854 -6.229604)
		(stroke
			(width 0.508)
			(type default)
		)
		(layer "In4.Cu")
	)
	(gr_line
		(start 391.515854 -6.129528)
		(end 392.150854 -6.129528)
		(stroke
			(width 0.508)
			(type default)
		)
		(layer "In4.Cu")
	)
	(gr_line
		(start 391.541254 -12.385548)
		(end 391.541254 -10.124948)
		(stroke
			(width 0.254)
			(type default)
		)
		(layer "In4.Cu")
	)
	(gr_line
		(start 391.541254 -12.285472)
		(end 391.541254 -10.024872)
		(stroke
			(width 0.254)
			(type default)
		)
		(layer "In4.Cu")
	)
	(gr_line
		(start 391.541254 -12.233148)
		(end 392.176254 -12.233148)
		(stroke
			(width 0.508)
			(type default)
		)
		(layer "In4.Cu")
	)
	(gr_line
		(start 391.541254 -12.133072)
		(end 392.176254 -12.133072)
		(stroke
			(width 0.508)
			(type default)
		)
		(layer "In4.Cu")
	)
	(gr_line
		(start 391.541254 -10.124948)
		(end 392.176254 -10.124948)
		(stroke
			(width 0.254)
			(type default)
		)
		(layer "In4.Cu")
	)
	(gr_line
		(start 391.541254 -10.024872)
		(end 392.176254 -10.024872)
		(stroke
			(width 0.254)
			(type default)
		)
		(layer "In4.Cu")
	)
	(gr_line
		(start 391.541254 -8.185404)
		(end 391.541254 -5.924804)
		(stroke
			(width 0.254)
			(type default)
		)
		(layer "In4.Cu")
	)
	(gr_line
		(start 391.541254 -8.085328)
		(end 391.541254 -5.824728)
		(stroke
			(width 0.254)
			(type default)
		)
		(layer "In4.Cu")
	)
	(gr_line
		(start 391.541254 -8.033004)
		(end 392.176254 -8.033004)
		(stroke
			(width 0.508)
			(type default)
		)
		(layer "In4.Cu")
	)
	(gr_line
		(start 391.541254 -7.932928)
		(end 392.176254 -7.932928)
		(stroke
			(width 0.508)
			(type default)
		)
		(layer "In4.Cu")
	)
	(gr_line
		(start 391.541254 -5.924804)
		(end 392.176254 -5.924804)
		(stroke
			(width 0.254)
			(type default)
		)
		(layer "In4.Cu")
	)
	(gr_line
		(start 391.541254 -5.824728)
		(end 392.176254 -5.824728)
		(stroke
			(width 0.254)
			(type default)
		)
		(layer "In4.Cu")
	)
	(gr_line
		(start 391.566654 -12.080748)
		(end 392.201654 -12.080748)
		(stroke
			(width 0.508)
			(type default)
		)
		(layer "In4.Cu")
	)
	(gr_line
		(start 391.566654 -11.980672)
		(end 392.201654 -11.980672)
		(stroke
			(width 0.508)
			(type default)
		)
		(layer "In4.Cu")
	)
	(gr_line
		(start 391.566654 -7.880604)
		(end 392.201654 -7.880604)
		(stroke
			(width 0.508)
			(type default)
		)
		(layer "In4.Cu")
	)
	(gr_line
		(start 391.566654 -7.780528)
		(end 392.201654 -7.780528)
		(stroke
			(width 0.508)
			(type default)
		)
		(layer "In4.Cu")
	)
	(gr_line
		(start 391.592054 -12.360148)
		(end 392.227054 -12.360148)
		(stroke
			(width 0.508)
			(type default)
		)
		(layer "In4.Cu")
	)
	(gr_line
		(start 391.592054 -12.260072)
		(end 392.227054 -12.260072)
		(stroke
			(width 0.508)
			(type default)
		)
		(layer "In4.Cu")
	)
	(gr_line
		(start 391.592054 -9.947148)
		(end 392.430254 -9.947148)
		(stroke
			(width 0.2032)
			(type default)
		)
		(layer "In4.Cu")
	)
	(gr_line
		(start 391.592054 -9.847072)
		(end 392.430254 -9.847072)
		(stroke
			(width 0.2032)
			(type default)
		)
		(layer "In4.Cu")
	)
	(gr_line
		(start 391.592054 -8.160004)
		(end 392.227054 -8.160004)
		(stroke
			(width 0.508)
			(type default)
		)
		(layer "In4.Cu")
	)
	(gr_line
		(start 391.592054 -8.059928)
		(end 392.227054 -8.059928)
		(stroke
			(width 0.508)
			(type default)
		)
		(layer "In4.Cu")
	)
	(gr_line
		(start 391.592054 -5.747004)
		(end 392.430254 -5.747004)
		(stroke
			(width 0.2032)
			(type default)
		)
		(layer "In4.Cu")
	)
	(gr_line
		(start 391.592054 -5.646928)
		(end 392.430254 -5.646928)
		(stroke
			(width 0.2032)
			(type default)
		)
		(layer "In4.Cu")
	)
	(gr_line
		(start 391.617454 -12.360148)
		(end 391.617454 -10.175748)
		(stroke
			(width 0.254)
			(type default)
		)
		(layer "In4.Cu")
	)
	(gr_line
		(start 391.617454 -12.260072)
		(end 391.617454 -10.075672)
		(stroke
			(width 0.254)
			(type default)
		)
		(layer "In4.Cu")
	)
	(gr_line
		(start 391.617454 -10.175748)
		(end 392.100054 -10.175748)
		(stroke
			(width 0.254)
			(type default)
		)
		(layer "In4.Cu")
	)
	(gr_line
		(start 391.617454 -10.075672)
		(end 392.100054 -10.075672)
		(stroke
			(width 0.254)
			(type default)
		)
		(layer "In4.Cu")
	)
	(gr_line
		(start 391.617454 -9.997948)
		(end 392.354054 -9.997948)
		(stroke
			(width 0.254)
			(type default)
		)
		(layer "In4.Cu")
	)
	(gr_line
		(start 391.617454 -9.897872)
		(end 392.354054 -9.897872)
		(stroke
			(width 0.254)
			(type default)
		)
		(layer "In4.Cu")
	)
	(gr_line
		(start 391.617454 -8.160004)
		(end 391.617454 -5.975604)
		(stroke
			(width 0.254)
			(type default)
		)
		(layer "In4.Cu")
	)
	(gr_line
		(start 391.617454 -8.059928)
		(end 391.617454 -5.875528)
		(stroke
			(width 0.254)
			(type default)
		)
		(layer "In4.Cu")
	)
	(gr_line
		(start 391.617454 -5.975604)
		(end 392.100054 -5.975604)
		(stroke
			(width 0.254)
			(type default)
		)
		(layer "In4.Cu")
	)
	(gr_line
		(start 391.617454 -5.875528)
		(end 392.100054 -5.875528)
		(stroke
			(width 0.254)
			(type default)
		)
		(layer "In4.Cu")
	)
	(gr_line
		(start 391.617454 -5.797804)
		(end 392.354054 -5.797804)
		(stroke
			(width 0.254)
			(type default)
		)
		(layer "In4.Cu")
	)
	(gr_line
		(start 391.617454 -5.697728)
		(end 392.354054 -5.697728)
		(stroke
			(width 0.254)
			(type default)
		)
		(layer "In4.Cu")
	)
	(gr_line
		(start 391.635996 -10.110978)
		(end 392.270996 -10.110978)
		(stroke
			(width 0.508)
			(type default)
		)
		(layer "In4.Cu")
	)
	(gr_line
		(start 391.635996 -10.010902)
		(end 392.270996 -10.010902)
		(stroke
			(width 0.508)
			(type default)
		)
		(layer "In4.Cu")
	)
	(gr_line
		(start 391.635996 -5.910834)
		(end 392.270996 -5.910834)
		(stroke
			(width 0.508)
			(type default)
		)
		(layer "In4.Cu")
	)
	(gr_line
		(start 391.635996 -5.810758)
		(end 392.270996 -5.810758)
		(stroke
			(width 0.508)
			(type default)
		)
		(layer "In4.Cu")
	)
	(gr_line
		(start 391.642854 -12.360148)
		(end 392.277854 -12.360148)
		(stroke
			(width 0.508)
			(type default)
		)
		(layer "In4.Cu")
	)
	(gr_line
		(start 391.642854 -12.260072)
		(end 392.277854 -12.260072)
		(stroke
			(width 0.508)
			(type default)
		)
		(layer "In4.Cu")
	)
	(gr_line
		(start 391.642854 -12.233148)
		(end 391.642854 -10.251948)
		(stroke
			(width 0.762)
			(type default)
		)
		(layer "In4.Cu")
	)
	(gr_line
		(start 391.642854 -12.133072)
		(end 391.642854 -10.151872)
		(stroke
			(width 0.762)
			(type default)
		)
		(layer "In4.Cu")
	)
	(gr_line
		(start 391.642854 -10.251948)
		(end 392.277854 -10.251948)
		(stroke
			(width 0.508)
			(type default)
		)
		(layer "In4.Cu")
	)
	(gr_line
		(start 391.642854 -10.151872)
		(end 392.277854 -10.151872)
		(stroke
			(width 0.508)
			(type default)
		)
		(layer "In4.Cu")
	)
	(gr_line
		(start 391.642854 -8.160004)
		(end 392.277854 -8.160004)
		(stroke
			(width 0.508)
			(type default)
		)
		(layer "In4.Cu")
	)
	(gr_line
		(start 391.642854 -8.059928)
		(end 392.277854 -8.059928)
		(stroke
			(width 0.508)
			(type default)
		)
		(layer "In4.Cu")
	)
	(gr_line
		(start 391.642854 -8.033004)
		(end 391.642854 -6.051804)
		(stroke
			(width 0.762)
			(type default)
		)
		(layer "In4.Cu")
	)
	(gr_line
		(start 391.642854 -7.932928)
		(end 391.642854 -5.951728)
		(stroke
			(width 0.762)
			(type default)
		)
		(layer "In4.Cu")
	)
	(gr_line
		(start 391.642854 -6.051804)
		(end 392.277854 -6.051804)
		(stroke
			(width 0.508)
			(type default)
		)
		(layer "In4.Cu")
	)
	(gr_line
		(start 391.642854 -5.951728)
		(end 392.277854 -5.951728)
		(stroke
			(width 0.508)
			(type default)
		)
		(layer "In4.Cu")
	)
	(gr_line
		(start 391.693654 -12.283948)
		(end 391.693654 -10.251948)
		(stroke
			(width 0.254)
			(type default)
		)
		(layer "In4.Cu")
	)
	(gr_line
		(start 391.693654 -12.183872)
		(end 391.693654 -10.151872)
		(stroke
			(width 0.254)
			(type default)
		)
		(layer "In4.Cu")
	)
	(gr_line
		(start 391.693654 -10.251948)
		(end 392.023854 -10.251948)
		(stroke
			(width 0.254)
			(type default)
		)
		(layer "In4.Cu")
	)
	(gr_line
		(start 391.693654 -10.151872)
		(end 392.023854 -10.151872)
		(stroke
			(width 0.254)
			(type default)
		)
		(layer "In4.Cu")
	)
	(gr_line
		(start 391.693654 -8.083804)
		(end 391.693654 -6.051804)
		(stroke
			(width 0.254)
			(type default)
		)
		(layer "In4.Cu")
	)
	(gr_line
		(start 391.693654 -7.983728)
		(end 391.693654 -5.951728)
		(stroke
			(width 0.254)
			(type default)
		)
		(layer "In4.Cu")
	)
	(gr_line
		(start 391.693654 -6.051804)
		(end 392.023854 -6.051804)
		(stroke
			(width 0.254)
			(type default)
		)
		(layer "In4.Cu")
	)
	(gr_line
		(start 391.693654 -5.951728)
		(end 392.023854 -5.951728)
		(stroke
			(width 0.254)
			(type default)
		)
		(layer "In4.Cu")
	)
	(gr_line
		(start 391.795254 -12.207748)
		(end 391.795254 -10.404348)
		(stroke
			(width 0.254)
			(type default)
		)
		(layer "In4.Cu")
	)
	(gr_line
		(start 391.795254 -12.207748)
		(end 391.795254 -10.226548)
		(stroke
			(width 0.762)
			(type default)
		)
		(layer "In4.Cu")
	)
	(gr_line
		(start 391.795254 -12.107672)
		(end 391.795254 -10.304272)
		(stroke
			(width 0.254)
			(type default)
		)
		(layer "In4.Cu")
	)
	(gr_line
		(start 391.795254 -12.107672)
		(end 391.795254 -10.126472)
		(stroke
			(width 0.762)
			(type default)
		)
		(layer "In4.Cu")
	)
	(gr_line
		(start 391.795254 -10.404348)
		(end 391.896854 -10.404348)
		(stroke
			(width 0.254)
			(type default)
		)
		(layer "In4.Cu")
	)
	(gr_line
		(start 391.795254 -10.304272)
		(end 391.896854 -10.304272)
		(stroke
			(width 0.254)
			(type default)
		)
		(layer "In4.Cu")
	)
	(gr_line
		(start 391.795254 -8.007604)
		(end 391.795254 -6.204204)
		(stroke
			(width 0.254)
			(type default)
		)
		(layer "In4.Cu")
	)
	(gr_line
		(start 391.795254 -8.007604)
		(end 391.795254 -6.026404)
		(stroke
			(width 0.762)
			(type default)
		)
		(layer "In4.Cu")
	)
	(gr_line
		(start 391.795254 -7.907528)
		(end 391.795254 -6.104128)
		(stroke
			(width 0.254)
			(type default)
		)
		(layer "In4.Cu")
	)
	(gr_line
		(start 391.795254 -7.907528)
		(end 391.795254 -5.926328)
		(stroke
			(width 0.762)
			(type default)
		)
		(layer "In4.Cu")
	)
	(gr_line
		(start 391.795254 -6.204204)
		(end 391.896854 -6.204204)
		(stroke
			(width 0.254)
			(type default)
		)
		(layer "In4.Cu")
	)
	(gr_line
		(start 391.795254 -6.104128)
		(end 391.896854 -6.104128)
		(stroke
			(width 0.254)
			(type default)
		)
		(layer "In4.Cu")
	)
	(gr_line
		(start 391.850118 -23.69566)
		(end 393.120118 -23.69566)
		(stroke
			(width 0.7874)
			(type default)
		)
		(layer "In4.Cu")
	)
	(gr_line
		(start 391.896854 -12.309348)
		(end 391.846054 -12.309348)
		(stroke
			(width 0.254)
			(type default)
		)
		(layer "In4.Cu")
	)
	(gr_line
		(start 391.896854 -12.209272)
		(end 391.846054 -12.209272)
		(stroke
			(width 0.254)
			(type default)
		)
		(layer "In4.Cu")
	)
	(gr_line
		(start 391.896854 -10.404348)
		(end 391.896854 -12.309348)
		(stroke
			(width 0.254)
			(type default)
		)
		(layer "In4.Cu")
	)
	(gr_line
		(start 391.896854 -10.304272)
		(end 391.896854 -12.209272)
		(stroke
			(width 0.254)
			(type default)
		)
		(layer "In4.Cu")
	)
	(gr_line
		(start 391.896854 -8.109204)
		(end 391.846054 -8.109204)
		(stroke
			(width 0.254)
			(type default)
		)
		(layer "In4.Cu")
	)
	(gr_line
		(start 391.896854 -8.009128)
		(end 391.846054 -8.009128)
		(stroke
			(width 0.254)
			(type default)
		)
		(layer "In4.Cu")
	)
	(gr_line
		(start 391.896854 -6.204204)
		(end 391.896854 -8.109204)
		(stroke
			(width 0.254)
			(type default)
		)
		(layer "In4.Cu")
	)
	(gr_line
		(start 391.896854 -6.104128)
		(end 391.896854 -8.009128)
		(stroke
			(width 0.254)
			(type default)
		)
		(layer "In4.Cu")
	)
	(gr_line
		(start 391.947654 -12.233148)
		(end 391.947654 -10.251948)
		(stroke
			(width 0.762)
			(type default)
		)
		(layer "In4.Cu")
	)
	(gr_line
		(start 391.947654 -12.133072)
		(end 391.947654 -10.151872)
		(stroke
			(width 0.762)
			(type default)
		)
		(layer "In4.Cu")
	)
	(gr_line
		(start 391.947654 -8.033004)
		(end 391.947654 -6.051804)
		(stroke
			(width 0.762)
			(type default)
		)
		(layer "In4.Cu")
	)
	(gr_line
		(start 391.947654 -7.932928)
		(end 391.947654 -5.951728)
		(stroke
			(width 0.762)
			(type default)
		)
		(layer "In4.Cu")
	)
	(gr_line
		(start 392.023854 -12.207748)
		(end 391.795254 -12.207748)
		(stroke
			(width 0.254)
			(type default)
		)
		(layer "In4.Cu")
	)
	(gr_line
		(start 392.023854 -12.107672)
		(end 391.795254 -12.107672)
		(stroke
			(width 0.254)
			(type default)
		)
		(layer "In4.Cu")
	)
	(gr_line
		(start 392.023854 -10.251948)
		(end 392.023854 -12.207748)
		(stroke
			(width 0.254)
			(type default)
		)
		(layer "In4.Cu")
	)
	(gr_line
		(start 392.023854 -10.151872)
		(end 392.023854 -12.107672)
		(stroke
			(width 0.254)
			(type default)
		)
		(layer "In4.Cu")
	)
	(gr_line
		(start 392.023854 -8.007604)
		(end 391.795254 -8.007604)
		(stroke
			(width 0.254)
			(type default)
		)
		(layer "In4.Cu")
	)
	(gr_line
		(start 392.023854 -7.907528)
		(end 391.795254 -7.907528)
		(stroke
			(width 0.254)
			(type default)
		)
		(layer "In4.Cu")
	)
	(gr_line
		(start 392.023854 -6.051804)
		(end 392.023854 -8.007604)
		(stroke
			(width 0.254)
			(type default)
		)
		(layer "In4.Cu")
	)
	(gr_line
		(start 392.023854 -5.951728)
		(end 392.023854 -7.907528)
		(stroke
			(width 0.254)
			(type default)
		)
		(layer "In4.Cu")
	)
	(gr_line
		(start 392.074654 -12.563348)
		(end 392.074654 -12.512548)
		(stroke
			(width 0.1016)
			(type default)
		)
		(layer "In4.Cu")
	)
	(gr_line
		(start 392.074654 -12.563348)
		(end 392.481054 -12.563348)
		(stroke
			(width 0.1016)
			(type default)
		)
		(layer "In4.Cu")
	)
	(gr_line
		(start 392.074654 -12.512548)
		(end 391.312654 -12.512548)
		(stroke
			(width 0.1016)
			(type default)
		)
		(layer "In4.Cu")
	)
	(gr_line
		(start 392.074654 -12.463272)
		(end 392.074654 -12.412472)
		(stroke
			(width 0.1016)
			(type default)
		)
		(layer "In4.Cu")
	)
	(gr_line
		(start 392.074654 -12.463272)
		(end 392.481054 -12.463272)
		(stroke
			(width 0.1016)
			(type default)
		)
		(layer "In4.Cu")
	)
	(gr_line
		(start 392.074654 -12.412472)
		(end 391.312654 -12.412472)
		(stroke
			(width 0.1016)
			(type default)
		)
		(layer "In4.Cu")
	)
	(gr_line
		(start 392.074654 -12.233148)
		(end 392.074654 -10.251948)
		(stroke
			(width 0.762)
			(type default)
		)
		(layer "In4.Cu")
	)
	(gr_line
		(start 392.074654 -12.133072)
		(end 392.074654 -10.151872)
		(stroke
			(width 0.762)
			(type default)
		)
		(layer "In4.Cu")
	)
	(gr_line
		(start 392.074654 -8.363204)
		(end 392.074654 -8.312404)
		(stroke
			(width 0.1016)
			(type default)
		)
		(layer "In4.Cu")
	)
	(gr_line
		(start 392.074654 -8.363204)
		(end 392.481054 -8.363204)
		(stroke
			(width 0.1016)
			(type default)
		)
		(layer "In4.Cu")
	)
	(gr_line
		(start 392.074654 -8.312404)
		(end 391.312654 -8.312404)
		(stroke
			(width 0.1016)
			(type default)
		)
		(layer "In4.Cu")
	)
	(gr_line
		(start 392.074654 -8.263128)
		(end 392.074654 -8.212328)
		(stroke
			(width 0.1016)
			(type default)
		)
		(layer "In4.Cu")
	)
	(gr_line
		(start 392.074654 -8.263128)
		(end 392.481054 -8.263128)
		(stroke
			(width 0.1016)
			(type default)
		)
		(layer "In4.Cu")
	)
	(gr_line
		(start 392.074654 -8.212328)
		(end 391.312654 -8.212328)
		(stroke
			(width 0.1016)
			(type default)
		)
		(layer "In4.Cu")
	)
	(gr_line
		(start 392.074654 -8.033004)
		(end 392.074654 -6.051804)
		(stroke
			(width 0.762)
			(type default)
		)
		(layer "In4.Cu")
	)
	(gr_line
		(start 392.074654 -7.932928)
		(end 392.074654 -5.951728)
		(stroke
			(width 0.762)
			(type default)
		)
		(layer "In4.Cu")
	)
	(gr_line
		(start 392.100054 -12.283948)
		(end 391.693654 -12.283948)
		(stroke
			(width 0.254)
			(type default)
		)
		(layer "In4.Cu")
	)
	(gr_line
		(start 392.100054 -12.183872)
		(end 391.693654 -12.183872)
		(stroke
			(width 0.254)
			(type default)
		)
		(layer "In4.Cu")
	)
	(gr_line
		(start 392.100054 -10.175748)
		(end 392.100054 -12.283948)
		(stroke
			(width 0.254)
			(type default)
		)
		(layer "In4.Cu")
	)
	(gr_line
		(start 392.100054 -10.075672)
		(end 392.100054 -12.183872)
		(stroke
			(width 0.254)
			(type default)
		)
		(layer "In4.Cu")
	)
	(gr_line
		(start 392.100054 -8.083804)
		(end 391.693654 -8.083804)
		(stroke
			(width 0.254)
			(type default)
		)
		(layer "In4.Cu")
	)
	(gr_line
		(start 392.100054 -7.983728)
		(end 391.693654 -7.983728)
		(stroke
			(width 0.254)
			(type default)
		)
		(layer "In4.Cu")
	)
	(gr_line
		(start 392.100054 -5.975604)
		(end 392.100054 -8.083804)
		(stroke
			(width 0.254)
			(type default)
		)
		(layer "In4.Cu")
	)
	(gr_line
		(start 392.100054 -5.875528)
		(end 392.100054 -7.983728)
		(stroke
			(width 0.254)
			(type default)
		)
		(layer "In4.Cu")
	)
	(gr_line
		(start 392.150854 -12.233148)
		(end 392.150854 -10.251948)
		(stroke
			(width 0.762)
			(type default)
		)
		(layer "In4.Cu")
	)
	(gr_line
		(start 392.150854 -12.133072)
		(end 392.150854 -10.151872)
		(stroke
			(width 0.762)
			(type default)
		)
		(layer "In4.Cu")
	)
	(gr_line
		(start 392.150854 -8.033004)
		(end 392.150854 -6.051804)
		(stroke
			(width 0.762)
			(type default)
		)
		(layer "In4.Cu")
	)
	(gr_line
		(start 392.150854 -7.932928)
		(end 392.150854 -5.951728)
		(stroke
			(width 0.762)
			(type default)
		)
		(layer "In4.Cu")
	)
	(gr_line
		(start 392.176254 -12.360148)
		(end 391.617454 -12.360148)
		(stroke
			(width 0.254)
			(type default)
		)
		(layer "In4.Cu")
	)
	(gr_line
		(start 392.176254 -12.260072)
		(end 391.617454 -12.260072)
		(stroke
			(width 0.254)
			(type default)
		)
		(layer "In4.Cu")
	)
	(gr_line
		(start 392.176254 -10.124948)
		(end 392.176254 -12.360148)
		(stroke
			(width 0.254)
			(type default)
		)
		(layer "In4.Cu")
	)
	(gr_line
		(start 392.176254 -10.024872)
		(end 392.176254 -12.260072)
		(stroke
			(width 0.254)
			(type default)
		)
		(layer "In4.Cu")
	)
	(gr_line
		(start 392.176254 -8.160004)
		(end 391.617454 -8.160004)
		(stroke
			(width 0.254)
			(type default)
		)
		(layer "In4.Cu")
	)
	(gr_line
		(start 392.176254 -8.059928)
		(end 391.617454 -8.059928)
		(stroke
			(width 0.254)
			(type default)
		)
		(layer "In4.Cu")
	)
	(gr_line
		(start 392.176254 -5.924804)
		(end 392.176254 -8.160004)
		(stroke
			(width 0.254)
			(type default)
		)
		(layer "In4.Cu")
	)
	(gr_line
		(start 392.176254 -5.824728)
		(end 392.176254 -8.059928)
		(stroke
			(width 0.254)
			(type default)
		)
		(layer "In4.Cu")
	)
	(gr_line
		(start 392.252454 -12.385548)
		(end 391.541254 -12.385548)
		(stroke
			(width 0.254)
			(type default)
		)
		(layer "In4.Cu")
	)
	(gr_line
		(start 392.252454 -12.285472)
		(end 391.541254 -12.285472)
		(stroke
			(width 0.254)
			(type default)
		)
		(layer "In4.Cu")
	)
	(gr_line
		(start 392.252454 -10.048748)
		(end 392.252454 -12.385548)
		(stroke
			(width 0.254)
			(type default)
		)
		(layer "In4.Cu")
	)
	(gr_line
		(start 392.252454 -9.948672)
		(end 392.252454 -12.285472)
		(stroke
			(width 0.254)
			(type default)
		)
		(layer "In4.Cu")
	)
	(gr_line
		(start 392.252454 -8.185404)
		(end 391.541254 -8.185404)
		(stroke
			(width 0.254)
			(type default)
		)
		(layer "In4.Cu")
	)
	(gr_line
		(start 392.252454 -8.085328)
		(end 391.541254 -8.085328)
		(stroke
			(width 0.254)
			(type default)
		)
		(layer "In4.Cu")
	)
	(gr_line
		(start 392.252454 -5.848604)
		(end 392.252454 -8.185404)
		(stroke
			(width 0.254)
			(type default)
		)
		(layer "In4.Cu")
	)
	(gr_line
		(start 392.252454 -5.748528)
		(end 392.252454 -8.085328)
		(stroke
			(width 0.254)
			(type default)
		)
		(layer "In4.Cu")
	)
	(gr_line
		(start 392.277854 -12.512548)
		(end 391.287254 -12.512548)
		(stroke
			(width 0.1016)
			(type default)
		)
		(layer "In4.Cu")
	)
	(gr_line
		(start 392.277854 -12.436348)
		(end 391.465054 -12.436348)
		(stroke
			(width 0.254)
			(type default)
		)
		(layer "In4.Cu")
	)
	(gr_line
		(start 392.277854 -12.412472)
		(end 391.287254 -12.412472)
		(stroke
			(width 0.1016)
			(type default)
		)
		(layer "In4.Cu")
	)
	(gr_line
		(start 392.277854 -12.336272)
		(end 391.465054 -12.336272)
		(stroke
			(width 0.254)
			(type default)
		)
		(layer "In4.Cu")
	)
	(gr_line
		(start 392.277854 -10.023348)
		(end 392.277854 -12.436348)
		(stroke
			(width 0.254)
			(type default)
		)
		(layer "In4.Cu")
	)
	(gr_line
		(start 392.277854 -9.923272)
		(end 392.277854 -12.336272)
		(stroke
			(width 0.254)
			(type default)
		)
		(layer "In4.Cu")
	)
	(gr_line
		(start 392.277854 -8.312404)
		(end 391.287254 -8.312404)
		(stroke
			(width 0.1016)
			(type default)
		)
		(layer "In4.Cu")
	)
	(gr_line
		(start 392.277854 -8.236204)
		(end 391.465054 -8.236204)
		(stroke
			(width 0.254)
			(type default)
		)
		(layer "In4.Cu")
	)
	(gr_line
		(start 392.277854 -8.212328)
		(end 391.287254 -8.212328)
		(stroke
			(width 0.1016)
			(type default)
		)
		(layer "In4.Cu")
	)
	(gr_line
		(start 392.277854 -8.136128)
		(end 391.465054 -8.136128)
		(stroke
			(width 0.254)
			(type default)
		)
		(layer "In4.Cu")
	)
	(gr_line
		(start 392.277854 -5.823204)
		(end 392.277854 -8.236204)
		(stroke
			(width 0.254)
			(type default)
		)
		(layer "In4.Cu")
	)
	(gr_line
		(start 392.277854 -5.723128)
		(end 392.277854 -8.136128)
		(stroke
			(width 0.254)
			(type default)
		)
		(layer "In4.Cu")
	)
	(gr_line
		(start 392.303254 -12.461748)
		(end 391.439654 -12.461748)
		(stroke
			(width 0.254)
			(type default)
		)
		(layer "In4.Cu")
	)
	(gr_line
		(start 392.303254 -12.361672)
		(end 391.439654 -12.361672)
		(stroke
			(width 0.254)
			(type default)
		)
		(layer "In4.Cu")
	)
	(gr_line
		(start 392.303254 -9.997948)
		(end 392.303254 -12.461748)
		(stroke
			(width 0.254)
			(type default)
		)
		(layer "In4.Cu")
	)
	(gr_line
		(start 392.303254 -9.897872)
		(end 392.303254 -12.361672)
		(stroke
			(width 0.254)
			(type default)
		)
		(layer "In4.Cu")
	)
	(gr_line
		(start 392.303254 -8.261604)
		(end 391.439654 -8.261604)
		(stroke
			(width 0.254)
			(type default)
		)
		(layer "In4.Cu")
	)
	(gr_line
		(start 392.303254 -8.161528)
		(end 391.439654 -8.161528)
		(stroke
			(width 0.254)
			(type default)
		)
		(layer "In4.Cu")
	)
	(gr_line
		(start 392.303254 -5.797804)
		(end 392.303254 -8.261604)
		(stroke
			(width 0.254)
			(type default)
		)
		(layer "In4.Cu")
	)
	(gr_line
		(start 392.303254 -5.697728)
		(end 392.303254 -8.161528)
		(stroke
			(width 0.254)
			(type default)
		)
		(layer "In4.Cu")
	)
	(gr_line
		(start 392.354054 -12.487148)
		(end 391.414254 -12.487148)
		(stroke
			(width 0.254)
			(type default)
		)
		(layer "In4.Cu")
	)
	(gr_line
		(start 392.354054 -12.387072)
		(end 391.414254 -12.387072)
		(stroke
			(width 0.254)
			(type default)
		)
		(layer "In4.Cu")
	)
	(gr_line
		(start 392.354054 -9.997948)
		(end 392.354054 -12.487148)
		(stroke
			(width 0.254)
			(type default)
		)
		(layer "In4.Cu")
	)
	(gr_line
		(start 392.354054 -9.897872)
		(end 392.354054 -12.387072)
		(stroke
			(width 0.254)
			(type default)
		)
		(layer "In4.Cu")
	)
	(gr_line
		(start 392.354054 -8.287004)
		(end 391.414254 -8.287004)
		(stroke
			(width 0.254)
			(type default)
		)
		(layer "In4.Cu")
	)
	(gr_line
		(start 392.354054 -8.186928)
		(end 391.414254 -8.186928)
		(stroke
			(width 0.254)
			(type default)
		)
		(layer "In4.Cu")
	)
	(gr_line
		(start 392.354054 -5.797804)
		(end 392.354054 -8.287004)
		(stroke
			(width 0.254)
			(type default)
		)
		(layer "In4.Cu")
	)
	(gr_line
		(start 392.354054 -5.697728)
		(end 392.354054 -8.186928)
		(stroke
			(width 0.254)
			(type default)
		)
		(layer "In4.Cu")
	)
	(gr_line
		(start 392.379454 -12.487148)
		(end 391.414254 -12.487148)
		(stroke
			(width 0.2032)
			(type default)
		)
		(layer "In4.Cu")
	)
	(gr_line
		(start 392.379454 -12.387072)
		(end 391.414254 -12.387072)
		(stroke
			(width 0.2032)
			(type default)
		)
		(layer "In4.Cu")
	)
	(gr_line
		(start 392.379454 -9.947148)
		(end 392.379454 -12.487148)
		(stroke
			(width 0.2032)
			(type default)
		)
		(layer "In4.Cu")
	)
	(gr_line
		(start 392.379454 -9.847072)
		(end 392.379454 -12.387072)
		(stroke
			(width 0.2032)
			(type default)
		)
		(layer "In4.Cu")
	)
	(gr_line
		(start 392.379454 -8.287004)
		(end 391.414254 -8.287004)
		(stroke
			(width 0.2032)
			(type default)
		)
		(layer "In4.Cu")
	)
	(gr_line
		(start 392.379454 -8.186928)
		(end 391.414254 -8.186928)
		(stroke
			(width 0.2032)
			(type default)
		)
		(layer "In4.Cu")
	)
	(gr_line
		(start 392.379454 -5.747004)
		(end 392.379454 -8.287004)
		(stroke
			(width 0.2032)
			(type default)
		)
		(layer "In4.Cu")
	)
	(gr_line
		(start 392.379454 -5.646928)
		(end 392.379454 -8.186928)
		(stroke
			(width 0.2032)
			(type default)
		)
		(layer "In4.Cu")
	)
	(gr_line
		(start 392.430254 -12.512548)
		(end 391.363454 -12.512548)
		(stroke
			(width 0.2032)
			(type default)
		)
		(layer "In4.Cu")
	)
	(gr_line
		(start 392.430254 -12.412472)
		(end 391.363454 -12.412472)
		(stroke
			(width 0.2032)
			(type default)
		)
		(layer "In4.Cu")
	)
	(gr_line
		(start 392.430254 -9.947148)
		(end 392.430254 -12.512548)
		(stroke
			(width 0.2032)
			(type default)
		)
		(layer "In4.Cu")
	)
	(gr_line
		(start 392.430254 -9.847072)
		(end 392.430254 -12.412472)
		(stroke
			(width 0.2032)
			(type default)
		)
		(layer "In4.Cu")
	)
	(gr_line
		(start 392.430254 -8.312404)
		(end 391.363454 -8.312404)
		(stroke
			(width 0.2032)
			(type default)
		)
		(layer "In4.Cu")
	)
	(gr_line
		(start 392.430254 -8.212328)
		(end 391.363454 -8.212328)
		(stroke
			(width 0.2032)
			(type default)
		)
		(layer "In4.Cu")
	)
	(gr_line
		(start 392.430254 -5.747004)
		(end 392.430254 -8.312404)
		(stroke
			(width 0.2032)
			(type default)
		)
		(layer "In4.Cu")
	)
	(gr_line
		(start 392.430254 -5.646928)
		(end 392.430254 -8.212328)
		(stroke
			(width 0.2032)
			(type default)
		)
		(layer "In4.Cu")
	)
	(gr_line
		(start 392.455654 -12.512548)
		(end 391.338054 -12.512548)
		(stroke
			(width 0.1016)
			(type default)
		)
		(layer "In4.Cu")
	)
	(gr_line
		(start 392.455654 -12.412472)
		(end 391.338054 -12.412472)
		(stroke
			(width 0.1016)
			(type default)
		)
		(layer "In4.Cu")
	)
	(gr_line
		(start 392.455654 -9.921748)
		(end 392.455654 -12.512548)
		(stroke
			(width 0.1016)
			(type default)
		)
		(layer "In4.Cu")
	)
	(gr_line
		(start 392.455654 -9.821672)
		(end 392.455654 -12.412472)
		(stroke
			(width 0.1016)
			(type default)
		)
		(layer "In4.Cu")
	)
	(gr_line
		(start 392.455654 -8.312404)
		(end 391.338054 -8.312404)
		(stroke
			(width 0.1016)
			(type default)
		)
		(layer "In4.Cu")
	)
	(gr_line
		(start 392.455654 -8.212328)
		(end 391.338054 -8.212328)
		(stroke
			(width 0.1016)
			(type default)
		)
		(layer "In4.Cu")
	)
	(gr_line
		(start 392.455654 -5.721604)
		(end 392.455654 -8.312404)
		(stroke
			(width 0.1016)
			(type default)
		)
		(layer "In4.Cu")
	)
	(gr_line
		(start 392.455654 -5.621528)
		(end 392.455654 -8.212328)
		(stroke
			(width 0.1016)
			(type default)
		)
		(layer "In4.Cu")
	)
	(gr_line
		(start 392.481054 -12.563348)
		(end 392.074654 -12.563348)
		(stroke
			(width 0.1016)
			(type default)
		)
		(layer "In4.Cu")
	)
	(gr_line
		(start 392.481054 -12.563348)
		(end 392.481054 -9.896348)
		(stroke
			(width 0.1016)
			(type default)
		)
		(layer "In4.Cu")
	)
	(gr_line
		(start 392.481054 -12.463272)
		(end 392.074654 -12.463272)
		(stroke
			(width 0.1016)
			(type default)
		)
		(layer "In4.Cu")
	)
	(gr_line
		(start 392.481054 -12.463272)
		(end 392.481054 -9.796272)
		(stroke
			(width 0.1016)
			(type default)
		)
		(layer "In4.Cu")
	)
	(gr_line
		(start 392.481054 -9.896348)
		(end 391.287254 -9.896348)
		(stroke
			(width 0.1016)
			(type default)
		)
		(layer "In4.Cu")
	)
	(gr_line
		(start 392.481054 -9.896348)
		(end 392.481054 -12.563348)
		(stroke
			(width 0.1016)
			(type default)
		)
		(layer "In4.Cu")
	)
	(gr_line
		(start 392.481054 -9.796272)
		(end 391.287254 -9.796272)
		(stroke
			(width 0.1016)
			(type default)
		)
		(layer "In4.Cu")
	)
	(gr_line
		(start 392.481054 -9.796272)
		(end 392.481054 -12.463272)
		(stroke
			(width 0.1016)
			(type default)
		)
		(layer "In4.Cu")
	)
	(gr_line
		(start 392.481054 -8.363204)
		(end 392.074654 -8.363204)
		(stroke
			(width 0.1016)
			(type default)
		)
		(layer "In4.Cu")
	)
	(gr_line
		(start 392.481054 -8.363204)
		(end 392.481054 -5.696204)
		(stroke
			(width 0.1016)
			(type default)
		)
		(layer "In4.Cu")
	)
	(gr_line
		(start 392.481054 -8.263128)
		(end 392.074654 -8.263128)
		(stroke
			(width 0.1016)
			(type default)
		)
		(layer "In4.Cu")
	)
	(gr_line
		(start 392.481054 -8.263128)
		(end 392.481054 -5.596128)
		(stroke
			(width 0.1016)
			(type default)
		)
		(layer "In4.Cu")
	)
	(gr_line
		(start 392.481054 -5.696204)
		(end 391.287254 -5.696204)
		(stroke
			(width 0.1016)
			(type default)
		)
		(layer "In4.Cu")
	)
	(gr_line
		(start 392.481054 -5.696204)
		(end 392.481054 -8.363204)
		(stroke
			(width 0.1016)
			(type default)
		)
		(layer "In4.Cu")
	)
	(gr_line
		(start 392.481054 -5.596128)
		(end 391.287254 -5.596128)
		(stroke
			(width 0.1016)
			(type default)
		)
		(layer "In4.Cu")
	)
	(gr_line
		(start 392.481054 -5.596128)
		(end 392.481054 -8.263128)
		(stroke
			(width 0.1016)
			(type default)
		)
		(layer "In4.Cu")
	)
	(gr_line
		(start 392.719814 -31.98622)
		(end 391.449814 -31.98622)
		(stroke
			(width 0.7874)
			(type default)
		)
		(layer "In4.Cu")
	)
	(gr_line
		(start 393.28725 -13.8176)
		(end 394.07465 -13.8176)
		(stroke
			(width 0.1016)
			(type default)
		)
		(layer "In4.Cu")
	)
	(gr_line
		(start 393.28725 -13.7668)
		(end 393.28725 -11.1506)
		(stroke
			(width 0.1016)
			(type default)
		)
		(layer "In4.Cu")
	)
	(gr_line
		(start 393.28725 -11.1506)
		(end 393.28725 -13.8176)
		(stroke
			(width 0.1016)
			(type default)
		)
		(layer "In4.Cu")
	)
	(gr_line
		(start 393.28725 -11.1506)
		(end 394.48105 -11.1506)
		(stroke
			(width 0.1016)
			(type default)
		)
		(layer "In4.Cu")
	)
	(gr_line
		(start 393.28725 -9.617456)
		(end 394.07465 -9.617456)
		(stroke
			(width 0.1016)
			(type default)
		)
		(layer "In4.Cu")
	)
	(gr_line
		(start 393.28725 -9.566656)
		(end 393.28725 -6.950456)
		(stroke
			(width 0.1016)
			(type default)
		)
		(layer "In4.Cu")
	)
	(gr_line
		(start 393.28725 -6.950456)
		(end 393.28725 -9.617456)
		(stroke
			(width 0.1016)
			(type default)
		)
		(layer "In4.Cu")
	)
	(gr_line
		(start 393.28725 -6.950456)
		(end 394.48105 -6.950456)
		(stroke
			(width 0.1016)
			(type default)
		)
		(layer "In4.Cu")
	)
	(gr_line
		(start 393.28725 -5.417312)
		(end 394.07465 -5.417312)
		(stroke
			(width 0.1016)
			(type default)
		)
		(layer "In4.Cu")
	)
	(gr_line
		(start 393.28725 -5.366512)
		(end 393.28725 -2.750312)
		(stroke
			(width 0.1016)
			(type default)
		)
		(layer "In4.Cu")
	)
	(gr_line
		(start 393.28725 -2.750312)
		(end 393.28725 -5.417312)
		(stroke
			(width 0.1016)
			(type default)
		)
		(layer "In4.Cu")
	)
	(gr_line
		(start 393.28725 -2.750312)
		(end 394.48105 -2.750312)
		(stroke
			(width 0.1016)
			(type default)
		)
		(layer "In4.Cu")
	)
	(gr_line
		(start 393.31265 -13.7668)
		(end 393.31265 -11.176)
		(stroke
			(width 0.1016)
			(type default)
		)
		(layer "In4.Cu")
	)
	(gr_line
		(start 393.31265 -11.176)
		(end 394.45565 -11.176)
		(stroke
			(width 0.1016)
			(type default)
		)
		(layer "In4.Cu")
	)
	(gr_line
		(start 393.31265 -9.566656)
		(end 393.31265 -6.975856)
		(stroke
			(width 0.1016)
			(type default)
		)
		(layer "In4.Cu")
	)
	(gr_line
		(start 393.31265 -6.975856)
		(end 394.45565 -6.975856)
		(stroke
			(width 0.1016)
			(type default)
		)
		(layer "In4.Cu")
	)
	(gr_line
		(start 393.31265 -5.366512)
		(end 393.31265 -2.775712)
		(stroke
			(width 0.1016)
			(type default)
		)
		(layer "In4.Cu")
	)
	(gr_line
		(start 393.31265 -2.775712)
		(end 394.45565 -2.775712)
		(stroke
			(width 0.1016)
			(type default)
		)
		(layer "In4.Cu")
	)
	(gr_line
		(start 393.33805 -13.7668)
		(end 393.33805 -11.2014)
		(stroke
			(width 0.1016)
			(type default)
		)
		(layer "In4.Cu")
	)
	(gr_line
		(start 393.33805 -11.2014)
		(end 393.59205 -11.2014)
		(stroke
			(width 0.1016)
			(type default)
		)
		(layer "In4.Cu")
	)
	(gr_line
		(start 393.33805 -9.566656)
		(end 393.33805 -7.001256)
		(stroke
			(width 0.1016)
			(type default)
		)
		(layer "In4.Cu")
	)
	(gr_line
		(start 393.33805 -7.001256)
		(end 393.59205 -7.001256)
		(stroke
			(width 0.1016)
			(type default)
		)
		(layer "In4.Cu")
	)
	(gr_line
		(start 393.33805 -5.366512)
		(end 393.33805 -2.801112)
		(stroke
			(width 0.1016)
			(type default)
		)
		(layer "In4.Cu")
	)
	(gr_line
		(start 393.33805 -2.801112)
		(end 393.59205 -2.801112)
		(stroke
			(width 0.1016)
			(type default)
		)
		(layer "In4.Cu")
	)
	(gr_line
		(start 393.36345 -13.7668)
		(end 393.36345 -11.2014)
		(stroke
			(width 0.2032)
			(type default)
		)
		(layer "In4.Cu")
	)
	(gr_line
		(start 393.36345 -11.2014)
		(end 394.37945 -11.2014)
		(stroke
			(width 0.2032)
			(type default)
		)
		(layer "In4.Cu")
	)
	(gr_line
		(start 393.36345 -9.566656)
		(end 393.36345 -7.001256)
		(stroke
			(width 0.2032)
			(type default)
		)
		(layer "In4.Cu")
	)
	(gr_line
		(start 393.36345 -7.001256)
		(end 394.37945 -7.001256)
		(stroke
			(width 0.2032)
			(type default)
		)
		(layer "In4.Cu")
	)
	(gr_line
		(start 393.36345 -5.366512)
		(end 393.36345 -2.801112)
		(stroke
			(width 0.2032)
			(type default)
		)
		(layer "In4.Cu")
	)
	(gr_line
		(start 393.36345 -2.801112)
		(end 394.37945 -2.801112)
		(stroke
			(width 0.2032)
			(type default)
		)
		(layer "In4.Cu")
	)
	(gr_line
		(start 393.41425 -13.7414)
		(end 393.41425 -11.2522)
		(stroke
			(width 0.2032)
			(type default)
		)
		(layer "In4.Cu")
	)
	(gr_line
		(start 393.41425 -13.7414)
		(end 393.41425 -11.2522)
		(stroke
			(width 0.254)
			(type default)
		)
		(layer "In4.Cu")
	)
	(gr_line
		(start 393.41425 -11.2522)
		(end 393.61745 -11.2522)
		(stroke
			(width 0.2032)
			(type default)
		)
		(layer "In4.Cu")
	)
	(gr_line
		(start 393.41425 -11.2522)
		(end 394.30325 -11.2522)
		(stroke
			(width 0.254)
			(type default)
		)
		(layer "In4.Cu")
	)
	(gr_line
		(start 393.41425 -9.541256)
		(end 393.41425 -7.052056)
		(stroke
			(width 0.2032)
			(type default)
		)
		(layer "In4.Cu")
	)
	(gr_line
		(start 393.41425 -9.541256)
		(end 393.41425 -7.052056)
		(stroke
			(width 0.254)
			(type default)
		)
		(layer "In4.Cu")
	)
	(gr_line
		(start 393.41425 -7.052056)
		(end 393.61745 -7.052056)
		(stroke
			(width 0.2032)
			(type default)
		)
		(layer "In4.Cu")
	)
	(gr_line
		(start 393.41425 -7.052056)
		(end 394.30325 -7.052056)
		(stroke
			(width 0.254)
			(type default)
		)
		(layer "In4.Cu")
	)
	(gr_line
		(start 393.41425 -5.341112)
		(end 393.41425 -2.851912)
		(stroke
			(width 0.2032)
			(type default)
		)
		(layer "In4.Cu")
	)
	(gr_line
		(start 393.41425 -5.341112)
		(end 393.41425 -2.851912)
		(stroke
			(width 0.254)
			(type default)
		)
		(layer "In4.Cu")
	)
	(gr_line
		(start 393.41425 -2.851912)
		(end 393.61745 -2.851912)
		(stroke
			(width 0.2032)
			(type default)
		)
		(layer "In4.Cu")
	)
	(gr_line
		(start 393.41425 -2.851912)
		(end 394.30325 -2.851912)
		(stroke
			(width 0.254)
			(type default)
		)
		(layer "In4.Cu")
	)
	(gr_line
		(start 393.43965 -13.716)
		(end 393.43965 -11.2776)
		(stroke
			(width 0.254)
			(type default)
		)
		(layer "In4.Cu")
	)
	(gr_line
		(start 393.43965 -11.2776)
		(end 394.27785 -11.2776)
		(stroke
			(width 0.254)
			(type default)
		)
		(layer "In4.Cu")
	)
	(gr_line
		(start 393.43965 -9.515856)
		(end 393.43965 -7.077456)
		(stroke
			(width 0.254)
			(type default)
		)
		(layer "In4.Cu")
	)
	(gr_line
		(start 393.43965 -7.077456)
		(end 394.27785 -7.077456)
		(stroke
			(width 0.254)
			(type default)
		)
		(layer "In4.Cu")
	)
	(gr_line
		(start 393.43965 -5.315712)
		(end 393.43965 -2.877312)
		(stroke
			(width 0.254)
			(type default)
		)
		(layer "In4.Cu")
	)
	(gr_line
		(start 393.43965 -2.877312)
		(end 394.27785 -2.877312)
		(stroke
			(width 0.254)
			(type default)
		)
		(layer "In4.Cu")
	)
	(gr_line
		(start 393.46505 -13.6906)
		(end 393.46505 -11.303)
		(stroke
			(width 0.254)
			(type default)
		)
		(layer "In4.Cu")
	)
	(gr_line
		(start 393.46505 -11.303)
		(end 394.25245 -11.303)
		(stroke
			(width 0.254)
			(type default)
		)
		(layer "In4.Cu")
	)
	(gr_line
		(start 393.46505 -9.490456)
		(end 393.46505 -7.102856)
		(stroke
			(width 0.254)
			(type default)
		)
		(layer "In4.Cu")
	)
	(gr_line
		(start 393.46505 -7.102856)
		(end 394.25245 -7.102856)
		(stroke
			(width 0.254)
			(type default)
		)
		(layer "In4.Cu")
	)
	(gr_line
		(start 393.46505 -5.290312)
		(end 393.46505 -2.902712)
		(stroke
			(width 0.254)
			(type default)
		)
		(layer "In4.Cu")
	)
	(gr_line
		(start 393.46505 -2.902712)
		(end 394.25245 -2.902712)
		(stroke
			(width 0.254)
			(type default)
		)
		(layer "In4.Cu")
	)
	(gr_line
		(start 393.49045 -13.6144)
		(end 394.12545 -13.6144)
		(stroke
			(width 0.508)
			(type default)
		)
		(layer "In4.Cu")
	)
	(gr_line
		(start 393.49045 -11.43)
		(end 394.12545 -11.43)
		(stroke
			(width 0.508)
			(type default)
		)
		(layer "In4.Cu")
	)
	(gr_line
		(start 393.49045 -11.3792)
		(end 394.12545 -11.3792)
		(stroke
			(width 0.508)
			(type default)
		)
		(layer "In4.Cu")
	)
	(gr_line
		(start 393.49045 -9.414256)
		(end 394.12545 -9.414256)
		(stroke
			(width 0.508)
			(type default)
		)
		(layer "In4.Cu")
	)
	(gr_line
		(start 393.49045 -7.229856)
		(end 394.12545 -7.229856)
		(stroke
			(width 0.508)
			(type default)
		)
		(layer "In4.Cu")
	)
	(gr_line
		(start 393.49045 -7.179056)
		(end 394.12545 -7.179056)
		(stroke
			(width 0.508)
			(type default)
		)
		(layer "In4.Cu")
	)
	(gr_line
		(start 393.49045 -5.214112)
		(end 394.12545 -5.214112)
		(stroke
			(width 0.508)
			(type default)
		)
		(layer "In4.Cu")
	)
	(gr_line
		(start 393.49045 -3.029712)
		(end 394.12545 -3.029712)
		(stroke
			(width 0.508)
			(type default)
		)
		(layer "In4.Cu")
	)
	(gr_line
		(start 393.49045 -2.978912)
		(end 394.12545 -2.978912)
		(stroke
			(width 0.508)
			(type default)
		)
		(layer "In4.Cu")
	)
	(gr_line
		(start 393.51585 -11.684)
		(end 394.15085 -11.684)
		(stroke
			(width 0.508)
			(type default)
		)
		(layer "In4.Cu")
	)
	(gr_line
		(start 393.51585 -7.483856)
		(end 394.15085 -7.483856)
		(stroke
			(width 0.508)
			(type default)
		)
		(layer "In4.Cu")
	)
	(gr_line
		(start 393.51585 -3.283712)
		(end 394.15085 -3.283712)
		(stroke
			(width 0.508)
			(type default)
		)
		(layer "In4.Cu")
	)
	(gr_line
		(start 393.54125 -13.6398)
		(end 393.54125 -11.3792)
		(stroke
			(width 0.254)
			(type default)
		)
		(layer "In4.Cu")
	)
	(gr_line
		(start 393.54125 -13.4874)
		(end 394.17625 -13.4874)
		(stroke
			(width 0.508)
			(type default)
		)
		(layer "In4.Cu")
	)
	(gr_line
		(start 393.54125 -11.3792)
		(end 394.17625 -11.3792)
		(stroke
			(width 0.254)
			(type default)
		)
		(layer "In4.Cu")
	)
	(gr_line
		(start 393.54125 -9.439656)
		(end 393.54125 -7.179056)
		(stroke
			(width 0.254)
			(type default)
		)
		(layer "In4.Cu")
	)
	(gr_line
		(start 393.54125 -9.287256)
		(end 394.17625 -9.287256)
		(stroke
			(width 0.508)
			(type default)
		)
		(layer "In4.Cu")
	)
	(gr_line
		(start 393.54125 -7.179056)
		(end 394.17625 -7.179056)
		(stroke
			(width 0.254)
			(type default)
		)
		(layer "In4.Cu")
	)
	(gr_line
		(start 393.54125 -5.239512)
		(end 393.54125 -2.978912)
		(stroke
			(width 0.254)
			(type default)
		)
		(layer "In4.Cu")
	)
	(gr_line
		(start 393.54125 -5.087112)
		(end 394.17625 -5.087112)
		(stroke
			(width 0.508)
			(type default)
		)
		(layer "In4.Cu")
	)
	(gr_line
		(start 393.54125 -2.978912)
		(end 394.17625 -2.978912)
		(stroke
			(width 0.254)
			(type default)
		)
		(layer "In4.Cu")
	)
	(gr_line
		(start 393.56665 -13.335)
		(end 394.20165 -13.335)
		(stroke
			(width 0.508)
			(type default)
		)
		(layer "In4.Cu")
	)
	(gr_line
		(start 393.56665 -9.134856)
		(end 394.20165 -9.134856)
		(stroke
			(width 0.508)
			(type default)
		)
		(layer "In4.Cu")
	)
	(gr_line
		(start 393.56665 -4.934712)
		(end 394.20165 -4.934712)
		(stroke
			(width 0.508)
			(type default)
		)
		(layer "In4.Cu")
	)
	(gr_line
		(start 393.59205 -13.6144)
		(end 394.22705 -13.6144)
		(stroke
			(width 0.508)
			(type default)
		)
		(layer "In4.Cu")
	)
	(gr_line
		(start 393.59205 -11.2014)
		(end 394.43025 -11.2014)
		(stroke
			(width 0.2032)
			(type default)
		)
		(layer "In4.Cu")
	)
	(gr_line
		(start 393.59205 -9.414256)
		(end 394.22705 -9.414256)
		(stroke
			(width 0.508)
			(type default)
		)
		(layer "In4.Cu")
	)
	(gr_line
		(start 393.59205 -7.001256)
		(end 394.43025 -7.001256)
		(stroke
			(width 0.2032)
			(type default)
		)
		(layer "In4.Cu")
	)
	(gr_line
		(start 393.59205 -5.214112)
		(end 394.22705 -5.214112)
		(stroke
			(width 0.508)
			(type default)
		)
		(layer "In4.Cu")
	)
	(gr_line
		(start 393.59205 -2.801112)
		(end 394.43025 -2.801112)
		(stroke
			(width 0.2032)
			(type default)
		)
		(layer "In4.Cu")
	)
	(gr_line
		(start 393.61745 -13.6144)
		(end 393.61745 -11.43)
		(stroke
			(width 0.254)
			(type default)
		)
		(layer "In4.Cu")
	)
	(gr_line
		(start 393.61745 -11.43)
		(end 394.10005 -11.43)
		(stroke
			(width 0.254)
			(type default)
		)
		(layer "In4.Cu")
	)
	(gr_line
		(start 393.61745 -11.2522)
		(end 394.35405 -11.2522)
		(stroke
			(width 0.254)
			(type default)
		)
		(layer "In4.Cu")
	)
	(gr_line
		(start 393.61745 -9.414256)
		(end 393.61745 -7.229856)
		(stroke
			(width 0.254)
			(type default)
		)
		(layer "In4.Cu")
	)
	(gr_line
		(start 393.61745 -7.229856)
		(end 394.10005 -7.229856)
		(stroke
			(width 0.254)
			(type default)
		)
		(layer "In4.Cu")
	)
	(gr_line
		(start 393.61745 -7.052056)
		(end 394.35405 -7.052056)
		(stroke
			(width 0.254)
			(type default)
		)
		(layer "In4.Cu")
	)
	(gr_line
		(start 393.61745 -5.214112)
		(end 393.61745 -3.029712)
		(stroke
			(width 0.254)
			(type default)
		)
		(layer "In4.Cu")
	)
	(gr_line
		(start 393.61745 -3.029712)
		(end 394.10005 -3.029712)
		(stroke
			(width 0.254)
			(type default)
		)
		(layer "In4.Cu")
	)
	(gr_line
		(start 393.61745 -2.851912)
		(end 394.35405 -2.851912)
		(stroke
			(width 0.254)
			(type default)
		)
		(layer "In4.Cu")
	)
	(gr_line
		(start 393.635992 -11.36523)
		(end 394.270992 -11.36523)
		(stroke
			(width 0.508)
			(type default)
		)
		(layer "In4.Cu")
	)
	(gr_line
		(start 393.635992 -7.165086)
		(end 394.270992 -7.165086)
		(stroke
			(width 0.508)
			(type default)
		)
		(layer "In4.Cu")
	)
	(gr_line
		(start 393.635992 -2.964942)
		(end 394.270992 -2.964942)
		(stroke
			(width 0.508)
			(type default)
		)
		(layer "In4.Cu")
	)
	(gr_line
		(start 393.64285 -13.6144)
		(end 394.27785 -13.6144)
		(stroke
			(width 0.508)
			(type default)
		)
		(layer "In4.Cu")
	)
	(gr_line
		(start 393.64285 -13.4874)
		(end 393.64285 -11.5062)
		(stroke
			(width 0.762)
			(type default)
		)
		(layer "In4.Cu")
	)
	(gr_line
		(start 393.64285 -11.5062)
		(end 394.27785 -11.5062)
		(stroke
			(width 0.508)
			(type default)
		)
		(layer "In4.Cu")
	)
	(gr_line
		(start 393.64285 -9.414256)
		(end 394.27785 -9.414256)
		(stroke
			(width 0.508)
			(type default)
		)
		(layer "In4.Cu")
	)
	(gr_line
		(start 393.64285 -9.287256)
		(end 393.64285 -7.306056)
		(stroke
			(width 0.762)
			(type default)
		)
		(layer "In4.Cu")
	)
	(gr_line
		(start 393.64285 -7.306056)
		(end 394.27785 -7.306056)
		(stroke
			(width 0.508)
			(type default)
		)
		(layer "In4.Cu")
	)
	(gr_line
		(start 393.64285 -5.214112)
		(end 394.27785 -5.214112)
		(stroke
			(width 0.508)
			(type default)
		)
		(layer "In4.Cu")
	)
	(gr_line
		(start 393.64285 -5.087112)
		(end 393.64285 -3.105912)
		(stroke
			(width 0.762)
			(type default)
		)
		(layer "In4.Cu")
	)
	(gr_line
		(start 393.64285 -3.105912)
		(end 394.27785 -3.105912)
		(stroke
			(width 0.508)
			(type default)
		)
		(layer "In4.Cu")
	)
	(gr_line
		(start 393.69365 -13.5382)
		(end 393.69365 -11.5062)
		(stroke
			(width 0.254)
			(type default)
		)
		(layer "In4.Cu")
	)
	(gr_line
		(start 393.69365 -11.5062)
		(end 394.02385 -11.5062)
		(stroke
			(width 0.254)
			(type default)
		)
		(layer "In4.Cu")
	)
	(gr_line
		(start 393.69365 -9.338056)
		(end 393.69365 -7.306056)
		(stroke
			(width 0.254)
			(type default)
		)
		(layer "In4.Cu")
	)
	(gr_line
		(start 393.69365 -7.306056)
		(end 394.02385 -7.306056)
		(stroke
			(width 0.254)
			(type default)
		)
		(layer "In4.Cu")
	)
	(gr_line
		(start 393.69365 -5.137912)
		(end 393.69365 -3.105912)
		(stroke
			(width 0.254)
			(type default)
		)
		(layer "In4.Cu")
	)
	(gr_line
		(start 393.69365 -3.105912)
		(end 394.02385 -3.105912)
		(stroke
			(width 0.254)
			(type default)
		)
		(layer "In4.Cu")
	)
	(gr_line
		(start 393.79525 -13.462)
		(end 393.79525 -11.6586)
		(stroke
			(width 0.254)
			(type default)
		)
		(layer "In4.Cu")
	)
	(gr_line
		(start 393.79525 -13.462)
		(end 393.79525 -11.4808)
		(stroke
			(width 0.762)
			(type default)
		)
		(layer "In4.Cu")
	)
	(gr_line
		(start 393.79525 -11.6586)
		(end 393.89685 -11.6586)
		(stroke
			(width 0.254)
			(type default)
		)
		(layer "In4.Cu")
	)
	(gr_line
		(start 393.79525 -9.261856)
		(end 393.79525 -7.458456)
		(stroke
			(width 0.254)
			(type default)
		)
		(layer "In4.Cu")
	)
	(gr_line
		(start 393.79525 -9.261856)
		(end 393.79525 -7.280656)
		(stroke
			(width 0.762)
			(type default)
		)
		(layer "In4.Cu")
	)
	(gr_line
		(start 393.79525 -7.458456)
		(end 393.89685 -7.458456)
		(stroke
			(width 0.254)
			(type default)
		)
		(layer "In4.Cu")
	)
	(gr_line
		(start 393.79525 -5.061712)
		(end 393.79525 -3.258312)
		(stroke
			(width 0.254)
			(type default)
		)
		(layer "In4.Cu")
	)
	(gr_line
		(start 393.79525 -5.061712)
		(end 393.79525 -3.080512)
		(stroke
			(width 0.762)
			(type default)
		)
		(layer "In4.Cu")
	)
	(gr_line
		(start 393.79525 -3.258312)
		(end 393.89685 -3.258312)
		(stroke
			(width 0.254)
			(type default)
		)
		(layer "In4.Cu")
	)
	(gr_line
		(start 393.89685 -13.5636)
		(end 393.84605 -13.5636)
		(stroke
			(width 0.254)
			(type default)
		)
		(layer "In4.Cu")
	)
	(gr_line
		(start 393.89685 -11.6586)
		(end 393.89685 -13.5636)
		(stroke
			(width 0.254)
			(type default)
		)
		(layer "In4.Cu")
	)
	(gr_line
		(start 393.89685 -9.363456)
		(end 393.84605 -9.363456)
		(stroke
			(width 0.254)
			(type default)
		)
		(layer "In4.Cu")
	)
	(gr_line
		(start 393.89685 -7.458456)
		(end 393.89685 -9.363456)
		(stroke
			(width 0.254)
			(type default)
		)
		(layer "In4.Cu")
	)
	(gr_line
		(start 393.89685 -5.163312)
		(end 393.84605 -5.163312)
		(stroke
			(width 0.254)
			(type default)
		)
		(layer "In4.Cu")
	)
	(gr_line
		(start 393.89685 -3.258312)
		(end 393.89685 -5.163312)
		(stroke
			(width 0.254)
			(type default)
		)
		(layer "In4.Cu")
	)
	(gr_line
		(start 393.94765 -13.4874)
		(end 393.94765 -11.5062)
		(stroke
			(width 0.762)
			(type default)
		)
		(layer "In4.Cu")
	)
	(gr_line
		(start 393.94765 -9.287256)
		(end 393.94765 -7.306056)
		(stroke
			(width 0.762)
			(type default)
		)
		(layer "In4.Cu")
	)
	(gr_line
		(start 393.94765 -5.087112)
		(end 393.94765 -3.105912)
		(stroke
			(width 0.762)
			(type default)
		)
		(layer "In4.Cu")
	)
	(gr_line
		(start 394.02385 -13.462)
		(end 393.79525 -13.462)
		(stroke
			(width 0.254)
			(type default)
		)
		(layer "In4.Cu")
	)
	(gr_line
		(start 394.02385 -11.5062)
		(end 394.02385 -13.462)
		(stroke
			(width 0.254)
			(type default)
		)
		(layer "In4.Cu")
	)
	(gr_line
		(start 394.02385 -9.261856)
		(end 393.79525 -9.261856)
		(stroke
			(width 0.254)
			(type default)
		)
		(layer "In4.Cu")
	)
	(gr_line
		(start 394.02385 -7.306056)
		(end 394.02385 -9.261856)
		(stroke
			(width 0.254)
			(type default)
		)
		(layer "In4.Cu")
	)
	(gr_line
		(start 394.02385 -5.061712)
		(end 393.79525 -5.061712)
		(stroke
			(width 0.254)
			(type default)
		)
		(layer "In4.Cu")
	)
	(gr_line
		(start 394.02385 -3.105912)
		(end 394.02385 -5.061712)
		(stroke
			(width 0.254)
			(type default)
		)
		(layer "In4.Cu")
	)
	(gr_line
		(start 394.07465 -13.8176)
		(end 394.07465 -13.7668)
		(stroke
			(width 0.1016)
			(type default)
		)
		(layer "In4.Cu")
	)
	(gr_line
		(start 394.07465 -13.8176)
		(end 394.48105 -13.8176)
		(stroke
			(width 0.1016)
			(type default)
		)
		(layer "In4.Cu")
	)
	(gr_line
		(start 394.07465 -13.7668)
		(end 393.31265 -13.7668)
		(stroke
			(width 0.1016)
			(type default)
		)
		(layer "In4.Cu")
	)
	(gr_line
		(start 394.07465 -13.4874)
		(end 394.07465 -11.5062)
		(stroke
			(width 0.762)
			(type default)
		)
		(layer "In4.Cu")
	)
	(gr_line
		(start 394.07465 -9.617456)
		(end 394.07465 -9.566656)
		(stroke
			(width 0.1016)
			(type default)
		)
		(layer "In4.Cu")
	)
	(gr_line
		(start 394.07465 -9.617456)
		(end 394.48105 -9.617456)
		(stroke
			(width 0.1016)
			(type default)
		)
		(layer "In4.Cu")
	)
	(gr_line
		(start 394.07465 -9.566656)
		(end 393.31265 -9.566656)
		(stroke
			(width 0.1016)
			(type default)
		)
		(layer "In4.Cu")
	)
	(gr_line
		(start 394.07465 -9.287256)
		(end 394.07465 -7.306056)
		(stroke
			(width 0.762)
			(type default)
		)
		(layer "In4.Cu")
	)
	(gr_line
		(start 394.07465 -5.417312)
		(end 394.07465 -5.366512)
		(stroke
			(width 0.1016)
			(type default)
		)
		(layer "In4.Cu")
	)
	(gr_line
		(start 394.07465 -5.417312)
		(end 394.48105 -5.417312)
		(stroke
			(width 0.1016)
			(type default)
		)
		(layer "In4.Cu")
	)
	(gr_line
		(start 394.07465 -5.366512)
		(end 393.31265 -5.366512)
		(stroke
			(width 0.1016)
			(type default)
		)
		(layer "In4.Cu")
	)
	(gr_line
		(start 394.07465 -5.087112)
		(end 394.07465 -3.105912)
		(stroke
			(width 0.762)
			(type default)
		)
		(layer "In4.Cu")
	)
	(gr_line
		(start 394.10005 -13.5382)
		(end 393.69365 -13.5382)
		(stroke
			(width 0.254)
			(type default)
		)
		(layer "In4.Cu")
	)
	(gr_line
		(start 394.10005 -11.43)
		(end 394.10005 -13.5382)
		(stroke
			(width 0.254)
			(type default)
		)
		(layer "In4.Cu")
	)
	(gr_line
		(start 394.10005 -9.338056)
		(end 393.69365 -9.338056)
		(stroke
			(width 0.254)
			(type default)
		)
		(layer "In4.Cu")
	)
	(gr_line
		(start 394.10005 -7.229856)
		(end 394.10005 -9.338056)
		(stroke
			(width 0.254)
			(type default)
		)
		(layer "In4.Cu")
	)
	(gr_line
		(start 394.10005 -5.137912)
		(end 393.69365 -5.137912)
		(stroke
			(width 0.254)
			(type default)
		)
		(layer "In4.Cu")
	)
	(gr_line
		(start 394.10005 -3.029712)
		(end 394.10005 -5.137912)
		(stroke
			(width 0.254)
			(type default)
		)
		(layer "In4.Cu")
	)
	(gr_line
		(start 394.15085 -13.4874)
		(end 394.15085 -11.5062)
		(stroke
			(width 0.762)
			(type default)
		)
		(layer "In4.Cu")
	)
	(gr_line
		(start 394.15085 -9.287256)
		(end 394.15085 -7.306056)
		(stroke
			(width 0.762)
			(type default)
		)
		(layer "In4.Cu")
	)
	(gr_line
		(start 394.15085 -5.087112)
		(end 394.15085 -3.105912)
		(stroke
			(width 0.762)
			(type default)
		)
		(layer "In4.Cu")
	)
	(gr_line
		(start 394.17625 -13.6144)
		(end 393.61745 -13.6144)
		(stroke
			(width 0.254)
			(type default)
		)
		(layer "In4.Cu")
	)
	(gr_line
		(start 394.17625 -11.3792)
		(end 394.17625 -13.6144)
		(stroke
			(width 0.254)
			(type default)
		)
		(layer "In4.Cu")
	)
	(gr_line
		(start 394.17625 -9.414256)
		(end 393.61745 -9.414256)
		(stroke
			(width 0.254)
			(type default)
		)
		(layer "In4.Cu")
	)
	(gr_line
		(start 394.17625 -7.179056)
		(end 394.17625 -9.414256)
		(stroke
			(width 0.254)
			(type default)
		)
		(layer "In4.Cu")
	)
	(gr_line
		(start 394.17625 -5.214112)
		(end 393.61745 -5.214112)
		(stroke
			(width 0.254)
			(type default)
		)
		(layer "In4.Cu")
	)
	(gr_line
		(start 394.17625 -2.978912)
		(end 394.17625 -5.214112)
		(stroke
			(width 0.254)
			(type default)
		)
		(layer "In4.Cu")
	)
	(gr_line
		(start 394.25245 -13.6398)
		(end 393.54125 -13.6398)
		(stroke
			(width 0.254)
			(type default)
		)
		(layer "In4.Cu")
	)
	(gr_line
		(start 394.25245 -11.303)
		(end 394.25245 -13.6398)
		(stroke
			(width 0.254)
			(type default)
		)
		(layer "In4.Cu")
	)
	(gr_line
		(start 394.25245 -9.439656)
		(end 393.54125 -9.439656)
		(stroke
			(width 0.254)
			(type default)
		)
		(layer "In4.Cu")
	)
	(gr_line
		(start 394.25245 -7.102856)
		(end 394.25245 -9.439656)
		(stroke
			(width 0.254)
			(type default)
		)
		(layer "In4.Cu")
	)
	(gr_line
		(start 394.25245 -5.239512)
		(end 393.54125 -5.239512)
		(stroke
			(width 0.254)
			(type default)
		)
		(layer "In4.Cu")
	)
	(gr_line
		(start 394.25245 -2.902712)
		(end 394.25245 -5.239512)
		(stroke
			(width 0.254)
			(type default)
		)
		(layer "In4.Cu")
	)
	(gr_line
		(start 394.27785 -13.7668)
		(end 393.28725 -13.7668)
		(stroke
			(width 0.1016)
			(type default)
		)
		(layer "In4.Cu")
	)
	(gr_line
		(start 394.27785 -13.6906)
		(end 393.46505 -13.6906)
		(stroke
			(width 0.254)
			(type default)
		)
		(layer "In4.Cu")
	)
	(gr_line
		(start 394.27785 -11.2776)
		(end 394.27785 -13.6906)
		(stroke
			(width 0.254)
			(type default)
		)
		(layer "In4.Cu")
	)
	(gr_line
		(start 394.27785 -9.566656)
		(end 393.28725 -9.566656)
		(stroke
			(width 0.1016)
			(type default)
		)
		(layer "In4.Cu")
	)
	(gr_line
		(start 394.27785 -9.490456)
		(end 393.46505 -9.490456)
		(stroke
			(width 0.254)
			(type default)
		)
		(layer "In4.Cu")
	)
	(gr_line
		(start 394.27785 -7.077456)
		(end 394.27785 -9.490456)
		(stroke
			(width 0.254)
			(type default)
		)
		(layer "In4.Cu")
	)
	(gr_line
		(start 394.27785 -5.366512)
		(end 393.28725 -5.366512)
		(stroke
			(width 0.1016)
			(type default)
		)
		(layer "In4.Cu")
	)
	(gr_line
		(start 394.27785 -5.290312)
		(end 393.46505 -5.290312)
		(stroke
			(width 0.254)
			(type default)
		)
		(layer "In4.Cu")
	)
	(gr_line
		(start 394.27785 -2.877312)
		(end 394.27785 -5.290312)
		(stroke
			(width 0.254)
			(type default)
		)
		(layer "In4.Cu")
	)
	(gr_line
		(start 394.30325 -13.716)
		(end 393.43965 -13.716)
		(stroke
			(width 0.254)
			(type default)
		)
		(layer "In4.Cu")
	)
	(gr_line
		(start 394.30325 -11.2522)
		(end 394.30325 -13.716)
		(stroke
			(width 0.254)
			(type default)
		)
		(layer "In4.Cu")
	)
	(gr_line
		(start 394.30325 -9.515856)
		(end 393.43965 -9.515856)
		(stroke
			(width 0.254)
			(type default)
		)
		(layer "In4.Cu")
	)
	(gr_line
		(start 394.30325 -7.052056)
		(end 394.30325 -9.515856)
		(stroke
			(width 0.254)
			(type default)
		)
		(layer "In4.Cu")
	)
	(gr_line
		(start 394.30325 -5.315712)
		(end 393.43965 -5.315712)
		(stroke
			(width 0.254)
			(type default)
		)
		(layer "In4.Cu")
	)
	(gr_line
		(start 394.30325 -2.851912)
		(end 394.30325 -5.315712)
		(stroke
			(width 0.254)
			(type default)
		)
		(layer "In4.Cu")
	)
	(gr_line
		(start 394.35405 -13.7414)
		(end 393.41425 -13.7414)
		(stroke
			(width 0.254)
			(type default)
		)
		(layer "In4.Cu")
	)
	(gr_line
		(start 394.35405 -11.2522)
		(end 394.35405 -13.7414)
		(stroke
			(width 0.254)
			(type default)
		)
		(layer "In4.Cu")
	)
	(gr_line
		(start 394.35405 -9.541256)
		(end 393.41425 -9.541256)
		(stroke
			(width 0.254)
			(type default)
		)
		(layer "In4.Cu")
	)
	(gr_line
		(start 394.35405 -7.052056)
		(end 394.35405 -9.541256)
		(stroke
			(width 0.254)
			(type default)
		)
		(layer "In4.Cu")
	)
	(gr_line
		(start 394.35405 -5.341112)
		(end 393.41425 -5.341112)
		(stroke
			(width 0.254)
			(type default)
		)
		(layer "In4.Cu")
	)
	(gr_line
		(start 394.35405 -2.851912)
		(end 394.35405 -5.341112)
		(stroke
			(width 0.254)
			(type default)
		)
		(layer "In4.Cu")
	)
	(gr_line
		(start 394.37945 -13.7414)
		(end 393.41425 -13.7414)
		(stroke
			(width 0.2032)
			(type default)
		)
		(layer "In4.Cu")
	)
	(gr_line
		(start 394.37945 -11.2014)
		(end 394.37945 -13.7414)
		(stroke
			(width 0.2032)
			(type default)
		)
		(layer "In4.Cu")
	)
	(gr_line
		(start 394.37945 -9.541256)
		(end 393.41425 -9.541256)
		(stroke
			(width 0.2032)
			(type default)
		)
		(layer "In4.Cu")
	)
	(gr_line
		(start 394.37945 -7.001256)
		(end 394.37945 -9.541256)
		(stroke
			(width 0.2032)
			(type default)
		)
		(layer "In4.Cu")
	)
	(gr_line
		(start 394.37945 -5.341112)
		(end 393.41425 -5.341112)
		(stroke
			(width 0.2032)
			(type default)
		)
		(layer "In4.Cu")
	)
	(gr_line
		(start 394.37945 -2.801112)
		(end 394.37945 -5.341112)
		(stroke
			(width 0.2032)
			(type default)
		)
		(layer "In4.Cu")
	)
	(gr_line
		(start 394.43025 -13.7668)
		(end 393.36345 -13.7668)
		(stroke
			(width 0.2032)
			(type default)
		)
		(layer "In4.Cu")
	)
	(gr_line
		(start 394.43025 -11.2014)
		(end 394.43025 -13.7668)
		(stroke
			(width 0.2032)
			(type default)
		)
		(layer "In4.Cu")
	)
	(gr_line
		(start 394.43025 -9.566656)
		(end 393.36345 -9.566656)
		(stroke
			(width 0.2032)
			(type default)
		)
		(layer "In4.Cu")
	)
	(gr_line
		(start 394.43025 -7.001256)
		(end 394.43025 -9.566656)
		(stroke
			(width 0.2032)
			(type default)
		)
		(layer "In4.Cu")
	)
	(gr_line
		(start 394.43025 -5.366512)
		(end 393.36345 -5.366512)
		(stroke
			(width 0.2032)
			(type default)
		)
		(layer "In4.Cu")
	)
	(gr_line
		(start 394.43025 -2.801112)
		(end 394.43025 -5.366512)
		(stroke
			(width 0.2032)
			(type default)
		)
		(layer "In4.Cu")
	)
	(gr_line
		(start 394.45565 -13.7668)
		(end 393.33805 -13.7668)
		(stroke
			(width 0.1016)
			(type default)
		)
		(layer "In4.Cu")
	)
	(gr_line
		(start 394.45565 -11.176)
		(end 394.45565 -13.7668)
		(stroke
			(width 0.1016)
			(type default)
		)
		(layer "In4.Cu")
	)
	(gr_line
		(start 394.45565 -9.566656)
		(end 393.33805 -9.566656)
		(stroke
			(width 0.1016)
			(type default)
		)
		(layer "In4.Cu")
	)
	(gr_line
		(start 394.45565 -6.975856)
		(end 394.45565 -9.566656)
		(stroke
			(width 0.1016)
			(type default)
		)
		(layer "In4.Cu")
	)
	(gr_line
		(start 394.45565 -5.366512)
		(end 393.33805 -5.366512)
		(stroke
			(width 0.1016)
			(type default)
		)
		(layer "In4.Cu")
	)
	(gr_line
		(start 394.45565 -2.775712)
		(end 394.45565 -5.366512)
		(stroke
			(width 0.1016)
			(type default)
		)
		(layer "In4.Cu")
	)
	(gr_line
		(start 394.48105 -13.8176)
		(end 394.07465 -13.8176)
		(stroke
			(width 0.1016)
			(type default)
		)
		(layer "In4.Cu")
	)
	(gr_line
		(start 394.48105 -13.8176)
		(end 394.48105 -11.1506)
		(stroke
			(width 0.1016)
			(type default)
		)
		(layer "In4.Cu")
	)
	(gr_line
		(start 394.48105 -11.1506)
		(end 393.28725 -11.1506)
		(stroke
			(width 0.1016)
			(type default)
		)
		(layer "In4.Cu")
	)
	(gr_line
		(start 394.48105 -11.1506)
		(end 394.48105 -13.8176)
		(stroke
			(width 0.1016)
			(type default)
		)
		(layer "In4.Cu")
	)
	(gr_line
		(start 394.48105 -9.617456)
		(end 394.07465 -9.617456)
		(stroke
			(width 0.1016)
			(type default)
		)
		(layer "In4.Cu")
	)
	(gr_line
		(start 394.48105 -9.617456)
		(end 394.48105 -6.950456)
		(stroke
			(width 0.1016)
			(type default)
		)
		(layer "In4.Cu")
	)
	(gr_line
		(start 394.48105 -6.950456)
		(end 393.28725 -6.950456)
		(stroke
			(width 0.1016)
			(type default)
		)
		(layer "In4.Cu")
	)
	(gr_line
		(start 394.48105 -6.950456)
		(end 394.48105 -9.617456)
		(stroke
			(width 0.1016)
			(type default)
		)
		(layer "In4.Cu")
	)
	(gr_line
		(start 394.48105 -5.417312)
		(end 394.07465 -5.417312)
		(stroke
			(width 0.1016)
			(type default)
		)
		(layer "In4.Cu")
	)
	(gr_line
		(start 394.48105 -5.417312)
		(end 394.48105 -2.750312)
		(stroke
			(width 0.1016)
			(type default)
		)
		(layer "In4.Cu")
	)
	(gr_line
		(start 394.48105 -2.750312)
		(end 393.28725 -2.750312)
		(stroke
			(width 0.1016)
			(type default)
		)
		(layer "In4.Cu")
	)
	(gr_line
		(start 394.48105 -2.750312)
		(end 394.48105 -5.417312)
		(stroke
			(width 0.1016)
			(type default)
		)
		(layer "In4.Cu")
	)
	(gr_line
		(start 395.14526 -32.9184)
		(end 393.87526 -32.9184)
		(stroke
			(width 0.7874)
			(type default)
		)
		(layer "In4.Cu")
	)
	(gr_line
		(start 395.287246 -12.563348)
		(end 396.074646 -12.563348)
		(stroke
			(width 0.1016)
			(type default)
		)
		(layer "In4.Cu")
	)
	(gr_line
		(start 395.287246 -12.512548)
		(end 395.287246 -9.896348)
		(stroke
			(width 0.1016)
			(type default)
		)
		(layer "In4.Cu")
	)
	(gr_line
		(start 395.287246 -12.463272)
		(end 396.074646 -12.463272)
		(stroke
			(width 0.1016)
			(type default)
		)
		(layer "In4.Cu")
	)
	(gr_line
		(start 395.287246 -12.412472)
		(end 395.287246 -9.796272)
		(stroke
			(width 0.1016)
			(type default)
		)
		(layer "In4.Cu")
	)
	(gr_line
		(start 395.287246 -9.896348)
		(end 395.287246 -12.563348)
		(stroke
			(width 0.1016)
			(type default)
		)
		(layer "In4.Cu")
	)
	(gr_line
		(start 395.287246 -9.896348)
		(end 396.481046 -9.896348)
		(stroke
			(width 0.1016)
			(type default)
		)
		(layer "In4.Cu")
	)
	(gr_line
		(start 395.287246 -9.796272)
		(end 395.287246 -12.463272)
		(stroke
			(width 0.1016)
			(type default)
		)
		(layer "In4.Cu")
	)
	(gr_line
		(start 395.287246 -9.796272)
		(end 396.481046 -9.796272)
		(stroke
			(width 0.1016)
			(type default)
		)
		(layer "In4.Cu")
	)
	(gr_line
		(start 395.287246 -8.363204)
		(end 396.074646 -8.363204)
		(stroke
			(width 0.1016)
			(type default)
		)
		(layer "In4.Cu")
	)
	(gr_line
		(start 395.287246 -8.312404)
		(end 395.287246 -5.696204)
		(stroke
			(width 0.1016)
			(type default)
		)
		(layer "In4.Cu")
	)
	(gr_line
		(start 395.287246 -8.263128)
		(end 396.074646 -8.263128)
		(stroke
			(width 0.1016)
			(type default)
		)
		(layer "In4.Cu")
	)
	(gr_line
		(start 395.287246 -8.212328)
		(end 395.287246 -5.596128)
		(stroke
			(width 0.1016)
			(type default)
		)
		(layer "In4.Cu")
	)
	(gr_line
		(start 395.287246 -5.696204)
		(end 395.287246 -8.363204)
		(stroke
			(width 0.1016)
			(type default)
		)
		(layer "In4.Cu")
	)
	(gr_line
		(start 395.287246 -5.696204)
		(end 396.481046 -5.696204)
		(stroke
			(width 0.1016)
			(type default)
		)
		(layer "In4.Cu")
	)
	(gr_line
		(start 395.287246 -5.596128)
		(end 395.287246 -8.263128)
		(stroke
			(width 0.1016)
			(type default)
		)
		(layer "In4.Cu")
	)
	(gr_line
		(start 395.287246 -5.596128)
		(end 396.481046 -5.596128)
		(stroke
			(width 0.1016)
			(type default)
		)
		(layer "In4.Cu")
	)
	(gr_line
		(start 395.287246 -4.16306)
		(end 396.074646 -4.16306)
		(stroke
			(width 0.1016)
			(type default)
		)
		(layer "In4.Cu")
	)
	(gr_line
		(start 395.287246 -4.11226)
		(end 395.287246 -1.49606)
		(stroke
			(width 0.1016)
			(type default)
		)
		(layer "In4.Cu")
	)
	(gr_line
		(start 395.287246 -4.062984)
		(end 396.074646 -4.062984)
		(stroke
			(width 0.1016)
			(type default)
		)
		(layer "In4.Cu")
	)
	(gr_line
		(start 395.287246 -4.012184)
		(end 395.287246 -1.395984)
		(stroke
			(width 0.1016)
			(type default)
		)
		(layer "In4.Cu")
	)
	(gr_line
		(start 395.287246 -1.49606)
		(end 395.287246 -4.16306)
		(stroke
			(width 0.1016)
			(type default)
		)
		(layer "In4.Cu")
	)
	(gr_line
		(start 395.287246 -1.49606)
		(end 396.481046 -1.49606)
		(stroke
			(width 0.1016)
			(type default)
		)
		(layer "In4.Cu")
	)
	(gr_line
		(start 395.287246 -1.395984)
		(end 395.287246 -4.062984)
		(stroke
			(width 0.1016)
			(type default)
		)
		(layer "In4.Cu")
	)
	(gr_line
		(start 395.287246 -1.395984)
		(end 396.481046 -1.395984)
		(stroke
			(width 0.1016)
			(type default)
		)
		(layer "In4.Cu")
	)
	(gr_line
		(start 395.312646 -12.512548)
		(end 395.312646 -9.921748)
		(stroke
			(width 0.1016)
			(type default)
		)
		(layer "In4.Cu")
	)
	(gr_line
		(start 395.312646 -12.412472)
		(end 395.312646 -9.821672)
		(stroke
			(width 0.1016)
			(type default)
		)
		(layer "In4.Cu")
	)
	(gr_line
		(start 395.312646 -9.921748)
		(end 396.455646 -9.921748)
		(stroke
			(width 0.1016)
			(type default)
		)
		(layer "In4.Cu")
	)
	(gr_line
		(start 395.312646 -9.821672)
		(end 396.455646 -9.821672)
		(stroke
			(width 0.1016)
			(type default)
		)
		(layer "In4.Cu")
	)
	(gr_line
		(start 395.312646 -8.312404)
		(end 395.312646 -5.721604)
		(stroke
			(width 0.1016)
			(type default)
		)
		(layer "In4.Cu")
	)
	(gr_line
		(start 395.312646 -8.212328)
		(end 395.312646 -5.621528)
		(stroke
			(width 0.1016)
			(type default)
		)
		(layer "In4.Cu")
	)
	(gr_line
		(start 395.312646 -5.721604)
		(end 396.455646 -5.721604)
		(stroke
			(width 0.1016)
			(type default)
		)
		(layer "In4.Cu")
	)
	(gr_line
		(start 395.312646 -5.621528)
		(end 396.455646 -5.621528)
		(stroke
			(width 0.1016)
			(type default)
		)
		(layer "In4.Cu")
	)
	(gr_line
		(start 395.312646 -4.11226)
		(end 395.312646 -1.52146)
		(stroke
			(width 0.1016)
			(type default)
		)
		(layer "In4.Cu")
	)
	(gr_line
		(start 395.312646 -4.012184)
		(end 395.312646 -1.421384)
		(stroke
			(width 0.1016)
			(type default)
		)
		(layer "In4.Cu")
	)
	(gr_line
		(start 395.312646 -1.52146)
		(end 396.455646 -1.52146)
		(stroke
			(width 0.1016)
			(type default)
		)
		(layer "In4.Cu")
	)
	(gr_line
		(start 395.312646 -1.421384)
		(end 396.455646 -1.421384)
		(stroke
			(width 0.1016)
			(type default)
		)
		(layer "In4.Cu")
	)
	(gr_line
		(start 395.338046 -12.512548)
		(end 395.338046 -9.947148)
		(stroke
			(width 0.1016)
			(type default)
		)
		(layer "In4.Cu")
	)
	(gr_line
		(start 395.338046 -12.412472)
		(end 395.338046 -9.847072)
		(stroke
			(width 0.1016)
			(type default)
		)
		(layer "In4.Cu")
	)
	(gr_line
		(start 395.338046 -9.947148)
		(end 395.592046 -9.947148)
		(stroke
			(width 0.1016)
			(type default)
		)
		(layer "In4.Cu")
	)
	(gr_line
		(start 395.338046 -9.847072)
		(end 395.592046 -9.847072)
		(stroke
			(width 0.1016)
			(type default)
		)
		(layer "In4.Cu")
	)
	(gr_line
		(start 395.338046 -8.312404)
		(end 395.338046 -5.747004)
		(stroke
			(width 0.1016)
			(type default)
		)
		(layer "In4.Cu")
	)
	(gr_line
		(start 395.338046 -8.212328)
		(end 395.338046 -5.646928)
		(stroke
			(width 0.1016)
			(type default)
		)
		(layer "In4.Cu")
	)
	(gr_line
		(start 395.338046 -5.747004)
		(end 395.592046 -5.747004)
		(stroke
			(width 0.1016)
			(type default)
		)
		(layer "In4.Cu")
	)
	(gr_line
		(start 395.338046 -5.646928)
		(end 395.592046 -5.646928)
		(stroke
			(width 0.1016)
			(type default)
		)
		(layer "In4.Cu")
	)
	(gr_line
		(start 395.338046 -4.11226)
		(end 395.338046 -1.54686)
		(stroke
			(width 0.1016)
			(type default)
		)
		(layer "In4.Cu")
	)
	(gr_line
		(start 395.338046 -4.012184)
		(end 395.338046 -1.446784)
		(stroke
			(width 0.1016)
			(type default)
		)
		(layer "In4.Cu")
	)
	(gr_line
		(start 395.338046 -1.54686)
		(end 395.592046 -1.54686)
		(stroke
			(width 0.1016)
			(type default)
		)
		(layer "In4.Cu")
	)
	(gr_line
		(start 395.338046 -1.446784)
		(end 395.592046 -1.446784)
		(stroke
			(width 0.1016)
			(type default)
		)
		(layer "In4.Cu")
	)
	(gr_line
		(start 395.363446 -12.512548)
		(end 395.363446 -9.947148)
		(stroke
			(width 0.2032)
			(type default)
		)
		(layer "In4.Cu")
	)
	(gr_line
		(start 395.363446 -12.412472)
		(end 395.363446 -9.847072)
		(stroke
			(width 0.2032)
			(type default)
		)
		(layer "In4.Cu")
	)
	(gr_line
		(start 395.363446 -9.947148)
		(end 396.379446 -9.947148)
		(stroke
			(width 0.2032)
			(type default)
		)
		(layer "In4.Cu")
	)
	(gr_line
		(start 395.363446 -9.847072)
		(end 396.379446 -9.847072)
		(stroke
			(width 0.2032)
			(type default)
		)
		(layer "In4.Cu")
	)
	(gr_line
		(start 395.363446 -8.312404)
		(end 395.363446 -5.747004)
		(stroke
			(width 0.2032)
			(type default)
		)
		(layer "In4.Cu")
	)
	(gr_line
		(start 395.363446 -8.212328)
		(end 395.363446 -5.646928)
		(stroke
			(width 0.2032)
			(type default)
		)
		(layer "In4.Cu")
	)
	(gr_line
		(start 395.363446 -5.747004)
		(end 396.379446 -5.747004)
		(stroke
			(width 0.2032)
			(type default)
		)
		(layer "In4.Cu")
	)
	(gr_line
		(start 395.363446 -5.646928)
		(end 396.379446 -5.646928)
		(stroke
			(width 0.2032)
			(type default)
		)
		(layer "In4.Cu")
	)
	(gr_line
		(start 395.363446 -4.11226)
		(end 395.363446 -1.54686)
		(stroke
			(width 0.2032)
			(type default)
		)
		(layer "In4.Cu")
	)
	(gr_line
		(start 395.363446 -4.012184)
		(end 395.363446 -1.446784)
		(stroke
			(width 0.2032)
			(type default)
		)
		(layer "In4.Cu")
	)
	(gr_line
		(start 395.363446 -1.54686)
		(end 396.379446 -1.54686)
		(stroke
			(width 0.2032)
			(type default)
		)
		(layer "In4.Cu")
	)
	(gr_line
		(start 395.363446 -1.446784)
		(end 396.379446 -1.446784)
		(stroke
			(width 0.2032)
			(type default)
		)
		(layer "In4.Cu")
	)
	(gr_line
		(start 395.414246 -12.487148)
		(end 395.414246 -9.997948)
		(stroke
			(width 0.2032)
			(type default)
		)
		(layer "In4.Cu")
	)
	(gr_line
		(start 395.414246 -12.487148)
		(end 395.414246 -9.997948)
		(stroke
			(width 0.254)
			(type default)
		)
		(layer "In4.Cu")
	)
	(gr_line
		(start 395.414246 -12.387072)
		(end 395.414246 -9.897872)
		(stroke
			(width 0.2032)
			(type default)
		)
		(layer "In4.Cu")
	)
	(gr_line
		(start 395.414246 -12.387072)
		(end 395.414246 -9.897872)
		(stroke
			(width 0.254)
			(type default)
		)
		(layer "In4.Cu")
	)
	(gr_line
		(start 395.414246 -9.997948)
		(end 395.617446 -9.997948)
		(stroke
			(width 0.2032)
			(type default)
		)
		(layer "In4.Cu")
	)
	(gr_line
		(start 395.414246 -9.997948)
		(end 396.303246 -9.997948)
		(stroke
			(width 0.254)
			(type default)
		)
		(layer "In4.Cu")
	)
	(gr_line
		(start 395.414246 -9.897872)
		(end 395.617446 -9.897872)
		(stroke
			(width 0.2032)
			(type default)
		)
		(layer "In4.Cu")
	)
	(gr_line
		(start 395.414246 -9.897872)
		(end 396.303246 -9.897872)
		(stroke
			(width 0.254)
			(type default)
		)
		(layer "In4.Cu")
	)
	(gr_line
		(start 395.414246 -8.287004)
		(end 395.414246 -5.797804)
		(stroke
			(width 0.2032)
			(type default)
		)
		(layer "In4.Cu")
	)
	(gr_line
		(start 395.414246 -8.287004)
		(end 395.414246 -5.797804)
		(stroke
			(width 0.254)
			(type default)
		)
		(layer "In4.Cu")
	)
	(gr_line
		(start 395.414246 -8.186928)
		(end 395.414246 -5.697728)
		(stroke
			(width 0.2032)
			(type default)
		)
		(layer "In4.Cu")
	)
	(gr_line
		(start 395.414246 -8.186928)
		(end 395.414246 -5.697728)
		(stroke
			(width 0.254)
			(type default)
		)
		(layer "In4.Cu")
	)
	(gr_line
		(start 395.414246 -5.797804)
		(end 395.617446 -5.797804)
		(stroke
			(width 0.2032)
			(type default)
		)
		(layer "In4.Cu")
	)
	(gr_line
		(start 395.414246 -5.797804)
		(end 396.303246 -5.797804)
		(stroke
			(width 0.254)
			(type default)
		)
		(layer "In4.Cu")
	)
	(gr_line
		(start 395.414246 -5.697728)
		(end 395.617446 -5.697728)
		(stroke
			(width 0.2032)
			(type default)
		)
		(layer "In4.Cu")
	)
	(gr_line
		(start 395.414246 -5.697728)
		(end 396.303246 -5.697728)
		(stroke
			(width 0.254)
			(type default)
		)
		(layer "In4.Cu")
	)
	(gr_line
		(start 395.414246 -4.08686)
		(end 395.414246 -1.59766)
		(stroke
			(width 0.2032)
			(type default)
		)
		(layer "In4.Cu")
	)
	(gr_line
		(start 395.414246 -4.08686)
		(end 395.414246 -1.59766)
		(stroke
			(width 0.254)
			(type default)
		)
		(layer "In4.Cu")
	)
	(gr_line
		(start 395.414246 -3.986784)
		(end 395.414246 -1.497584)
		(stroke
			(width 0.2032)
			(type default)
		)
		(layer "In4.Cu")
	)
	(gr_line
		(start 395.414246 -3.986784)
		(end 395.414246 -1.497584)
		(stroke
			(width 0.254)
			(type default)
		)
		(layer "In4.Cu")
	)
	(gr_line
		(start 395.414246 -1.59766)
		(end 395.617446 -1.59766)
		(stroke
			(width 0.2032)
			(type default)
		)
		(layer "In4.Cu")
	)
	(gr_line
		(start 395.414246 -1.59766)
		(end 396.303246 -1.59766)
		(stroke
			(width 0.254)
			(type default)
		)
		(layer "In4.Cu")
	)
	(gr_line
		(start 395.414246 -1.497584)
		(end 395.617446 -1.497584)
		(stroke
			(width 0.2032)
			(type default)
		)
		(layer "In4.Cu")
	)
	(gr_line
		(start 395.414246 -1.497584)
		(end 396.303246 -1.497584)
		(stroke
			(width 0.254)
			(type default)
		)
		(layer "In4.Cu")
	)
	(gr_line
		(start 395.439646 -12.461748)
		(end 395.439646 -10.023348)
		(stroke
			(width 0.254)
			(type default)
		)
		(layer "In4.Cu")
	)
	(gr_line
		(start 395.439646 -12.361672)
		(end 395.439646 -9.923272)
		(stroke
			(width 0.254)
			(type default)
		)
		(layer "In4.Cu")
	)
	(gr_line
		(start 395.439646 -10.023348)
		(end 396.277846 -10.023348)
		(stroke
			(width 0.254)
			(type default)
		)
		(layer "In4.Cu")
	)
	(gr_line
		(start 395.439646 -9.923272)
		(end 396.277846 -9.923272)
		(stroke
			(width 0.254)
			(type default)
		)
		(layer "In4.Cu")
	)
	(gr_line
		(start 395.439646 -8.261604)
		(end 395.439646 -5.823204)
		(stroke
			(width 0.254)
			(type default)
		)
		(layer "In4.Cu")
	)
	(gr_line
		(start 395.439646 -8.161528)
		(end 395.439646 -5.723128)
		(stroke
			(width 0.254)
			(type default)
		)
		(layer "In4.Cu")
	)
	(gr_line
		(start 395.439646 -5.823204)
		(end 396.277846 -5.823204)
		(stroke
			(width 0.254)
			(type default)
		)
		(layer "In4.Cu")
	)
	(gr_line
		(start 395.439646 -5.723128)
		(end 396.277846 -5.723128)
		(stroke
			(width 0.254)
			(type default)
		)
		(layer "In4.Cu")
	)
	(gr_line
		(start 395.439646 -4.06146)
		(end 395.439646 -1.62306)
		(stroke
			(width 0.254)
			(type default)
		)
		(layer "In4.Cu")
	)
	(gr_line
		(start 395.439646 -3.961384)
		(end 395.439646 -1.522984)
		(stroke
			(width 0.254)
			(type default)
		)
		(layer "In4.Cu")
	)
	(gr_line
		(start 395.439646 -1.62306)
		(end 396.277846 -1.62306)
		(stroke
			(width 0.254)
			(type default)
		)
		(layer "In4.Cu")
	)
	(gr_line
		(start 395.439646 -1.522984)
		(end 396.277846 -1.522984)
		(stroke
			(width 0.254)
			(type default)
		)
		(layer "In4.Cu")
	)
	(gr_line
		(start 395.465046 -12.436348)
		(end 395.465046 -10.048748)
		(stroke
			(width 0.254)
			(type default)
		)
		(layer "In4.Cu")
	)
	(gr_line
		(start 395.465046 -12.336272)
		(end 395.465046 -9.948672)
		(stroke
			(width 0.254)
			(type default)
		)
		(layer "In4.Cu")
	)
	(gr_line
		(start 395.465046 -10.048748)
		(end 396.252446 -10.048748)
		(stroke
			(width 0.254)
			(type default)
		)
		(layer "In4.Cu")
	)
	(gr_line
		(start 395.465046 -9.948672)
		(end 396.252446 -9.948672)
		(stroke
			(width 0.254)
			(type default)
		)
		(layer "In4.Cu")
	)
	(gr_line
		(start 395.465046 -8.236204)
		(end 395.465046 -5.848604)
		(stroke
			(width 0.254)
			(type default)
		)
		(layer "In4.Cu")
	)
	(gr_line
		(start 395.465046 -8.136128)
		(end 395.465046 -5.748528)
		(stroke
			(width 0.254)
			(type default)
		)
		(layer "In4.Cu")
	)
	(gr_line
		(start 395.465046 -5.848604)
		(end 396.252446 -5.848604)
		(stroke
			(width 0.254)
			(type default)
		)
		(layer "In4.Cu")
	)
	(gr_line
		(start 395.465046 -5.748528)
		(end 396.252446 -5.748528)
		(stroke
			(width 0.254)
			(type default)
		)
		(layer "In4.Cu")
	)
	(gr_line
		(start 395.465046 -4.03606)
		(end 395.465046 -1.64846)
		(stroke
			(width 0.254)
			(type default)
		)
		(layer "In4.Cu")
	)
	(gr_line
		(start 395.465046 -3.935984)
		(end 395.465046 -1.548384)
		(stroke
			(width 0.254)
			(type default)
		)
		(layer "In4.Cu")
	)
	(gr_line
		(start 395.465046 -1.64846)
		(end 396.252446 -1.64846)
		(stroke
			(width 0.254)
			(type default)
		)
		(layer "In4.Cu")
	)
	(gr_line
		(start 395.465046 -1.548384)
		(end 396.252446 -1.548384)
		(stroke
			(width 0.254)
			(type default)
		)
		(layer "In4.Cu")
	)
	(gr_line
		(start 395.490446 -12.360148)
		(end 396.125446 -12.360148)
		(stroke
			(width 0.508)
			(type default)
		)
		(layer "In4.Cu")
	)
	(gr_line
		(start 395.490446 -12.260072)
		(end 396.125446 -12.260072)
		(stroke
			(width 0.508)
			(type default)
		)
		(layer "In4.Cu")
	)
	(gr_line
		(start 395.490446 -10.175748)
		(end 396.125446 -10.175748)
		(stroke
			(width 0.508)
			(type default)
		)
		(layer "In4.Cu")
	)
	(gr_line
		(start 395.490446 -10.124948)
		(end 396.125446 -10.124948)
		(stroke
			(width 0.508)
			(type default)
		)
		(layer "In4.Cu")
	)
	(gr_line
		(start 395.490446 -10.075672)
		(end 396.125446 -10.075672)
		(stroke
			(width 0.508)
			(type default)
		)
		(layer "In4.Cu")
	)
	(gr_line
		(start 395.490446 -10.024872)
		(end 396.125446 -10.024872)
		(stroke
			(width 0.508)
			(type default)
		)
		(layer "In4.Cu")
	)
	(gr_line
		(start 395.490446 -8.160004)
		(end 396.125446 -8.160004)
		(stroke
			(width 0.508)
			(type default)
		)
		(layer "In4.Cu")
	)
	(gr_line
		(start 395.490446 -8.059928)
		(end 396.125446 -8.059928)
		(stroke
			(width 0.508)
			(type default)
		)
		(layer "In4.Cu")
	)
	(gr_line
		(start 395.490446 -5.975604)
		(end 396.125446 -5.975604)
		(stroke
			(width 0.508)
			(type default)
		)
		(layer "In4.Cu")
	)
	(gr_line
		(start 395.490446 -5.924804)
		(end 396.125446 -5.924804)
		(stroke
			(width 0.508)
			(type default)
		)
		(layer "In4.Cu")
	)
	(gr_line
		(start 395.490446 -5.875528)
		(end 396.125446 -5.875528)
		(stroke
			(width 0.508)
			(type default)
		)
		(layer "In4.Cu")
	)
	(gr_line
		(start 395.490446 -5.824728)
		(end 396.125446 -5.824728)
		(stroke
			(width 0.508)
			(type default)
		)
		(layer "In4.Cu")
	)
	(gr_line
		(start 395.490446 -3.95986)
		(end 396.125446 -3.95986)
		(stroke
			(width 0.508)
			(type default)
		)
		(layer "In4.Cu")
	)
	(gr_line
		(start 395.490446 -3.859784)
		(end 396.125446 -3.859784)
		(stroke
			(width 0.508)
			(type default)
		)
		(layer "In4.Cu")
	)
	(gr_line
		(start 395.490446 -1.77546)
		(end 396.125446 -1.77546)
		(stroke
			(width 0.508)
			(type default)
		)
		(layer "In4.Cu")
	)
	(gr_line
		(start 395.490446 -1.72466)
		(end 396.125446 -1.72466)
		(stroke
			(width 0.508)
			(type default)
		)
		(layer "In4.Cu")
	)
	(gr_line
		(start 395.490446 -1.675384)
		(end 396.125446 -1.675384)
		(stroke
			(width 0.508)
			(type default)
		)
		(layer "In4.Cu")
	)
	(gr_line
		(start 395.490446 -1.624584)
		(end 396.125446 -1.624584)
		(stroke
			(width 0.508)
			(type default)
		)
		(layer "In4.Cu")
	)
	(gr_line
		(start 395.515846 -10.429748)
		(end 396.150846 -10.429748)
		(stroke
			(width 0.508)
			(type default)
		)
		(layer "In4.Cu")
	)
	(gr_line
		(start 395.515846 -10.329672)
		(end 396.150846 -10.329672)
		(stroke
			(width 0.508)
			(type default)
		)
		(layer "In4.Cu")
	)
	(gr_line
		(start 395.515846 -6.229604)
		(end 396.150846 -6.229604)
		(stroke
			(width 0.508)
			(type default)
		)
		(layer "In4.Cu")
	)
	(gr_line
		(start 395.515846 -6.129528)
		(end 396.150846 -6.129528)
		(stroke
			(width 0.508)
			(type default)
		)
		(layer "In4.Cu")
	)
	(gr_line
		(start 395.515846 -2.02946)
		(end 396.150846 -2.02946)
		(stroke
			(width 0.508)
			(type default)
		)
		(layer "In4.Cu")
	)
	(gr_line
		(start 395.515846 -1.929384)
		(end 396.150846 -1.929384)
		(stroke
			(width 0.508)
			(type default)
		)
		(layer "In4.Cu")
	)
	(gr_line
		(start 395.541246 -12.385548)
		(end 395.541246 -10.124948)
		(stroke
			(width 0.254)
			(type default)
		)
		(layer "In4.Cu")
	)
	(gr_line
		(start 395.541246 -12.285472)
		(end 395.541246 -10.024872)
		(stroke
			(width 0.254)
			(type default)
		)
		(layer "In4.Cu")
	)
	(gr_line
		(start 395.541246 -12.233148)
		(end 396.176246 -12.233148)
		(stroke
			(width 0.508)
			(type default)
		)
		(layer "In4.Cu")
	)
	(gr_line
		(start 395.541246 -12.133072)
		(end 396.176246 -12.133072)
		(stroke
			(width 0.508)
			(type default)
		)
		(layer "In4.Cu")
	)
	(gr_line
		(start 395.541246 -10.124948)
		(end 396.176246 -10.124948)
		(stroke
			(width 0.254)
			(type default)
		)
		(layer "In4.Cu")
	)
	(gr_line
		(start 395.541246 -10.024872)
		(end 396.176246 -10.024872)
		(stroke
			(width 0.254)
			(type default)
		)
		(layer "In4.Cu")
	)
	(gr_line
		(start 395.541246 -8.185404)
		(end 395.541246 -5.924804)
		(stroke
			(width 0.254)
			(type default)
		)
		(layer "In4.Cu")
	)
	(gr_line
		(start 395.541246 -8.085328)
		(end 395.541246 -5.824728)
		(stroke
			(width 0.254)
			(type default)
		)
		(layer "In4.Cu")
	)
	(gr_line
		(start 395.541246 -8.033004)
		(end 396.176246 -8.033004)
		(stroke
			(width 0.508)
			(type default)
		)
		(layer "In4.Cu")
	)
	(gr_line
		(start 395.541246 -7.932928)
		(end 396.176246 -7.932928)
		(stroke
			(width 0.508)
			(type default)
		)
		(layer "In4.Cu")
	)
	(gr_line
		(start 395.541246 -5.924804)
		(end 396.176246 -5.924804)
		(stroke
			(width 0.254)
			(type default)
		)
		(layer "In4.Cu")
	)
	(gr_line
		(start 395.541246 -5.824728)
		(end 396.176246 -5.824728)
		(stroke
			(width 0.254)
			(type default)
		)
		(layer "In4.Cu")
	)
	(gr_line
		(start 395.541246 -3.98526)
		(end 395.541246 -1.72466)
		(stroke
			(width 0.254)
			(type default)
		)
		(layer "In4.Cu")
	)
	(gr_line
		(start 395.541246 -3.885184)
		(end 395.541246 -1.624584)
		(stroke
			(width 0.254)
			(type default)
		)
		(layer "In4.Cu")
	)
	(gr_line
		(start 395.541246 -3.83286)
		(end 396.176246 -3.83286)
		(stroke
			(width 0.508)
			(type default)
		)
		(layer "In4.Cu")
	)
	(gr_line
		(start 395.541246 -3.732784)
		(end 396.176246 -3.732784)
		(stroke
			(width 0.508)
			(type default)
		)
		(layer "In4.Cu")
	)
	(gr_line
		(start 395.541246 -1.72466)
		(end 396.176246 -1.72466)
		(stroke
			(width 0.254)
			(type default)
		)
		(layer "In4.Cu")
	)
	(gr_line
		(start 395.541246 -1.624584)
		(end 396.176246 -1.624584)
		(stroke
			(width 0.254)
			(type default)
		)
		(layer "In4.Cu")
	)
	(gr_line
		(start 395.566646 -12.080748)
		(end 396.201646 -12.080748)
		(stroke
			(width 0.508)
			(type default)
		)
		(layer "In4.Cu")
	)
	(gr_line
		(start 395.566646 -11.980672)
		(end 396.201646 -11.980672)
		(stroke
			(width 0.508)
			(type default)
		)
		(layer "In4.Cu")
	)
	(gr_line
		(start 395.566646 -7.880604)
		(end 396.201646 -7.880604)
		(stroke
			(width 0.508)
			(type default)
		)
		(layer "In4.Cu")
	)
	(gr_line
		(start 395.566646 -7.780528)
		(end 396.201646 -7.780528)
		(stroke
			(width 0.508)
			(type default)
		)
		(layer "In4.Cu")
	)
	(gr_line
		(start 395.566646 -3.68046)
		(end 396.201646 -3.68046)
		(stroke
			(width 0.508)
			(type default)
		)
		(layer "In4.Cu")
	)
	(gr_line
		(start 395.566646 -3.580384)
		(end 396.201646 -3.580384)
		(stroke
			(width 0.508)
			(type default)
		)
		(layer "In4.Cu")
	)
	(gr_line
		(start 395.592046 -12.360148)
		(end 396.227046 -12.360148)
		(stroke
			(width 0.508)
			(type default)
		)
		(layer "In4.Cu")
	)
	(gr_line
		(start 395.592046 -12.260072)
		(end 396.227046 -12.260072)
		(stroke
			(width 0.508)
			(type default)
		)
		(layer "In4.Cu")
	)
	(gr_line
		(start 395.592046 -9.947148)
		(end 396.430246 -9.947148)
		(stroke
			(width 0.2032)
			(type default)
		)
		(layer "In4.Cu")
	)
	(gr_line
		(start 395.592046 -9.847072)
		(end 396.430246 -9.847072)
		(stroke
			(width 0.2032)
			(type default)
		)
		(layer "In4.Cu")
	)
	(gr_line
		(start 395.592046 -8.160004)
		(end 396.227046 -8.160004)
		(stroke
			(width 0.508)
			(type default)
		)
		(layer "In4.Cu")
	)
	(gr_line
		(start 395.592046 -8.059928)
		(end 396.227046 -8.059928)
		(stroke
			(width 0.508)
			(type default)
		)
		(layer "In4.Cu")
	)
	(gr_line
		(start 395.592046 -5.747004)
		(end 396.430246 -5.747004)
		(stroke
			(width 0.2032)
			(type default)
		)
		(layer "In4.Cu")
	)
	(gr_line
		(start 395.592046 -5.646928)
		(end 396.430246 -5.646928)
		(stroke
			(width 0.2032)
			(type default)
		)
		(layer "In4.Cu")
	)
	(gr_line
		(start 395.592046 -3.95986)
		(end 396.227046 -3.95986)
		(stroke
			(width 0.508)
			(type default)
		)
		(layer "In4.Cu")
	)
	(gr_line
		(start 395.592046 -3.859784)
		(end 396.227046 -3.859784)
		(stroke
			(width 0.508)
			(type default)
		)
		(layer "In4.Cu")
	)
	(gr_line
		(start 395.592046 -1.54686)
		(end 396.430246 -1.54686)
		(stroke
			(width 0.2032)
			(type default)
		)
		(layer "In4.Cu")
	)
	(gr_line
		(start 395.592046 -1.446784)
		(end 396.430246 -1.446784)
		(stroke
			(width 0.2032)
			(type default)
		)
		(layer "In4.Cu")
	)
	(gr_line
		(start 395.617446 -12.360148)
		(end 395.617446 -10.175748)
		(stroke
			(width 0.254)
			(type default)
		)
		(layer "In4.Cu")
	)
	(gr_line
		(start 395.617446 -12.260072)
		(end 395.617446 -10.075672)
		(stroke
			(width 0.254)
			(type default)
		)
		(layer "In4.Cu")
	)
	(gr_line
		(start 395.617446 -10.175748)
		(end 396.100046 -10.175748)
		(stroke
			(width 0.254)
			(type default)
		)
		(layer "In4.Cu")
	)
	(gr_line
		(start 395.617446 -10.075672)
		(end 396.100046 -10.075672)
		(stroke
			(width 0.254)
			(type default)
		)
		(layer "In4.Cu")
	)
	(gr_line
		(start 395.617446 -9.997948)
		(end 396.354046 -9.997948)
		(stroke
			(width 0.254)
			(type default)
		)
		(layer "In4.Cu")
	)
	(gr_line
		(start 395.617446 -9.897872)
		(end 396.354046 -9.897872)
		(stroke
			(width 0.254)
			(type default)
		)
		(layer "In4.Cu")
	)
	(gr_line
		(start 395.617446 -8.160004)
		(end 395.617446 -5.975604)
		(stroke
			(width 0.254)
			(type default)
		)
		(layer "In4.Cu")
	)
	(gr_line
		(start 395.617446 -8.059928)
		(end 395.617446 -5.875528)
		(stroke
			(width 0.254)
			(type default)
		)
		(layer "In4.Cu")
	)
	(gr_line
		(start 395.617446 -5.975604)
		(end 396.100046 -5.975604)
		(stroke
			(width 0.254)
			(type default)
		)
		(layer "In4.Cu")
	)
	(gr_line
		(start 395.617446 -5.875528)
		(end 396.100046 -5.875528)
		(stroke
			(width 0.254)
			(type default)
		)
		(layer "In4.Cu")
	)
	(gr_line
		(start 395.617446 -5.797804)
		(end 396.354046 -5.797804)
		(stroke
			(width 0.254)
			(type default)
		)
		(layer "In4.Cu")
	)
	(gr_line
		(start 395.617446 -5.697728)
		(end 396.354046 -5.697728)
		(stroke
			(width 0.254)
			(type default)
		)
		(layer "In4.Cu")
	)
	(gr_line
		(start 395.617446 -3.95986)
		(end 395.617446 -1.77546)
		(stroke
			(width 0.254)
			(type default)
		)
		(layer "In4.Cu")
	)
	(gr_line
		(start 395.617446 -3.859784)
		(end 395.617446 -1.675384)
		(stroke
			(width 0.254)
			(type default)
		)
		(layer "In4.Cu")
	)
	(gr_line
		(start 395.617446 -1.77546)
		(end 396.100046 -1.77546)
		(stroke
			(width 0.254)
			(type default)
		)
		(layer "In4.Cu")
	)
	(gr_line
		(start 395.617446 -1.675384)
		(end 396.100046 -1.675384)
		(stroke
			(width 0.254)
			(type default)
		)
		(layer "In4.Cu")
	)
	(gr_line
		(start 395.617446 -1.59766)
		(end 396.354046 -1.59766)
		(stroke
			(width 0.254)
			(type default)
		)
		(layer "In4.Cu")
	)
	(gr_line
		(start 395.617446 -1.497584)
		(end 396.354046 -1.497584)
		(stroke
			(width 0.254)
			(type default)
		)
		(layer "In4.Cu")
	)
	(gr_line
		(start 395.635988 -10.110978)
		(end 396.270988 -10.110978)
		(stroke
			(width 0.508)
			(type default)
		)
		(layer "In4.Cu")
	)
	(gr_line
		(start 395.635988 -10.010902)
		(end 396.270988 -10.010902)
		(stroke
			(width 0.508)
			(type default)
		)
		(layer "In4.Cu")
	)
	(gr_line
		(start 395.635988 -5.910834)
		(end 396.270988 -5.910834)
		(stroke
			(width 0.508)
			(type default)
		)
		(layer "In4.Cu")
	)
	(gr_line
		(start 395.635988 -5.810758)
		(end 396.270988 -5.810758)
		(stroke
			(width 0.508)
			(type default)
		)
		(layer "In4.Cu")
	)
	(gr_line
		(start 395.635988 -1.71069)
		(end 396.270988 -1.71069)
		(stroke
			(width 0.508)
			(type default)
		)
		(layer "In4.Cu")
	)
	(gr_line
		(start 395.635988 -1.610614)
		(end 396.270988 -1.610614)
		(stroke
			(width 0.508)
			(type default)
		)
		(layer "In4.Cu")
	)
	(gr_line
		(start 395.642846 -12.360148)
		(end 396.277846 -12.360148)
		(stroke
			(width 0.508)
			(type default)
		)
		(layer "In4.Cu")
	)
	(gr_line
		(start 395.642846 -12.260072)
		(end 396.277846 -12.260072)
		(stroke
			(width 0.508)
			(type default)
		)
		(layer "In4.Cu")
	)
	(gr_line
		(start 395.642846 -12.233148)
		(end 395.642846 -10.251948)
		(stroke
			(width 0.762)
			(type default)
		)
		(layer "In4.Cu")
	)
	(gr_line
		(start 395.642846 -12.133072)
		(end 395.642846 -10.151872)
		(stroke
			(width 0.762)
			(type default)
		)
		(layer "In4.Cu")
	)
	(gr_line
		(start 395.642846 -10.251948)
		(end 396.277846 -10.251948)
		(stroke
			(width 0.508)
			(type default)
		)
		(layer "In4.Cu")
	)
	(gr_line
		(start 395.642846 -10.151872)
		(end 396.277846 -10.151872)
		(stroke
			(width 0.508)
			(type default)
		)
		(layer "In4.Cu")
	)
	(gr_line
		(start 395.642846 -8.160004)
		(end 396.277846 -8.160004)
		(stroke
			(width 0.508)
			(type default)
		)
		(layer "In4.Cu")
	)
	(gr_line
		(start 395.642846 -8.059928)
		(end 396.277846 -8.059928)
		(stroke
			(width 0.508)
			(type default)
		)
		(layer "In4.Cu")
	)
	(gr_line
		(start 395.642846 -8.033004)
		(end 395.642846 -6.051804)
		(stroke
			(width 0.762)
			(type default)
		)
		(layer "In4.Cu")
	)
	(gr_line
		(start 395.642846 -7.932928)
		(end 395.642846 -5.951728)
		(stroke
			(width 0.762)
			(type default)
		)
		(layer "In4.Cu")
	)
	(gr_line
		(start 395.642846 -6.051804)
		(end 396.277846 -6.051804)
		(stroke
			(width 0.508)
			(type default)
		)
		(layer "In4.Cu")
	)
	(gr_line
		(start 395.642846 -5.951728)
		(end 396.277846 -5.951728)
		(stroke
			(width 0.508)
			(type default)
		)
		(layer "In4.Cu")
	)
	(gr_line
		(start 395.642846 -3.95986)
		(end 396.277846 -3.95986)
		(stroke
			(width 0.508)
			(type default)
		)
		(layer "In4.Cu")
	)
	(gr_line
		(start 395.642846 -3.859784)
		(end 396.277846 -3.859784)
		(stroke
			(width 0.508)
			(type default)
		)
		(layer "In4.Cu")
	)
	(gr_line
		(start 395.642846 -3.83286)
		(end 395.642846 -1.85166)
		(stroke
			(width 0.762)
			(type default)
		)
		(layer "In4.Cu")
	)
	(gr_line
		(start 395.642846 -3.732784)
		(end 395.642846 -1.751584)
		(stroke
			(width 0.762)
			(type default)
		)
		(layer "In4.Cu")
	)
	(gr_line
		(start 395.642846 -1.85166)
		(end 396.277846 -1.85166)
		(stroke
			(width 0.508)
			(type default)
		)
		(layer "In4.Cu")
	)
	(gr_line
		(start 395.642846 -1.751584)
		(end 396.277846 -1.751584)
		(stroke
			(width 0.508)
			(type default)
		)
		(layer "In4.Cu")
	)
	(gr_line
		(start 395.693646 -12.283948)
		(end 395.693646 -10.251948)
		(stroke
			(width 0.254)
			(type default)
		)
		(layer "In4.Cu")
	)
	(gr_line
		(start 395.693646 -12.183872)
		(end 395.693646 -10.151872)
		(stroke
			(width 0.254)
			(type default)
		)
		(layer "In4.Cu")
	)
	(gr_line
		(start 395.693646 -10.251948)
		(end 396.023846 -10.251948)
		(stroke
			(width 0.254)
			(type default)
		)
		(layer "In4.Cu")
	)
	(gr_line
		(start 395.693646 -10.151872)
		(end 396.023846 -10.151872)
		(stroke
			(width 0.254)
			(type default)
		)
		(layer "In4.Cu")
	)
	(gr_line
		(start 395.693646 -8.083804)
		(end 395.693646 -6.051804)
		(stroke
			(width 0.254)
			(type default)
		)
		(layer "In4.Cu")
	)
	(gr_line
		(start 395.693646 -7.983728)
		(end 395.693646 -5.951728)
		(stroke
			(width 0.254)
			(type default)
		)
		(layer "In4.Cu")
	)
	(gr_line
		(start 395.693646 -6.051804)
		(end 396.023846 -6.051804)
		(stroke
			(width 0.254)
			(type default)
		)
		(layer "In4.Cu")
	)
	(gr_line
		(start 395.693646 -5.951728)
		(end 396.023846 -5.951728)
		(stroke
			(width 0.254)
			(type default)
		)
		(layer "In4.Cu")
	)
	(gr_line
		(start 395.693646 -3.88366)
		(end 395.693646 -1.85166)
		(stroke
			(width 0.254)
			(type default)
		)
		(layer "In4.Cu")
	)
	(gr_line
		(start 395.693646 -3.783584)
		(end 395.693646 -1.751584)
		(stroke
			(width 0.254)
			(type default)
		)
		(layer "In4.Cu")
	)
	(gr_line
		(start 395.693646 -1.85166)
		(end 396.023846 -1.85166)
		(stroke
			(width 0.254)
			(type default)
		)
		(layer "In4.Cu")
	)
	(gr_line
		(start 395.693646 -1.751584)
		(end 396.023846 -1.751584)
		(stroke
			(width 0.254)
			(type default)
		)
		(layer "In4.Cu")
	)
	(gr_line
		(start 395.795246 -12.207748)
		(end 395.795246 -10.404348)
		(stroke
			(width 0.254)
			(type default)
		)
		(layer "In4.Cu")
	)
	(gr_line
		(start 395.795246 -12.207748)
		(end 395.795246 -10.226548)
		(stroke
			(width 0.762)
			(type default)
		)
		(layer "In4.Cu")
	)
	(gr_line
		(start 395.795246 -12.107672)
		(end 395.795246 -10.304272)
		(stroke
			(width 0.254)
			(type default)
		)
		(layer "In4.Cu")
	)
	(gr_line
		(start 395.795246 -12.107672)
		(end 395.795246 -10.126472)
		(stroke
			(width 0.762)
			(type default)
		)
		(layer "In4.Cu")
	)
	(gr_line
		(start 395.795246 -10.404348)
		(end 395.896846 -10.404348)
		(stroke
			(width 0.254)
			(type default)
		)
		(layer "In4.Cu")
	)
	(gr_line
		(start 395.795246 -10.304272)
		(end 395.896846 -10.304272)
		(stroke
			(width 0.254)
			(type default)
		)
		(layer "In4.Cu")
	)
	(gr_line
		(start 395.795246 -8.007604)
		(end 395.795246 -6.204204)
		(stroke
			(width 0.254)
			(type default)
		)
		(layer "In4.Cu")
	)
	(gr_line
		(start 395.795246 -8.007604)
		(end 395.795246 -6.026404)
		(stroke
			(width 0.762)
			(type default)
		)
		(layer "In4.Cu")
	)
	(gr_line
		(start 395.795246 -7.907528)
		(end 395.795246 -6.104128)
		(stroke
			(width 0.254)
			(type default)
		)
		(layer "In4.Cu")
	)
	(gr_line
		(start 395.795246 -7.907528)
		(end 395.795246 -5.926328)
		(stroke
			(width 0.762)
			(type default)
		)
		(layer "In4.Cu")
	)
	(gr_line
		(start 395.795246 -6.204204)
		(end 395.896846 -6.204204)
		(stroke
			(width 0.254)
			(type default)
		)
		(layer "In4.Cu")
	)
	(gr_line
		(start 395.795246 -6.104128)
		(end 395.896846 -6.104128)
		(stroke
			(width 0.254)
			(type default)
		)
		(layer "In4.Cu")
	)
	(gr_line
		(start 395.795246 -3.80746)
		(end 395.795246 -2.00406)
		(stroke
			(width 0.254)
			(type default)
		)
		(layer "In4.Cu")
	)
	(gr_line
		(start 395.795246 -3.80746)
		(end 395.795246 -1.82626)
		(stroke
			(width 0.762)
			(type default)
		)
		(layer "In4.Cu")
	)
	(gr_line
		(start 395.795246 -3.707384)
		(end 395.795246 -1.903984)
		(stroke
			(width 0.254)
			(type default)
		)
		(layer "In4.Cu")
	)
	(gr_line
		(start 395.795246 -3.707384)
		(end 395.795246 -1.726184)
		(stroke
			(width 0.762)
			(type default)
		)
		(layer "In4.Cu")
	)
	(gr_line
		(start 395.795246 -2.00406)
		(end 395.896846 -2.00406)
		(stroke
			(width 0.254)
			(type default)
		)
		(layer "In4.Cu")
	)
	(gr_line
		(start 395.795246 -1.903984)
		(end 395.896846 -1.903984)
		(stroke
			(width 0.254)
			(type default)
		)
		(layer "In4.Cu")
	)
	(gr_line
		(start 395.896846 -12.309348)
		(end 395.846046 -12.309348)
		(stroke
			(width 0.254)
			(type default)
		)
		(layer "In4.Cu")
	)
	(gr_line
		(start 395.896846 -12.209272)
		(end 395.846046 -12.209272)
		(stroke
			(width 0.254)
			(type default)
		)
		(layer "In4.Cu")
	)
	(gr_line
		(start 395.896846 -10.404348)
		(end 395.896846 -12.309348)
		(stroke
			(width 0.254)
			(type default)
		)
		(layer "In4.Cu")
	)
	(gr_line
		(start 395.896846 -10.304272)
		(end 395.896846 -12.209272)
		(stroke
			(width 0.254)
			(type default)
		)
		(layer "In4.Cu")
	)
	(gr_line
		(start 395.896846 -8.109204)
		(end 395.846046 -8.109204)
		(stroke
			(width 0.254)
			(type default)
		)
		(layer "In4.Cu")
	)
	(gr_line
		(start 395.896846 -8.009128)
		(end 395.846046 -8.009128)
		(stroke
			(width 0.254)
			(type default)
		)
		(layer "In4.Cu")
	)
	(gr_line
		(start 395.896846 -6.204204)
		(end 395.896846 -8.109204)
		(stroke
			(width 0.254)
			(type default)
		)
		(layer "In4.Cu")
	)
	(gr_line
		(start 395.896846 -6.104128)
		(end 395.896846 -8.009128)
		(stroke
			(width 0.254)
			(type default)
		)
		(layer "In4.Cu")
	)
	(gr_line
		(start 395.896846 -3.90906)
		(end 395.846046 -3.90906)
		(stroke
			(width 0.254)
			(type default)
		)
		(layer "In4.Cu")
	)
	(gr_line
		(start 395.896846 -3.808984)
		(end 395.846046 -3.808984)
		(stroke
			(width 0.254)
			(type default)
		)
		(layer "In4.Cu")
	)
	(gr_line
		(start 395.896846 -2.00406)
		(end 395.896846 -3.90906)
		(stroke
			(width 0.254)
			(type default)
		)
		(layer "In4.Cu")
	)
	(gr_line
		(start 395.896846 -1.903984)
		(end 395.896846 -3.808984)
		(stroke
			(width 0.254)
			(type default)
		)
		(layer "In4.Cu")
	)
	(gr_line
		(start 395.947646 -12.233148)
		(end 395.947646 -10.251948)
		(stroke
			(width 0.762)
			(type default)
		)
		(layer "In4.Cu")
	)
	(gr_line
		(start 395.947646 -12.133072)
		(end 395.947646 -10.151872)
		(stroke
			(width 0.762)
			(type default)
		)
		(layer "In4.Cu")
	)
	(gr_line
		(start 395.947646 -8.033004)
		(end 395.947646 -6.051804)
		(stroke
			(width 0.762)
			(type default)
		)
		(layer "In4.Cu")
	)
	(gr_line
		(start 395.947646 -7.932928)
		(end 395.947646 -5.951728)
		(stroke
			(width 0.762)
			(type default)
		)
		(layer "In4.Cu")
	)
	(gr_line
		(start 395.947646 -3.83286)
		(end 395.947646 -1.85166)
		(stroke
			(width 0.762)
			(type default)
		)
		(layer "In4.Cu")
	)
	(gr_line
		(start 395.947646 -3.732784)
		(end 395.947646 -1.751584)
		(stroke
			(width 0.762)
			(type default)
		)
		(layer "In4.Cu")
	)
	(gr_line
		(start 396.023846 -12.207748)
		(end 395.795246 -12.207748)
		(stroke
			(width 0.254)
			(type default)
		)
		(layer "In4.Cu")
	)
	(gr_line
		(start 396.023846 -12.107672)
		(end 395.795246 -12.107672)
		(stroke
			(width 0.254)
			(type default)
		)
		(layer "In4.Cu")
	)
	(gr_line
		(start 396.023846 -10.251948)
		(end 396.023846 -12.207748)
		(stroke
			(width 0.254)
			(type default)
		)
		(layer "In4.Cu")
	)
	(gr_line
		(start 396.023846 -10.151872)
		(end 396.023846 -12.107672)
		(stroke
			(width 0.254)
			(type default)
		)
		(layer "In4.Cu")
	)
	(gr_line
		(start 396.023846 -8.007604)
		(end 395.795246 -8.007604)
		(stroke
			(width 0.254)
			(type default)
		)
		(layer "In4.Cu")
	)
	(gr_line
		(start 396.023846 -7.907528)
		(end 395.795246 -7.907528)
		(stroke
			(width 0.254)
			(type default)
		)
		(layer "In4.Cu")
	)
	(gr_line
		(start 396.023846 -6.051804)
		(end 396.023846 -8.007604)
		(stroke
			(width 0.254)
			(type default)
		)
		(layer "In4.Cu")
	)
	(gr_line
		(start 396.023846 -5.951728)
		(end 396.023846 -7.907528)
		(stroke
			(width 0.254)
			(type default)
		)
		(layer "In4.Cu")
	)
	(gr_line
		(start 396.023846 -3.80746)
		(end 395.795246 -3.80746)
		(stroke
			(width 0.254)
			(type default)
		)
		(layer "In4.Cu")
	)
	(gr_line
		(start 396.023846 -3.707384)
		(end 395.795246 -3.707384)
		(stroke
			(width 0.254)
			(type default)
		)
		(layer "In4.Cu")
	)
	(gr_line
		(start 396.023846 -1.85166)
		(end 396.023846 -3.80746)
		(stroke
			(width 0.254)
			(type default)
		)
		(layer "In4.Cu")
	)
	(gr_line
		(start 396.023846 -1.751584)
		(end 396.023846 -3.707384)
		(stroke
			(width 0.254)
			(type default)
		)
		(layer "In4.Cu")
	)
	(gr_line
		(start 396.074646 -12.563348)
		(end 396.074646 -12.512548)
		(stroke
			(width 0.1016)
			(type default)
		)
		(layer "In4.Cu")
	)
	(gr_line
		(start 396.074646 -12.563348)
		(end 396.481046 -12.563348)
		(stroke
			(width 0.1016)
			(type default)
		)
		(layer "In4.Cu")
	)
	(gr_line
		(start 396.074646 -12.512548)
		(end 395.312646 -12.512548)
		(stroke
			(width 0.1016)
			(type default)
		)
		(layer "In4.Cu")
	)
	(gr_line
		(start 396.074646 -12.463272)
		(end 396.074646 -12.412472)
		(stroke
			(width 0.1016)
			(type default)
		)
		(layer "In4.Cu")
	)
	(gr_line
		(start 396.074646 -12.463272)
		(end 396.481046 -12.463272)
		(stroke
			(width 0.1016)
			(type default)
		)
		(layer "In4.Cu")
	)
	(gr_line
		(start 396.074646 -12.412472)
		(end 395.312646 -12.412472)
		(stroke
			(width 0.1016)
			(type default)
		)
		(layer "In4.Cu")
	)
	(gr_line
		(start 396.074646 -12.233148)
		(end 396.074646 -10.251948)
		(stroke
			(width 0.762)
			(type default)
		)
		(layer "In4.Cu")
	)
	(gr_line
		(start 396.074646 -12.133072)
		(end 396.074646 -10.151872)
		(stroke
			(width 0.762)
			(type default)
		)
		(layer "In4.Cu")
	)
	(gr_line
		(start 396.074646 -8.363204)
		(end 396.074646 -8.312404)
		(stroke
			(width 0.1016)
			(type default)
		)
		(layer "In4.Cu")
	)
	(gr_line
		(start 396.074646 -8.363204)
		(end 396.481046 -8.363204)
		(stroke
			(width 0.1016)
			(type default)
		)
		(layer "In4.Cu")
	)
	(gr_line
		(start 396.074646 -8.312404)
		(end 395.312646 -8.312404)
		(stroke
			(width 0.1016)
			(type default)
		)
		(layer "In4.Cu")
	)
	(gr_line
		(start 396.074646 -8.263128)
		(end 396.074646 -8.212328)
		(stroke
			(width 0.1016)
			(type default)
		)
		(layer "In4.Cu")
	)
	(gr_line
		(start 396.074646 -8.263128)
		(end 396.481046 -8.263128)
		(stroke
			(width 0.1016)
			(type default)
		)
		(layer "In4.Cu")
	)
	(gr_line
		(start 396.074646 -8.212328)
		(end 395.312646 -8.212328)
		(stroke
			(width 0.1016)
			(type default)
		)
		(layer "In4.Cu")
	)
	(gr_line
		(start 396.074646 -8.033004)
		(end 396.074646 -6.051804)
		(stroke
			(width 0.762)
			(type default)
		)
		(layer "In4.Cu")
	)
	(gr_line
		(start 396.074646 -7.932928)
		(end 396.074646 -5.951728)
		(stroke
			(width 0.762)
			(type default)
		)
		(layer "In4.Cu")
	)
	(gr_line
		(start 396.074646 -4.16306)
		(end 396.074646 -4.11226)
		(stroke
			(width 0.1016)
			(type default)
		)
		(layer "In4.Cu")
	)
	(gr_line
		(start 396.074646 -4.16306)
		(end 396.481046 -4.16306)
		(stroke
			(width 0.1016)
			(type default)
		)
		(layer "In4.Cu")
	)
	(gr_line
		(start 396.074646 -4.11226)
		(end 395.312646 -4.11226)
		(stroke
			(width 0.1016)
			(type default)
		)
		(layer "In4.Cu")
	)
	(gr_line
		(start 396.074646 -4.062984)
		(end 396.074646 -4.012184)
		(stroke
			(width 0.1016)
			(type default)
		)
		(layer "In4.Cu")
	)
	(gr_line
		(start 396.074646 -4.062984)
		(end 396.481046 -4.062984)
		(stroke
			(width 0.1016)
			(type default)
		)
		(layer "In4.Cu")
	)
	(gr_line
		(start 396.074646 -4.012184)
		(end 395.312646 -4.012184)
		(stroke
			(width 0.1016)
			(type default)
		)
		(layer "In4.Cu")
	)
	(gr_line
		(start 396.074646 -3.83286)
		(end 396.074646 -1.85166)
		(stroke
			(width 0.762)
			(type default)
		)
		(layer "In4.Cu")
	)
	(gr_line
		(start 396.074646 -3.732784)
		(end 396.074646 -1.751584)
		(stroke
			(width 0.762)
			(type default)
		)
		(layer "In4.Cu")
	)
	(gr_line
		(start 396.100046 -12.283948)
		(end 395.693646 -12.283948)
		(stroke
			(width 0.254)
			(type default)
		)
		(layer "In4.Cu")
	)
	(gr_line
		(start 396.100046 -12.183872)
		(end 395.693646 -12.183872)
		(stroke
			(width 0.254)
			(type default)
		)
		(layer "In4.Cu")
	)
	(gr_line
		(start 396.100046 -10.175748)
		(end 396.100046 -12.283948)
		(stroke
			(width 0.254)
			(type default)
		)
		(layer "In4.Cu")
	)
	(gr_line
		(start 396.100046 -10.075672)
		(end 396.100046 -12.183872)
		(stroke
			(width 0.254)
			(type default)
		)
		(layer "In4.Cu")
	)
	(gr_line
		(start 396.100046 -8.083804)
		(end 395.693646 -8.083804)
		(stroke
			(width 0.254)
			(type default)
		)
		(layer "In4.Cu")
	)
	(gr_line
		(start 396.100046 -7.983728)
		(end 395.693646 -7.983728)
		(stroke
			(width 0.254)
			(type default)
		)
		(layer "In4.Cu")
	)
	(gr_line
		(start 396.100046 -5.975604)
		(end 396.100046 -8.083804)
		(stroke
			(width 0.254)
			(type default)
		)
		(layer "In4.Cu")
	)
	(gr_line
		(start 396.100046 -5.875528)
		(end 396.100046 -7.983728)
		(stroke
			(width 0.254)
			(type default)
		)
		(layer "In4.Cu")
	)
	(gr_line
		(start 396.100046 -3.88366)
		(end 395.693646 -3.88366)
		(stroke
			(width 0.254)
			(type default)
		)
		(layer "In4.Cu")
	)
	(gr_line
		(start 396.100046 -3.783584)
		(end 395.693646 -3.783584)
		(stroke
			(width 0.254)
			(type default)
		)
		(layer "In4.Cu")
	)
	(gr_line
		(start 396.100046 -1.77546)
		(end 396.100046 -3.88366)
		(stroke
			(width 0.254)
			(type default)
		)
		(layer "In4.Cu")
	)
	(gr_line
		(start 396.100046 -1.675384)
		(end 396.100046 -3.783584)
		(stroke
			(width 0.254)
			(type default)
		)
		(layer "In4.Cu")
	)
	(gr_line
		(start 396.150846 -12.233148)
		(end 396.150846 -10.251948)
		(stroke
			(width 0.762)
			(type default)
		)
		(layer "In4.Cu")
	)
	(gr_line
		(start 396.150846 -12.133072)
		(end 396.150846 -10.151872)
		(stroke
			(width 0.762)
			(type default)
		)
		(layer "In4.Cu")
	)
	(gr_line
		(start 396.150846 -8.033004)
		(end 396.150846 -6.051804)
		(stroke
			(width 0.762)
			(type default)
		)
		(layer "In4.Cu")
	)
	(gr_line
		(start 396.150846 -7.932928)
		(end 396.150846 -5.951728)
		(stroke
			(width 0.762)
			(type default)
		)
		(layer "In4.Cu")
	)
	(gr_line
		(start 396.150846 -3.83286)
		(end 396.150846 -1.85166)
		(stroke
			(width 0.762)
			(type default)
		)
		(layer "In4.Cu")
	)
	(gr_line
		(start 396.150846 -3.732784)
		(end 396.150846 -1.751584)
		(stroke
			(width 0.762)
			(type default)
		)
		(layer "In4.Cu")
	)
	(gr_line
		(start 396.176246 -12.360148)
		(end 395.617446 -12.360148)
		(stroke
			(width 0.254)
			(type default)
		)
		(layer "In4.Cu")
	)
	(gr_line
		(start 396.176246 -12.260072)
		(end 395.617446 -12.260072)
		(stroke
			(width 0.254)
			(type default)
		)
		(layer "In4.Cu")
	)
	(gr_line
		(start 396.176246 -10.124948)
		(end 396.176246 -12.360148)
		(stroke
			(width 0.254)
			(type default)
		)
		(layer "In4.Cu")
	)
	(gr_line
		(start 396.176246 -10.024872)
		(end 396.176246 -12.260072)
		(stroke
			(width 0.254)
			(type default)
		)
		(layer "In4.Cu")
	)
	(gr_line
		(start 396.176246 -8.160004)
		(end 395.617446 -8.160004)
		(stroke
			(width 0.254)
			(type default)
		)
		(layer "In4.Cu")
	)
	(gr_line
		(start 396.176246 -8.059928)
		(end 395.617446 -8.059928)
		(stroke
			(width 0.254)
			(type default)
		)
		(layer "In4.Cu")
	)
	(gr_line
		(start 396.176246 -5.924804)
		(end 396.176246 -8.160004)
		(stroke
			(width 0.254)
			(type default)
		)
		(layer "In4.Cu")
	)
	(gr_line
		(start 396.176246 -5.824728)
		(end 396.176246 -8.059928)
		(stroke
			(width 0.254)
			(type default)
		)
		(layer "In4.Cu")
	)
	(gr_line
		(start 396.176246 -3.95986)
		(end 395.617446 -3.95986)
		(stroke
			(width 0.254)
			(type default)
		)
		(layer "In4.Cu")
	)
	(gr_line
		(start 396.176246 -3.859784)
		(end 395.617446 -3.859784)
		(stroke
			(width 0.254)
			(type default)
		)
		(layer "In4.Cu")
	)
	(gr_line
		(start 396.176246 -1.72466)
		(end 396.176246 -3.95986)
		(stroke
			(width 0.254)
			(type default)
		)
		(layer "In4.Cu")
	)
	(gr_line
		(start 396.176246 -1.624584)
		(end 396.176246 -3.859784)
		(stroke
			(width 0.254)
			(type default)
		)
		(layer "In4.Cu")
	)
	(gr_line
		(start 396.252446 -12.385548)
		(end 395.541246 -12.385548)
		(stroke
			(width 0.254)
			(type default)
		)
		(layer "In4.Cu")
	)
	(gr_line
		(start 396.252446 -12.285472)
		(end 395.541246 -12.285472)
		(stroke
			(width 0.254)
			(type default)
		)
		(layer "In4.Cu")
	)
	(gr_line
		(start 396.252446 -10.048748)
		(end 396.252446 -12.385548)
		(stroke
			(width 0.254)
			(type default)
		)
		(layer "In4.Cu")
	)
	(gr_line
		(start 396.252446 -9.948672)
		(end 396.252446 -12.285472)
		(stroke
			(width 0.254)
			(type default)
		)
		(layer "In4.Cu")
	)
	(gr_line
		(start 396.252446 -8.185404)
		(end 395.541246 -8.185404)
		(stroke
			(width 0.254)
			(type default)
		)
		(layer "In4.Cu")
	)
	(gr_line
		(start 396.252446 -8.085328)
		(end 395.541246 -8.085328)
		(stroke
			(width 0.254)
			(type default)
		)
		(layer "In4.Cu")
	)
	(gr_line
		(start 396.252446 -5.848604)
		(end 396.252446 -8.185404)
		(stroke
			(width 0.254)
			(type default)
		)
		(layer "In4.Cu")
	)
	(gr_line
		(start 396.252446 -5.748528)
		(end 396.252446 -8.085328)
		(stroke
			(width 0.254)
			(type default)
		)
		(layer "In4.Cu")
	)
	(gr_line
		(start 396.252446 -3.98526)
		(end 395.541246 -3.98526)
		(stroke
			(width 0.254)
			(type default)
		)
		(layer "In4.Cu")
	)
	(gr_line
		(start 396.252446 -3.885184)
		(end 395.541246 -3.885184)
		(stroke
			(width 0.254)
			(type default)
		)
		(layer "In4.Cu")
	)
	(gr_line
		(start 396.252446 -1.64846)
		(end 396.252446 -3.98526)
		(stroke
			(width 0.254)
			(type default)
		)
		(layer "In4.Cu")
	)
	(gr_line
		(start 396.252446 -1.548384)
		(end 396.252446 -3.885184)
		(stroke
			(width 0.254)
			(type default)
		)
		(layer "In4.Cu")
	)
	(gr_line
		(start 396.277846 -12.512548)
		(end 395.287246 -12.512548)
		(stroke
			(width 0.1016)
			(type default)
		)
		(layer "In4.Cu")
	)
	(gr_line
		(start 396.277846 -12.436348)
		(end 395.465046 -12.436348)
		(stroke
			(width 0.254)
			(type default)
		)
		(layer "In4.Cu")
	)
	(gr_line
		(start 396.277846 -12.412472)
		(end 395.287246 -12.412472)
		(stroke
			(width 0.1016)
			(type default)
		)
		(layer "In4.Cu")
	)
	(gr_line
		(start 396.277846 -12.336272)
		(end 395.465046 -12.336272)
		(stroke
			(width 0.254)
			(type default)
		)
		(layer "In4.Cu")
	)
	(gr_line
		(start 396.277846 -10.023348)
		(end 396.277846 -12.436348)
		(stroke
			(width 0.254)
			(type default)
		)
		(layer "In4.Cu")
	)
	(gr_line
		(start 396.277846 -9.923272)
		(end 396.277846 -12.336272)
		(stroke
			(width 0.254)
			(type default)
		)
		(layer "In4.Cu")
	)
	(gr_line
		(start 396.277846 -8.312404)
		(end 395.287246 -8.312404)
		(stroke
			(width 0.1016)
			(type default)
		)
		(layer "In4.Cu")
	)
	(gr_line
		(start 396.277846 -8.236204)
		(end 395.465046 -8.236204)
		(stroke
			(width 0.254)
			(type default)
		)
		(layer "In4.Cu")
	)
	(gr_line
		(start 396.277846 -8.212328)
		(end 395.287246 -8.212328)
		(stroke
			(width 0.1016)
			(type default)
		)
		(layer "In4.Cu")
	)
	(gr_line
		(start 396.277846 -8.136128)
		(end 395.465046 -8.136128)
		(stroke
			(width 0.254)
			(type default)
		)
		(layer "In4.Cu")
	)
	(gr_line
		(start 396.277846 -5.823204)
		(end 396.277846 -8.236204)
		(stroke
			(width 0.254)
			(type default)
		)
		(layer "In4.Cu")
	)
	(gr_line
		(start 396.277846 -5.723128)
		(end 396.277846 -8.136128)
		(stroke
			(width 0.254)
			(type default)
		)
		(layer "In4.Cu")
	)
	(gr_line
		(start 396.277846 -4.11226)
		(end 395.287246 -4.11226)
		(stroke
			(width 0.1016)
			(type default)
		)
		(layer "In4.Cu")
	)
	(gr_line
		(start 396.277846 -4.03606)
		(end 395.465046 -4.03606)
		(stroke
			(width 0.254)
			(type default)
		)
		(layer "In4.Cu")
	)
	(gr_line
		(start 396.277846 -4.012184)
		(end 395.287246 -4.012184)
		(stroke
			(width 0.1016)
			(type default)
		)
		(layer "In4.Cu")
	)
	(gr_line
		(start 396.277846 -3.935984)
		(end 395.465046 -3.935984)
		(stroke
			(width 0.254)
			(type default)
		)
		(layer "In4.Cu")
	)
	(gr_line
		(start 396.277846 -1.62306)
		(end 396.277846 -4.03606)
		(stroke
			(width 0.254)
			(type default)
		)
		(layer "In4.Cu")
	)
	(gr_line
		(start 396.277846 -1.522984)
		(end 396.277846 -3.935984)
		(stroke
			(width 0.254)
			(type default)
		)
		(layer "In4.Cu")
	)
	(gr_line
		(start 396.303246 -12.461748)
		(end 395.439646 -12.461748)
		(stroke
			(width 0.254)
			(type default)
		)
		(layer "In4.Cu")
	)
	(gr_line
		(start 396.303246 -12.361672)
		(end 395.439646 -12.361672)
		(stroke
			(width 0.254)
			(type default)
		)
		(layer "In4.Cu")
	)
	(gr_line
		(start 396.303246 -9.997948)
		(end 396.303246 -12.461748)
		(stroke
			(width 0.254)
			(type default)
		)
		(layer "In4.Cu")
	)
	(gr_line
		(start 396.303246 -9.897872)
		(end 396.303246 -12.361672)
		(stroke
			(width 0.254)
			(type default)
		)
		(layer "In4.Cu")
	)
	(gr_line
		(start 396.303246 -8.261604)
		(end 395.439646 -8.261604)
		(stroke
			(width 0.254)
			(type default)
		)
		(layer "In4.Cu")
	)
	(gr_line
		(start 396.303246 -8.161528)
		(end 395.439646 -8.161528)
		(stroke
			(width 0.254)
			(type default)
		)
		(layer "In4.Cu")
	)
	(gr_line
		(start 396.303246 -5.797804)
		(end 396.303246 -8.261604)
		(stroke
			(width 0.254)
			(type default)
		)
		(layer "In4.Cu")
	)
	(gr_line
		(start 396.303246 -5.697728)
		(end 396.303246 -8.161528)
		(stroke
			(width 0.254)
			(type default)
		)
		(layer "In4.Cu")
	)
	(gr_line
		(start 396.303246 -4.06146)
		(end 395.439646 -4.06146)
		(stroke
			(width 0.254)
			(type default)
		)
		(layer "In4.Cu")
	)
	(gr_line
		(start 396.303246 -3.961384)
		(end 395.439646 -3.961384)
		(stroke
			(width 0.254)
			(type default)
		)
		(layer "In4.Cu")
	)
	(gr_line
		(start 396.303246 -1.59766)
		(end 396.303246 -4.06146)
		(stroke
			(width 0.254)
			(type default)
		)
		(layer "In4.Cu")
	)
	(gr_line
		(start 396.303246 -1.497584)
		(end 396.303246 -3.961384)
		(stroke
			(width 0.254)
			(type default)
		)
		(layer "In4.Cu")
	)
	(gr_line
		(start 396.354046 -12.487148)
		(end 395.414246 -12.487148)
		(stroke
			(width 0.254)
			(type default)
		)
		(layer "In4.Cu")
	)
	(gr_line
		(start 396.354046 -12.387072)
		(end 395.414246 -12.387072)
		(stroke
			(width 0.254)
			(type default)
		)
		(layer "In4.Cu")
	)
	(gr_line
		(start 396.354046 -9.997948)
		(end 396.354046 -12.487148)
		(stroke
			(width 0.254)
			(type default)
		)
		(layer "In4.Cu")
	)
	(gr_line
		(start 396.354046 -9.897872)
		(end 396.354046 -12.387072)
		(stroke
			(width 0.254)
			(type default)
		)
		(layer "In4.Cu")
	)
	(gr_line
		(start 396.354046 -8.287004)
		(end 395.414246 -8.287004)
		(stroke
			(width 0.254)
			(type default)
		)
		(layer "In4.Cu")
	)
	(gr_line
		(start 396.354046 -8.186928)
		(end 395.414246 -8.186928)
		(stroke
			(width 0.254)
			(type default)
		)
		(layer "In4.Cu")
	)
	(gr_line
		(start 396.354046 -5.797804)
		(end 396.354046 -8.287004)
		(stroke
			(width 0.254)
			(type default)
		)
		(layer "In4.Cu")
	)
	(gr_line
		(start 396.354046 -5.697728)
		(end 396.354046 -8.186928)
		(stroke
			(width 0.254)
			(type default)
		)
		(layer "In4.Cu")
	)
	(gr_line
		(start 396.354046 -4.08686)
		(end 395.414246 -4.08686)
		(stroke
			(width 0.254)
			(type default)
		)
		(layer "In4.Cu")
	)
	(gr_line
		(start 396.354046 -3.986784)
		(end 395.414246 -3.986784)
		(stroke
			(width 0.254)
			(type default)
		)
		(layer "In4.Cu")
	)
	(gr_line
		(start 396.354046 -1.59766)
		(end 396.354046 -4.08686)
		(stroke
			(width 0.254)
			(type default)
		)
		(layer "In4.Cu")
	)
	(gr_line
		(start 396.354046 -1.497584)
		(end 396.354046 -3.986784)
		(stroke
			(width 0.254)
			(type default)
		)
		(layer "In4.Cu")
	)
	(gr_line
		(start 396.379446 -12.487148)
		(end 395.414246 -12.487148)
		(stroke
			(width 0.2032)
			(type default)
		)
		(layer "In4.Cu")
	)
	(gr_line
		(start 396.379446 -12.387072)
		(end 395.414246 -12.387072)
		(stroke
			(width 0.2032)
			(type default)
		)
		(layer "In4.Cu")
	)
	(gr_line
		(start 396.379446 -9.947148)
		(end 396.379446 -12.487148)
		(stroke
			(width 0.2032)
			(type default)
		)
		(layer "In4.Cu")
	)
	(gr_line
		(start 396.379446 -9.847072)
		(end 396.379446 -12.387072)
		(stroke
			(width 0.2032)
			(type default)
		)
		(layer "In4.Cu")
	)
	(gr_line
		(start 396.379446 -8.287004)
		(end 395.414246 -8.287004)
		(stroke
			(width 0.2032)
			(type default)
		)
		(layer "In4.Cu")
	)
	(gr_line
		(start 396.379446 -8.186928)
		(end 395.414246 -8.186928)
		(stroke
			(width 0.2032)
			(type default)
		)
		(layer "In4.Cu")
	)
	(gr_line
		(start 396.379446 -5.747004)
		(end 396.379446 -8.287004)
		(stroke
			(width 0.2032)
			(type default)
		)
		(layer "In4.Cu")
	)
	(gr_line
		(start 396.379446 -5.646928)
		(end 396.379446 -8.186928)
		(stroke
			(width 0.2032)
			(type default)
		)
		(layer "In4.Cu")
	)
	(gr_line
		(start 396.379446 -4.08686)
		(end 395.414246 -4.08686)
		(stroke
			(width 0.2032)
			(type default)
		)
		(layer "In4.Cu")
	)
	(gr_line
		(start 396.379446 -3.986784)
		(end 395.414246 -3.986784)
		(stroke
			(width 0.2032)
			(type default)
		)
		(layer "In4.Cu")
	)
	(gr_line
		(start 396.379446 -1.54686)
		(end 396.379446 -4.08686)
		(stroke
			(width 0.2032)
			(type default)
		)
		(layer "In4.Cu")
	)
	(gr_line
		(start 396.379446 -1.446784)
		(end 396.379446 -3.986784)
		(stroke
			(width 0.2032)
			(type default)
		)
		(layer "In4.Cu")
	)
	(gr_line
		(start 396.430246 -12.512548)
		(end 395.363446 -12.512548)
		(stroke
			(width 0.2032)
			(type default)
		)
		(layer "In4.Cu")
	)
	(gr_line
		(start 396.430246 -12.412472)
		(end 395.363446 -12.412472)
		(stroke
			(width 0.2032)
			(type default)
		)
		(layer "In4.Cu")
	)
	(gr_line
		(start 396.430246 -9.947148)
		(end 396.430246 -12.512548)
		(stroke
			(width 0.2032)
			(type default)
		)
		(layer "In4.Cu")
	)
	(gr_line
		(start 396.430246 -9.847072)
		(end 396.430246 -12.412472)
		(stroke
			(width 0.2032)
			(type default)
		)
		(layer "In4.Cu")
	)
	(gr_line
		(start 396.430246 -8.312404)
		(end 395.363446 -8.312404)
		(stroke
			(width 0.2032)
			(type default)
		)
		(layer "In4.Cu")
	)
	(gr_line
		(start 396.430246 -8.212328)
		(end 395.363446 -8.212328)
		(stroke
			(width 0.2032)
			(type default)
		)
		(layer "In4.Cu")
	)
	(gr_line
		(start 396.430246 -5.747004)
		(end 396.430246 -8.312404)
		(stroke
			(width 0.2032)
			(type default)
		)
		(layer "In4.Cu")
	)
	(gr_line
		(start 396.430246 -5.646928)
		(end 396.430246 -8.212328)
		(stroke
			(width 0.2032)
			(type default)
		)
		(layer "In4.Cu")
	)
	(gr_line
		(start 396.430246 -4.11226)
		(end 395.363446 -4.11226)
		(stroke
			(width 0.2032)
			(type default)
		)
		(layer "In4.Cu")
	)
	(gr_line
		(start 396.430246 -4.012184)
		(end 395.363446 -4.012184)
		(stroke
			(width 0.2032)
			(type default)
		)
		(layer "In4.Cu")
	)
	(gr_line
		(start 396.430246 -1.54686)
		(end 396.430246 -4.11226)
		(stroke
			(width 0.2032)
			(type default)
		)
		(layer "In4.Cu")
	)
	(gr_line
		(start 396.430246 -1.446784)
		(end 396.430246 -4.012184)
		(stroke
			(width 0.2032)
			(type default)
		)
		(layer "In4.Cu")
	)
	(gr_line
		(start 396.455646 -12.512548)
		(end 395.338046 -12.512548)
		(stroke
			(width 0.1016)
			(type default)
		)
		(layer "In4.Cu")
	)
	(gr_line
		(start 396.455646 -12.412472)
		(end 395.338046 -12.412472)
		(stroke
			(width 0.1016)
			(type default)
		)
		(layer "In4.Cu")
	)
	(gr_line
		(start 396.455646 -9.921748)
		(end 396.455646 -12.512548)
		(stroke
			(width 0.1016)
			(type default)
		)
		(layer "In4.Cu")
	)
	(gr_line
		(start 396.455646 -9.821672)
		(end 396.455646 -12.412472)
		(stroke
			(width 0.1016)
			(type default)
		)
		(layer "In4.Cu")
	)
	(gr_line
		(start 396.455646 -8.312404)
		(end 395.338046 -8.312404)
		(stroke
			(width 0.1016)
			(type default)
		)
		(layer "In4.Cu")
	)
	(gr_line
		(start 396.455646 -8.212328)
		(end 395.338046 -8.212328)
		(stroke
			(width 0.1016)
			(type default)
		)
		(layer "In4.Cu")
	)
	(gr_line
		(start 396.455646 -5.721604)
		(end 396.455646 -8.312404)
		(stroke
			(width 0.1016)
			(type default)
		)
		(layer "In4.Cu")
	)
	(gr_line
		(start 396.455646 -5.621528)
		(end 396.455646 -8.212328)
		(stroke
			(width 0.1016)
			(type default)
		)
		(layer "In4.Cu")
	)
	(gr_line
		(start 396.455646 -4.11226)
		(end 395.338046 -4.11226)
		(stroke
			(width 0.1016)
			(type default)
		)
		(layer "In4.Cu")
	)
	(gr_line
		(start 396.455646 -4.012184)
		(end 395.338046 -4.012184)
		(stroke
			(width 0.1016)
			(type default)
		)
		(layer "In4.Cu")
	)
	(gr_line
		(start 396.455646 -1.52146)
		(end 396.455646 -4.11226)
		(stroke
			(width 0.1016)
			(type default)
		)
		(layer "In4.Cu")
	)
	(gr_line
		(start 396.455646 -1.421384)
		(end 396.455646 -4.012184)
		(stroke
			(width 0.1016)
			(type default)
		)
		(layer "In4.Cu")
	)
	(gr_line
		(start 396.481046 -12.563348)
		(end 396.074646 -12.563348)
		(stroke
			(width 0.1016)
			(type default)
		)
		(layer "In4.Cu")
	)
	(gr_line
		(start 396.481046 -12.563348)
		(end 396.481046 -9.896348)
		(stroke
			(width 0.1016)
			(type default)
		)
		(layer "In4.Cu")
	)
	(gr_line
		(start 396.481046 -12.463272)
		(end 396.074646 -12.463272)
		(stroke
			(width 0.1016)
			(type default)
		)
		(layer "In4.Cu")
	)
	(gr_line
		(start 396.481046 -12.463272)
		(end 396.481046 -9.796272)
		(stroke
			(width 0.1016)
			(type default)
		)
		(layer "In4.Cu")
	)
	(gr_line
		(start 396.481046 -9.896348)
		(end 395.287246 -9.896348)
		(stroke
			(width 0.1016)
			(type default)
		)
		(layer "In4.Cu")
	)
	(gr_line
		(start 396.481046 -9.896348)
		(end 396.481046 -12.563348)
		(stroke
			(width 0.1016)
			(type default)
		)
		(layer "In4.Cu")
	)
	(gr_line
		(start 396.481046 -9.796272)
		(end 395.287246 -9.796272)
		(stroke
			(width 0.1016)
			(type default)
		)
		(layer "In4.Cu")
	)
	(gr_line
		(start 396.481046 -9.796272)
		(end 396.481046 -12.463272)
		(stroke
			(width 0.1016)
			(type default)
		)
		(layer "In4.Cu")
	)
	(gr_line
		(start 396.481046 -8.363204)
		(end 396.074646 -8.363204)
		(stroke
			(width 0.1016)
			(type default)
		)
		(layer "In4.Cu")
	)
	(gr_line
		(start 396.481046 -8.363204)
		(end 396.481046 -5.696204)
		(stroke
			(width 0.1016)
			(type default)
		)
		(layer "In4.Cu")
	)
	(gr_line
		(start 396.481046 -8.263128)
		(end 396.074646 -8.263128)
		(stroke
			(width 0.1016)
			(type default)
		)
		(layer "In4.Cu")
	)
	(gr_line
		(start 396.481046 -8.263128)
		(end 396.481046 -5.596128)
		(stroke
			(width 0.1016)
			(type default)
		)
		(layer "In4.Cu")
	)
	(gr_line
		(start 396.481046 -5.696204)
		(end 395.287246 -5.696204)
		(stroke
			(width 0.1016)
			(type default)
		)
		(layer "In4.Cu")
	)
	(gr_line
		(start 396.481046 -5.696204)
		(end 396.481046 -8.363204)
		(stroke
			(width 0.1016)
			(type default)
		)
		(layer "In4.Cu")
	)
	(gr_line
		(start 396.481046 -5.596128)
		(end 395.287246 -5.596128)
		(stroke
			(width 0.1016)
			(type default)
		)
		(layer "In4.Cu")
	)
	(gr_line
		(start 396.481046 -5.596128)
		(end 396.481046 -8.263128)
		(stroke
			(width 0.1016)
			(type default)
		)
		(layer "In4.Cu")
	)
	(gr_line
		(start 396.481046 -4.16306)
		(end 396.074646 -4.16306)
		(stroke
			(width 0.1016)
			(type default)
		)
		(layer "In4.Cu")
	)
	(gr_line
		(start 396.481046 -4.16306)
		(end 396.481046 -1.49606)
		(stroke
			(width 0.1016)
			(type default)
		)
		(layer "In4.Cu")
	)
	(gr_line
		(start 396.481046 -4.062984)
		(end 396.074646 -4.062984)
		(stroke
			(width 0.1016)
			(type default)
		)
		(layer "In4.Cu")
	)
	(gr_line
		(start 396.481046 -4.062984)
		(end 396.481046 -1.395984)
		(stroke
			(width 0.1016)
			(type default)
		)
		(layer "In4.Cu")
	)
	(gr_line
		(start 396.481046 -1.49606)
		(end 395.287246 -1.49606)
		(stroke
			(width 0.1016)
			(type default)
		)
		(layer "In4.Cu")
	)
	(gr_line
		(start 396.481046 -1.49606)
		(end 396.481046 -4.16306)
		(stroke
			(width 0.1016)
			(type default)
		)
		(layer "In4.Cu")
	)
	(gr_line
		(start 396.481046 -1.494028)
		(end 395.261846 -1.494028)
		(stroke
			(width 0.1016)
			(type default)
		)
		(layer "In4.Cu")
	)
	(gr_line
		(start 396.481046 -1.494028)
		(end 395.287246 -1.494028)
		(stroke
			(width 0.1016)
			(type default)
		)
		(layer "In4.Cu")
	)
	(gr_line
		(start 396.481046 -1.395984)
		(end 395.287246 -1.395984)
		(stroke
			(width 0.1016)
			(type default)
		)
		(layer "In4.Cu")
	)
	(gr_line
		(start 396.481046 -1.395984)
		(end 396.481046 -4.062984)
		(stroke
			(width 0.1016)
			(type default)
		)
		(layer "In4.Cu")
	)
	(gr_line
		(start 396.506446 -1.468628)
		(end 395.261846 -1.468628)
		(stroke
			(width 0.1016)
			(type default)
		)
		(layer "In4.Cu")
	)
	(gr_line
		(start 397.519906 -30.99562)
		(end 396.249906 -30.99562)
		(stroke
			(width 0.7874)
			(type default)
		)
		(layer "In4.Cu")
	)
	(gr_line
		(start 399.224246 -24.6634)
		(end 399.224246 -23.3934)
		(stroke
			(width 0.7874)
			(type default)
		)
		(layer "In4.Cu")
	)
	(gr_line
		(start 404.997412 -26.8224)
		(end 406.267412 -26.8224)
		(stroke
			(width 0.7874)
			(type default)
		)
		(layer "In4.Cu")
	)
	(gr_line
		(start 405.228552 -29.30906)
		(end 406.498552 -29.30906)
		(stroke
			(width 0.7874)
			(type default)
		)
		(layer "In4.Cu")
	)
	(gr_line
		(start 410.459682 -30.594808)
		(end 411.729682 -30.594808)
		(stroke
			(width 0.7874)
			(type default)
		)
		(layer "In4.Cu")
	)
	(gr_line
		(start 410.859986 -23.57882)
		(end 412.129986 -23.57882)
		(stroke
			(width 0.7874)
			(type default)
		)
		(layer "In4.Cu")
	)
	(gr_line
		(start 412.873952 -31.68142)
		(end 414.143952 -31.68142)
		(stroke
			(width 0.7874)
			(type default)
		)
		(layer "In4.Cu")
	)
	(gr_line
		(start 413.260032 -18.5166)
		(end 414.530032 -18.5166)
		(stroke
			(width 0.7874)
			(type default)
		)
		(layer "In4.Cu")
	)
	(gr_line
		(start 415.259774 -30.56382)
		(end 416.529774 -30.56382)
		(stroke
			(width 0.7874)
			(type default)
		)
		(layer "In4.Cu")
	)
	(gr_line
		(start 418.662866 -24.67102)
		(end 418.662866 -23.40102)
		(stroke
			(width 0.7874)
			(type default)
		)
		(layer "In4.Cu")
	)
	(gr_line
		(start 424.310048 -4.700016)
		(end 424.310048 -4.699762)
		(stroke
			(width 8.128)
			(type default)
		)
		(layer "In4.Cu")
	)
	(gr_arc
		(start 425.010072 -41.000172)
		(mid 425.156481 -41.353635)
		(end 425.509944 -41.500044)
		(stroke
			(width 2.032)
			(type default)
		)
		(layer "In4.Cu")
	)
	(gr_line
		(start 425.010072 -31.999936)
		(end 425.010072 -41.000172)
		(stroke
			(width 2.032)
			(type default)
		)
		(layer "In4.Cu")
	)
	(gr_line
		(start 425.509944 -41.500044)
		(end 427.110144 -41.500044)
		(stroke
			(width 2.032)
			(type default)
		)
		(layer "In4.Cu")
	)
	(gr_arc
		(start 425.509944 -31.500064)
		(mid 425.156481 -31.646473)
		(end 425.010072 -31.999936)
		(stroke
			(width 2.032)
			(type default)
		)
		(layer "In4.Cu")
	)
	(gr_line
		(start 425.61002 -50.390044)
		(end 381.990092 -50.390044)
		(stroke
			(width 2.032)
			(type default)
		)
		(layer "In4.Cu")
	)
	(gr_arc
		(start 425.61002 -50.390044)
		(mid 427.024235 -49.804255)
		(end 427.610016 -48.390048)
		(stroke
			(width 2.032)
			(type default)
		)
		(layer "In4.Cu")
	)
	(gr_line
		(start 426.82033 -1.905)
		(end 426.82033 -1.905254)
		(stroke
			(width 5.588)
			(type default)
		)
		(layer "In4.Cu")
	)
	(gr_line
		(start 427.10989 -31.500064)
		(end 425.509944 -31.500064)
		(stroke
			(width 2.032)
			(type default)
		)
		(layer "In4.Cu")
	)
	(gr_arc
		(start 427.10989 -31.500064)
		(mid 427.463552 -31.353586)
		(end 427.610016 -30.999938)
		(stroke
			(width 2.032)
			(type default)
		)
		(layer "In4.Cu")
	)
	(gr_arc
		(start 427.610016 -41.999916)
		(mid 427.463615 -41.646427)
		(end 427.110144 -41.500044)
		(stroke
			(width 2.032)
			(type default)
		)
		(layer "In4.Cu")
	)
	(gr_line
		(start 427.610016 -41.999916)
		(end 427.610016 -48.390048)
		(stroke
			(width 2.032)
			(type default)
		)
		(layer "In4.Cu")
	)
	(gr_line
		(start 427.610016 -10.999978)
		(end 427.610016 -30.999938)
		(stroke
			(width 2.032)
			(type default)
		)
		(layer "In4.Cu")
	)
	(gr_arc
		(start 428.109888 -10.500106)
		(mid 427.756425 -10.646515)
		(end 427.610016 -10.999978)
		(stroke
			(width 2.032)
			(type default)
		)
		(layer "In4.Cu")
	)
	(gr_line
		(start 428.309786 -10.500106)
		(end 428.109888 -10.500106)
		(stroke
			(width 2.032)
			(type default)
		)
		(layer "In4.Cu")
	)
	(gr_arc
		(start 428.309786 -10.500106)
		(mid 428.66343 -10.353626)
		(end 428.809912 -9.99998)
		(stroke
			(width 2.032)
			(type default)
		)
		(layer "In4.Cu")
	)
	(gr_arc
		(start 428.809912 -1.999996)
		(mid 428.224126 -0.585782)
		(end 426.809916 0)
		(stroke
			(width 2.032)
			(type default)
		)
		(layer "In4.Cu")
	)
	(gr_line
		(start 428.809912 -1.999996)
		(end 428.809912 -9.99998)
		(stroke
			(width 2.032)
			(type default)
		)
		(layer "In4.Cu")
	)
	(gr_poly
		(pts
			(xy 203.61402 -34.401252) (xy 203.630635 -34.400709) (xy 203.662735 -34.39211) (xy 203.691518 -34.375502)
			(xy 203.703682 -34.364168) (xy 204.921104 -33.146492) (xy 212.112606 -33.146492) (xy 212.135497 -33.146004)
			(xy 212.180539 -33.137802) (xy 212.223382 -33.121663) (xy 212.262642 -33.098111) (xy 212.297047 -33.067907)
			(xy 212.325486 -33.032029) (xy 212.347037 -32.991636) (xy 212.361004 -32.948036) (xy 212.366934 -32.90264)
			(xy 212.364636 -32.856915) (xy 212.354185 -32.812342) (xy 212.345524 -32.791146) (xy 212.331613 -32.757949)
			(xy 212.310514 -32.68913) (xy 212.297326 -32.618367) (xy 212.292217 -32.546568) (xy 212.295254 -32.474651)
			(xy 212.306397 -32.403538) (xy 212.325503 -32.334139) (xy 212.352329 -32.267343) (xy 212.386529 -32.204006)
			(xy 212.427667 -32.144939) (xy 212.475216 -32.090899) (xy 212.528566 -32.042576) (xy 212.587034 -32.000591)
			(xy 212.649871 -31.965481) (xy 212.716273 -31.937696) (xy 212.785389 -31.917591) (xy 212.856334 -31.905424)
			(xy 212.9282 -31.901351) (xy 213.000066 -31.905424) (xy 213.071011 -31.917591) (xy 213.140127 -31.937696)
			(xy 213.206529 -31.965481) (xy 213.269366 -32.000591) (xy 213.327834 -32.042576) (xy 213.381184 -32.090899)
			(xy 213.428733 -32.144939) (xy 213.469871 -32.204006) (xy 213.504071 -32.267343) (xy 213.530897 -32.334139)
			(xy 213.550003 -32.403538) (xy 213.561146 -32.474651) (xy 213.564183 -32.546568) (xy 213.559074 -32.618367)
			(xy 213.545886 -32.68913) (xy 213.524787 -32.757949) (xy 213.510876 -32.791146) (xy 213.502188 -32.812333)
			(xy 213.491736 -32.856911) (xy 213.489438 -32.902641) (xy 213.495369 -32.948042) (xy 213.509337 -32.991647)
			(xy 213.530891 -33.032044) (xy 213.559332 -33.067927) (xy 213.593742 -33.098134) (xy 213.633006 -33.121689)
			(xy 213.675854 -33.137829) (xy 213.7209 -33.146032) (xy 213.743794 -33.146492) (xy 219.732606 -33.146492)
			(xy 219.755497 -33.146004) (xy 219.800539 -33.137802) (xy 219.843382 -33.121663) (xy 219.882642 -33.098111)
			(xy 219.917047 -33.067907) (xy 219.945486 -33.032029) (xy 219.967037 -32.991636) (xy 219.981004 -32.948036)
			(xy 219.986934 -32.90264) (xy 219.984636 -32.856915) (xy 219.974185 -32.812342) (xy 219.965524 -32.791146)
			(xy 219.951613 -32.757949) (xy 219.930514 -32.68913) (xy 219.917326 -32.618367) (xy 219.912217 -32.546568)
			(xy 219.915254 -32.474651) (xy 219.926397 -32.403538) (xy 219.945503 -32.334139) (xy 219.972329 -32.267343)
			(xy 220.006529 -32.204006) (xy 220.047667 -32.144939) (xy 220.095216 -32.090899) (xy 220.148566 -32.042576)
			(xy 220.207034 -32.000591) (xy 220.269871 -31.965481) (xy 220.336273 -31.937696) (xy 220.405389 -31.917591)
			(xy 220.476334 -31.905424) (xy 220.5482 -31.901351) (xy 220.620066 -31.905424) (xy 220.691011 -31.917591)
			(xy 220.760127 -31.937696) (xy 220.826529 -31.965481) (xy 220.889366 -32.000591) (xy 220.947834 -32.042576)
			(xy 221.001184 -32.090899) (xy 221.048733 -32.144939) (xy 221.089871 -32.204006) (xy 221.124071 -32.267343)
			(xy 221.150897 -32.334139) (xy 221.170003 -32.403538) (xy 221.181146 -32.474651) (xy 221.184183 -32.546568)
			(xy 221.179074 -32.618367) (xy 221.165886 -32.68913) (xy 221.144787 -32.757949) (xy 221.130876 -32.791146)
			(xy 221.122188 -32.812333) (xy 221.111736 -32.856911) (xy 221.109438 -32.902641) (xy 221.115369 -32.948042)
			(xy 221.129337 -32.991647) (xy 221.150891 -33.032044) (xy 221.179332 -33.067927) (xy 221.213742 -33.098134)
			(xy 221.253006 -33.121689) (xy 221.295854 -33.137829) (xy 221.3409 -33.146032) (xy 221.363794 -33.146492)
			(xy 227.352606 -33.146492) (xy 227.375497 -33.146004) (xy 227.420539 -33.137802) (xy 227.463382 -33.121663)
			(xy 227.502642 -33.098111) (xy 227.537047 -33.067907) (xy 227.565486 -33.032029) (xy 227.587037 -32.991636)
			(xy 227.601004 -32.948036) (xy 227.606934 -32.90264) (xy 227.604636 -32.856915) (xy 227.594185 -32.812342)
			(xy 227.585524 -32.791146) (xy 227.571613 -32.757949) (xy 227.550514 -32.68913) (xy 227.537326 -32.618367)
			(xy 227.532217 -32.546568) (xy 227.535254 -32.474651) (xy 227.546397 -32.403538) (xy 227.565503 -32.334139)
			(xy 227.592329 -32.267343) (xy 227.626529 -32.204006) (xy 227.667667 -32.144939) (xy 227.715216 -32.090899)
			(xy 227.768566 -32.042576) (xy 227.827034 -32.000591) (xy 227.889871 -31.965481) (xy 227.956273 -31.937696)
			(xy 228.025389 -31.917591) (xy 228.096334 -31.905424) (xy 228.1682 -31.901351) (xy 228.240066 -31.905424)
			(xy 228.311011 -31.917591) (xy 228.380127 -31.937696) (xy 228.446529 -31.965481) (xy 228.509366 -32.000591)
			(xy 228.567834 -32.042576) (xy 228.621184 -32.090899) (xy 228.668733 -32.144939) (xy 228.709871 -32.204006)
			(xy 228.744071 -32.267343) (xy 228.770897 -32.334139) (xy 228.790003 -32.403538) (xy 228.801146 -32.474651)
			(xy 228.804183 -32.546568) (xy 228.799074 -32.618367) (xy 228.785886 -32.68913) (xy 228.764787 -32.757949)
			(xy 228.750876 -32.791146) (xy 228.742188 -32.812333) (xy 228.731736 -32.856911) (xy 228.729438 -32.902641)
			(xy 228.735369 -32.948042) (xy 228.749337 -32.991647) (xy 228.770891 -33.032044) (xy 228.799332 -33.067927)
			(xy 228.833742 -33.098134) (xy 228.873006 -33.121689) (xy 228.915854 -33.137829) (xy 228.9609 -33.146032)
			(xy 228.983794 -33.146492) (xy 234.972606 -33.146492) (xy 234.995497 -33.146004) (xy 235.040539 -33.137802)
			(xy 235.083382 -33.121663) (xy 235.122642 -33.098111) (xy 235.157047 -33.067907) (xy 235.185486 -33.032029)
			(xy 235.207037 -32.991636) (xy 235.221004 -32.948036) (xy 235.226934 -32.90264) (xy 235.224636 -32.856915)
			(xy 235.214185 -32.812342) (xy 235.205524 -32.791146) (xy 235.191613 -32.757949) (xy 235.170514 -32.68913)
			(xy 235.157326 -32.618367) (xy 235.152217 -32.546568) (xy 235.155254 -32.474651) (xy 235.166397 -32.403538)
			(xy 235.185503 -32.334139) (xy 235.212329 -32.267343) (xy 235.246529 -32.204006) (xy 235.287667 -32.144939)
			(xy 235.335216 -32.090899) (xy 235.388566 -32.042576) (xy 235.447034 -32.000591) (xy 235.509871 -31.965481)
			(xy 235.576273 -31.937696) (xy 235.645389 -31.917591) (xy 235.716334 -31.905424) (xy 235.7882 -31.901351)
			(xy 235.860066 -31.905424) (xy 235.931011 -31.917591) (xy 236.000127 -31.937696) (xy 236.066529 -31.965481)
			(xy 236.129366 -32.000591) (xy 236.187834 -32.042576) (xy 236.241184 -32.090899) (xy 236.288733 -32.144939)
			(xy 236.329871 -32.204006) (xy 236.364071 -32.267343) (xy 236.390897 -32.334139) (xy 236.410003 -32.403538)
			(xy 236.421146 -32.474651) (xy 236.424183 -32.546568) (xy 236.419074 -32.618367) (xy 236.405886 -32.68913)
			(xy 236.384787 -32.757949) (xy 236.370876 -32.791146) (xy 236.362188 -32.812333) (xy 236.351736 -32.856911)
			(xy 236.349438 -32.902641) (xy 236.355369 -32.948042) (xy 236.369337 -32.991647) (xy 236.390891 -33.032044)
			(xy 236.419332 -33.067927) (xy 236.453742 -33.098134) (xy 236.493006 -33.121689) (xy 236.535854 -33.137829)
			(xy 236.5809 -33.146032) (xy 236.603794 -33.146492) (xy 242.592606 -33.146492) (xy 242.615497 -33.146004)
			(xy 242.660539 -33.137802) (xy 242.703382 -33.121663) (xy 242.742642 -33.098111) (xy 242.777047 -33.067907)
			(xy 242.805486 -33.032029) (xy 242.827037 -32.991636) (xy 242.841004 -32.948036) (xy 242.846934 -32.90264)
			(xy 242.844636 -32.856915) (xy 242.834185 -32.812342) (xy 242.825524 -32.791146) (xy 242.811613 -32.757949)
			(xy 242.790514 -32.68913) (xy 242.777326 -32.618367) (xy 242.772217 -32.546568) (xy 242.775254 -32.474651)
			(xy 242.786397 -32.403538) (xy 242.805503 -32.334139) (xy 242.832329 -32.267343) (xy 242.866529 -32.204006)
			(xy 242.907667 -32.144939) (xy 242.955216 -32.090899) (xy 243.008566 -32.042576) (xy 243.067034 -32.000591)
			(xy 243.129871 -31.965481) (xy 243.196273 -31.937696) (xy 243.265389 -31.917591) (xy 243.336334 -31.905424)
			(xy 243.4082 -31.901351) (xy 243.480066 -31.905424) (xy 243.551011 -31.917591) (xy 243.620127 -31.937696)
			(xy 243.686529 -31.965481) (xy 243.749366 -32.000591) (xy 243.807834 -32.042576) (xy 243.861184 -32.090899)
			(xy 243.908733 -32.144939) (xy 243.949871 -32.204006) (xy 243.984071 -32.267343) (xy 244.010897 -32.334139)
			(xy 244.030003 -32.403538) (xy 244.041146 -32.474651) (xy 244.044183 -32.546568) (xy 244.039074 -32.618367)
			(xy 244.025886 -32.68913) (xy 244.004787 -32.757949) (xy 243.990876 -32.791146) (xy 243.982188 -32.812333)
			(xy 243.971736 -32.856911) (xy 243.969438 -32.902641) (xy 243.975369 -32.948042) (xy 243.989337 -32.991647)
			(xy 244.010891 -33.032044) (xy 244.039332 -33.067927) (xy 244.073742 -33.098134) (xy 244.113006 -33.121689)
			(xy 244.155854 -33.137829) (xy 244.2009 -33.146032) (xy 244.223794 -33.146492) (xy 250.212606 -33.146492)
			(xy 250.235497 -33.146004) (xy 250.280539 -33.137802) (xy 250.323382 -33.121663) (xy 250.362642 -33.098111)
			(xy 250.397047 -33.067907) (xy 250.425486 -33.032029) (xy 250.447037 -32.991636) (xy 250.461004 -32.948036)
			(xy 250.466934 -32.90264) (xy 250.464636 -32.856915) (xy 250.454185 -32.812342) (xy 250.445524 -32.791146)
			(xy 250.431613 -32.757949) (xy 250.410514 -32.68913) (xy 250.397326 -32.618367) (xy 250.392217 -32.546568)
			(xy 250.395254 -32.474651) (xy 250.406397 -32.403538) (xy 250.425503 -32.334139) (xy 250.452329 -32.267343)
			(xy 250.486529 -32.204006) (xy 250.527667 -32.144939) (xy 250.575216 -32.090899) (xy 250.628566 -32.042576)
			(xy 250.687034 -32.000591) (xy 250.749871 -31.965481) (xy 250.816273 -31.937696) (xy 250.885389 -31.917591)
			(xy 250.956334 -31.905424) (xy 251.0282 -31.901351) (xy 251.100066 -31.905424) (xy 251.171011 -31.917591)
			(xy 251.240127 -31.937696) (xy 251.306529 -31.965481) (xy 251.369366 -32.000591) (xy 251.427834 -32.042576)
			(xy 251.481184 -32.090899) (xy 251.528733 -32.144939) (xy 251.569871 -32.204006) (xy 251.604071 -32.267343)
			(xy 251.630897 -32.334139) (xy 251.650003 -32.403538) (xy 251.661146 -32.474651) (xy 251.664183 -32.546568)
			(xy 251.659074 -32.618367) (xy 251.645886 -32.68913) (xy 251.624787 -32.757949) (xy 251.610876 -32.791146)
			(xy 251.602188 -32.812333) (xy 251.591736 -32.856911) (xy 251.589438 -32.902641) (xy 251.595369 -32.948042)
			(xy 251.609337 -32.991647) (xy 251.630891 -33.032044) (xy 251.659332 -33.067927) (xy 251.693742 -33.098134)
			(xy 251.733006 -33.121689) (xy 251.775854 -33.137829) (xy 251.8209 -33.146032) (xy 251.843794 -33.146492)
			(xy 257.832606 -33.146492) (xy 257.855497 -33.146004) (xy 257.900539 -33.137802) (xy 257.943382 -33.121663)
			(xy 257.982642 -33.098111) (xy 258.017047 -33.067907) (xy 258.045486 -33.032029) (xy 258.067037 -32.991636)
			(xy 258.081004 -32.948036) (xy 258.086934 -32.90264) (xy 258.084636 -32.856915) (xy 258.074185 -32.812342)
			(xy 258.065524 -32.791146) (xy 258.051613 -32.757949) (xy 258.030514 -32.68913) (xy 258.017326 -32.618367)
			(xy 258.012217 -32.546568) (xy 258.015254 -32.474651) (xy 258.026397 -32.403538) (xy 258.045503 -32.334139)
			(xy 258.072329 -32.267343) (xy 258.106529 -32.204006) (xy 258.147667 -32.144939) (xy 258.195216 -32.090899)
			(xy 258.248566 -32.042576) (xy 258.307034 -32.000591) (xy 258.369871 -31.965481) (xy 258.436273 -31.937696)
			(xy 258.505389 -31.917591) (xy 258.576334 -31.905424) (xy 258.6482 -31.901351) (xy 258.720066 -31.905424)
			(xy 258.791011 -31.917591) (xy 258.860127 -31.937696) (xy 258.926529 -31.965481) (xy 258.989366 -32.000591)
			(xy 259.047834 -32.042576) (xy 259.101184 -32.090899) (xy 259.148733 -32.144939) (xy 259.189871 -32.204006)
			(xy 259.224071 -32.267343) (xy 259.250897 -32.334139) (xy 259.270003 -32.403538) (xy 259.281146 -32.474651)
			(xy 259.284183 -32.546568) (xy 259.279074 -32.618367) (xy 259.265886 -32.68913) (xy 259.244787 -32.757949)
			(xy 259.230876 -32.791146) (xy 259.222188 -32.812333) (xy 259.211736 -32.856911) (xy 259.209438 -32.902641)
			(xy 259.215369 -32.948042) (xy 259.229337 -32.991647) (xy 259.250891 -33.032044) (xy 259.279332 -33.067927)
			(xy 259.313742 -33.098134) (xy 259.353006 -33.121689) (xy 259.395854 -33.137829) (xy 259.4409 -33.146032)
			(xy 259.463794 -33.146492) (xy 265.452606 -33.146492) (xy 265.475497 -33.146004) (xy 265.520539 -33.137802)
			(xy 265.563382 -33.121663) (xy 265.602642 -33.098111) (xy 265.637047 -33.067907) (xy 265.665486 -33.032029)
			(xy 265.687037 -32.991636) (xy 265.701004 -32.948036) (xy 265.706934 -32.90264) (xy 265.704636 -32.856915)
			(xy 265.694185 -32.812342) (xy 265.685524 -32.791146) (xy 265.671613 -32.757949) (xy 265.650514 -32.68913)
			(xy 265.637326 -32.618367) (xy 265.632217 -32.546568) (xy 265.635254 -32.474651) (xy 265.646397 -32.403538)
			(xy 265.665503 -32.334139) (xy 265.692329 -32.267343) (xy 265.726529 -32.204006) (xy 265.767667 -32.144939)
			(xy 265.815216 -32.090899) (xy 265.868566 -32.042576) (xy 265.927034 -32.000591) (xy 265.989871 -31.965481)
			(xy 266.056273 -31.937696) (xy 266.125389 -31.917591) (xy 266.196334 -31.905424) (xy 266.2682 -31.901351)
			(xy 266.340066 -31.905424) (xy 266.411011 -31.917591) (xy 266.480127 -31.937696) (xy 266.546529 -31.965481)
			(xy 266.609366 -32.000591) (xy 266.667834 -32.042576) (xy 266.721184 -32.090899) (xy 266.768733 -32.144939)
			(xy 266.809871 -32.204006) (xy 266.844071 -32.267343) (xy 266.870897 -32.334139) (xy 266.890003 -32.403538)
			(xy 266.901146 -32.474651) (xy 266.904183 -32.546568) (xy 266.899074 -32.618367) (xy 266.885886 -32.68913)
			(xy 266.864787 -32.757949) (xy 266.850876 -32.791146) (xy 266.842188 -32.812333) (xy 266.831736 -32.856911)
			(xy 266.829438 -32.902641) (xy 266.835369 -32.948042) (xy 266.849337 -32.991647) (xy 266.870891 -33.032044)
			(xy 266.899332 -33.067927) (xy 266.933742 -33.098134) (xy 266.973006 -33.121689) (xy 267.015854 -33.137829)
			(xy 267.0609 -33.146032) (xy 267.083794 -33.146492) (xy 273.072606 -33.146492) (xy 273.095497 -33.146004)
			(xy 273.140539 -33.137802) (xy 273.183382 -33.121663) (xy 273.222642 -33.098111) (xy 273.257047 -33.067907)
			(xy 273.285486 -33.032029) (xy 273.307037 -32.991636) (xy 273.321004 -32.948036) (xy 273.326934 -32.90264)
			(xy 273.324636 -32.856915) (xy 273.314185 -32.812342) (xy 273.305524 -32.791146) (xy 273.291613 -32.757949)
			(xy 273.270514 -32.68913) (xy 273.257326 -32.618367) (xy 273.252217 -32.546568) (xy 273.255254 -32.474651)
			(xy 273.266397 -32.403538) (xy 273.285503 -32.334139) (xy 273.312329 -32.267343) (xy 273.346529 -32.204006)
			(xy 273.387667 -32.144939) (xy 273.435216 -32.090899) (xy 273.488566 -32.042576) (xy 273.547034 -32.000591)
			(xy 273.609871 -31.965481) (xy 273.676273 -31.937696) (xy 273.745389 -31.917591) (xy 273.816334 -31.905424)
			(xy 273.8882 -31.901351) (xy 273.960066 -31.905424) (xy 274.031011 -31.917591) (xy 274.100127 -31.937696)
			(xy 274.166529 -31.965481) (xy 274.229366 -32.000591) (xy 274.287834 -32.042576) (xy 274.341184 -32.090899)
			(xy 274.388733 -32.144939) (xy 274.429871 -32.204006) (xy 274.464071 -32.267343) (xy 274.490897 -32.334139)
			(xy 274.510003 -32.403538) (xy 274.521146 -32.474651) (xy 274.524183 -32.546568) (xy 274.519074 -32.618367)
			(xy 274.505886 -32.68913) (xy 274.484787 -32.757949) (xy 274.470876 -32.791146) (xy 274.462188 -32.812333)
			(xy 274.451736 -32.856911) (xy 274.449438 -32.902641) (xy 274.455369 -32.948042) (xy 274.469337 -32.991647)
			(xy 274.490891 -33.032044) (xy 274.519332 -33.067927) (xy 274.553742 -33.098134) (xy 274.593006 -33.121689)
			(xy 274.635854 -33.137829) (xy 274.6809 -33.146032) (xy 274.703794 -33.146492) (xy 280.692606 -33.146492)
			(xy 280.715497 -33.146004) (xy 280.760539 -33.137802) (xy 280.803382 -33.121663) (xy 280.842642 -33.098111)
			(xy 280.877047 -33.067907) (xy 280.905486 -33.032029) (xy 280.927037 -32.991636) (xy 280.941004 -32.948036)
			(xy 280.946934 -32.90264) (xy 280.944636 -32.856915) (xy 280.934185 -32.812342) (xy 280.925524 -32.791146)
			(xy 280.911613 -32.757949) (xy 280.890514 -32.68913) (xy 280.877326 -32.618367) (xy 280.872217 -32.546568)
			(xy 280.875254 -32.474651) (xy 280.886397 -32.403538) (xy 280.905503 -32.334139) (xy 280.932329 -32.267343)
			(xy 280.966529 -32.204006) (xy 281.007667 -32.144939) (xy 281.055216 -32.090899) (xy 281.108566 -32.042576)
			(xy 281.167034 -32.000591) (xy 281.229871 -31.965481) (xy 281.296273 -31.937696) (xy 281.365389 -31.917591)
			(xy 281.436334 -31.905424) (xy 281.5082 -31.901351) (xy 281.580066 -31.905424) (xy 281.651011 -31.917591)
			(xy 281.720127 -31.937696) (xy 281.786529 -31.965481) (xy 281.849366 -32.000591) (xy 281.907834 -32.042576)
			(xy 281.961184 -32.090899) (xy 282.008733 -32.144939) (xy 282.049871 -32.204006) (xy 282.084071 -32.267343)
			(xy 282.110897 -32.334139) (xy 282.130003 -32.403538) (xy 282.141146 -32.474651) (xy 282.144183 -32.546568)
			(xy 282.139074 -32.618367) (xy 282.125886 -32.68913) (xy 282.104787 -32.757949) (xy 282.090876 -32.791146)
			(xy 282.082188 -32.812333) (xy 282.071736 -32.856911) (xy 282.069438 -32.902641) (xy 282.075369 -32.948042)
			(xy 282.089337 -32.991647) (xy 282.110891 -33.032044) (xy 282.139332 -33.067927) (xy 282.173742 -33.098134)
			(xy 282.213006 -33.121689) (xy 282.255854 -33.137829) (xy 282.3009 -33.146032) (xy 282.323794 -33.146492)
			(xy 306.4002 -33.146492) (xy 306.416854 -33.145997) (xy 306.449028 -33.137376) (xy 306.477874 -33.120721)
			(xy 306.501426 -33.097168) (xy 306.518079 -33.068321) (xy 306.526698 -33.036146) (xy 306.5272 -33.019492)
			(xy 306.5272 -27.0256) (xy 310.0324 -23.5204) (xy 314.5028 -23.5204) (xy 316.4713 -21.5519) (xy 316.4713 -3.3147)
			(xy 314.9346 -1.778) (xy 204.9018 -1.778) (xy 203.3016 -3.3782) (xy 203.3016 -3.921861) (xy 269.544792 -3.921861)
			(xy 269.544792 -3.850539) (xy 269.552778 -3.779665) (xy 269.568648 -3.71013) (xy 269.592205 -3.64281)
			(xy 269.62315 -3.578551) (xy 269.661096 -3.51816) (xy 269.705565 -3.462398) (xy 269.755998 -3.411965)
			(xy 269.81176 -3.367496) (xy 269.872151 -3.32955) (xy 269.93641 -3.298605) (xy 270.00373 -3.275048)
			(xy 270.073265 -3.259178) (xy 270.144139 -3.251192) (xy 270.215461 -3.251192) (xy 270.286335 -3.259178)
			(xy 270.35587 -3.275048) (xy 270.42319 -3.298605) (xy 270.487449 -3.32955) (xy 270.54784 -3.367496)
			(xy 270.603602 -3.411965) (xy 270.654035 -3.462398) (xy 270.698504 -3.51816) (xy 270.73645 -3.578551)
			(xy 270.767395 -3.64281) (xy 270.790952 -3.71013) (xy 270.806822 -3.779665) (xy 270.814808 -3.850539)
			(xy 270.815308 -3.8862) (xy 270.814808 -3.921861) (xy 270.806822 -3.992735) (xy 270.790952 -4.06227)
			(xy 270.767395 -4.12959) (xy 270.73645 -4.193849) (xy 270.698504 -4.25424) (xy 270.654035 -4.310002)
			(xy 270.603602 -4.360435) (xy 270.54784 -4.404904) (xy 270.487449 -4.44285) (xy 270.42319 -4.473795)
			(xy 270.35587 -4.497352) (xy 270.286335 -4.513222) (xy 270.215461 -4.521208) (xy 270.144139 -4.521208)
			(xy 270.073265 -4.513222) (xy 270.00373 -4.497352) (xy 269.93641 -4.473795) (xy 269.872151 -4.44285)
			(xy 269.81176 -4.404904) (xy 269.755998 -4.360435) (xy 269.705565 -4.310002) (xy 269.661096 -4.25424)
			(xy 269.62315 -4.193849) (xy 269.592205 -4.12959) (xy 269.568648 -4.06227) (xy 269.552778 -3.992735)
			(xy 269.544792 -3.921861) (xy 203.3016 -3.921861) (xy 203.3016 -4.607661) (xy 242.950992 -4.607661)
			(xy 242.950992 -4.536339) (xy 242.958978 -4.465465) (xy 242.974848 -4.39593) (xy 242.998405 -4.32861)
			(xy 243.02935 -4.264351) (xy 243.067296 -4.20396) (xy 243.111765 -4.148198) (xy 243.162198 -4.097765)
			(xy 243.21796 -4.053296) (xy 243.278351 -4.01535) (xy 243.34261 -3.984405) (xy 243.40993 -3.960848)
			(xy 243.479465 -3.944978) (xy 243.550339 -3.936992) (xy 243.621661 -3.936992) (xy 243.692535 -3.944978)
			(xy 243.76207 -3.960848) (xy 243.82939 -3.984405) (xy 243.893649 -4.01535) (xy 243.95404 -4.053296)
			(xy 244.009802 -4.097765) (xy 244.060235 -4.148198) (xy 244.104704 -4.20396) (xy 244.14265 -4.264351)
			(xy 244.173595 -4.32861) (xy 244.197152 -4.39593) (xy 244.213022 -4.465465) (xy 244.221008 -4.536339)
			(xy 244.221508 -4.572) (xy 244.221008 -4.607661) (xy 244.213022 -4.678535) (xy 244.197152 -4.74807)
			(xy 244.173595 -4.81539) (xy 244.14265 -4.879649) (xy 244.104704 -4.94004) (xy 244.060235 -4.995802)
			(xy 244.009802 -5.046235) (xy 243.95404 -5.090704) (xy 243.893649 -5.12865) (xy 243.82939 -5.159595)
			(xy 243.76207 -5.183152) (xy 243.692535 -5.199022) (xy 243.621661 -5.207008) (xy 243.550339 -5.207008)
			(xy 243.479465 -5.199022) (xy 243.40993 -5.183152) (xy 243.34261 -5.159595) (xy 243.278351 -5.12865)
			(xy 243.21796 -5.090704) (xy 243.162198 -5.046235) (xy 243.111765 -4.995802) (xy 243.067296 -4.94004)
			(xy 243.02935 -4.879649) (xy 242.998405 -4.81539) (xy 242.974848 -4.74807) (xy 242.958978 -4.678535)
			(xy 242.950992 -4.607661) (xy 203.3016 -4.607661) (xy 203.3016 -11.186261) (xy 206.044792 -11.186261)
			(xy 206.044792 -11.114939) (xy 206.052778 -11.044065) (xy 206.068648 -10.97453) (xy 206.092205 -10.90721)
			(xy 206.12315 -10.842951) (xy 206.161096 -10.78256) (xy 206.205565 -10.726798) (xy 206.255998 -10.676365)
			(xy 206.31176 -10.631896) (xy 206.372151 -10.59395) (xy 206.43641 -10.563005) (xy 206.50373 -10.539448)
			(xy 206.573265 -10.523578) (xy 206.644139 -10.515592) (xy 206.715461 -10.515592) (xy 206.786335 -10.523578)
			(xy 206.85587 -10.539448) (xy 206.92319 -10.563005) (xy 206.987449 -10.59395) (xy 207.04784 -10.631896)
			(xy 207.103602 -10.676365) (xy 207.154035 -10.726798) (xy 207.192829 -10.775444) (xy 276.301877 -10.775444)
			(xy 276.302267 -10.608177) (xy 276.310628 -10.441119) (xy 276.32694 -10.274649) (xy 276.351167 -10.109145)
			(xy 276.383252 -9.944984) (xy 276.423124 -9.782538) (xy 276.470691 -9.622177) (xy 276.525847 -9.464265)
			(xy 276.588464 -9.30916) (xy 276.658401 -9.157216) (xy 276.7355 -9.008776) (xy 276.819584 -8.86418)
			(xy 276.910463 -8.723754) (xy 277.007931 -8.587819) (xy 277.111766 -8.456682) (xy 277.221731 -8.330643)
			(xy 277.337578 -8.209987) (xy 277.397972 -8.15213) (xy 277.421756 -8.128827) (xy 277.463472 -8.076928)
			(xy 277.497794 -8.019869) (xy 277.524093 -7.958697) (xy 277.541887 -7.894533) (xy 277.55085 -7.828553)
			(xy 277.551388 -7.79526) (xy 277.551388 -4.700016) (xy 277.551884 -4.633065) (xy 277.559817 -4.499398)
			(xy 277.575654 -4.366435) (xy 277.59934 -4.234645) (xy 277.630791 -4.104489) (xy 277.669899 -3.976425)
			(xy 277.716523 -3.850902) (xy 277.770503 -3.728362) (xy 277.831646 -3.609235) (xy 277.89974 -3.493939)
			(xy 277.974544 -3.38288) (xy 278.055796 -3.276447) (xy 278.14321 -3.175015) (xy 278.23648 -3.078939)
			(xy 278.335277 -2.988557) (xy 278.439256 -2.904187) (xy 278.548049 -2.826125) (xy 278.661276 -2.754645)
			(xy 278.778539 -2.689998) (xy 278.899426 -2.632411) (xy 279.023512 -2.582087) (xy 279.150361 -2.539202)
			(xy 279.279528 -2.503907) (xy 279.410559 -2.476326) (xy 279.542993 -2.456556) (xy 279.676367 -2.444666)
			(xy 279.81021 -2.440698) (xy 279.944053 -2.444666) (xy 280.077427 -2.456556) (xy 280.209861 -2.476326)
			(xy 280.340892 -2.503907) (xy 280.470059 -2.539202) (xy 280.596908 -2.582087) (xy 280.720994 -2.632411)
			(xy 280.841881 -2.689998) (xy 280.959144 -2.754645) (xy 281.072371 -2.826125) (xy 281.181164 -2.904187)
			(xy 281.285143 -2.988557) (xy 281.297367 -2.99974) (xy 311.607711 -2.99974) (xy 311.611746 -2.924036)
			(xy 311.623805 -2.849191) (xy 311.643751 -2.77605) (xy 311.671358 -2.705445) (xy 311.706314 -2.638174)
			(xy 311.748222 -2.574999) (xy 311.796608 -2.516637) (xy 311.850924 -2.463749) (xy 311.910553 -2.416934)
			(xy 311.974821 -2.376722) (xy 312.042998 -2.34357) (xy 312.114314 -2.317852) (xy 312.187959 -2.29986)
			(xy 312.263099 -2.289798) (xy 312.338883 -2.287779) (xy 312.414453 -2.293828) (xy 312.488951 -2.307875)
			(xy 312.561534 -2.329761) (xy 312.63138 -2.359238) (xy 312.697697 -2.395973) (xy 312.759733 -2.439548)
			(xy 312.816786 -2.48947) (xy 312.86821 -2.545174) (xy 312.913421 -2.606029) (xy 312.951908 -2.671344)
			(xy 312.983234 -2.74038) (xy 313.007044 -2.812355) (xy 313.023069 -2.886453) (xy 313.031128 -2.961834)
			(xy 313.031632 -2.99974) (xy 313.607707 -2.99974) (xy 313.611742 -2.924036) (xy 313.623801 -2.849191)
			(xy 313.643747 -2.77605) (xy 313.671354 -2.705445) (xy 313.70631 -2.638174) (xy 313.748218 -2.574999)
			(xy 313.796604 -2.516637) (xy 313.85092 -2.463749) (xy 313.910549 -2.416934) (xy 313.974817 -2.376722)
			(xy 314.042994 -2.34357) (xy 314.11431 -2.317852) (xy 314.187955 -2.29986) (xy 314.263095 -2.289798)
			(xy 314.338879 -2.287779) (xy 314.414449 -2.293828) (xy 314.488947 -2.307875) (xy 314.56153 -2.329761)
			(xy 314.631376 -2.359238) (xy 314.697693 -2.395973) (xy 314.759729 -2.439548) (xy 314.816782 -2.48947)
			(xy 314.868206 -2.545174) (xy 314.913417 -2.606029) (xy 314.951904 -2.671344) (xy 314.98323 -2.74038)
			(xy 315.00704 -2.812355) (xy 315.023065 -2.886453) (xy 315.031124 -2.961834) (xy 315.031628 -2.99974)
			(xy 315.031124 -3.037646) (xy 315.023065 -3.113027) (xy 315.00704 -3.187125) (xy 314.98323 -3.2591)
			(xy 314.951904 -3.328136) (xy 314.913417 -3.393451) (xy 314.868206 -3.454306) (xy 314.816782 -3.51001)
			(xy 314.759729 -3.559932) (xy 314.697693 -3.603507) (xy 314.631376 -3.640242) (xy 314.56153 -3.669719)
			(xy 314.488947 -3.691605) (xy 314.414449 -3.705652) (xy 314.338879 -3.711701) (xy 314.263095 -3.709682)
			(xy 314.187955 -3.69962) (xy 314.11431 -3.681628) (xy 314.042994 -3.65591) (xy 313.974817 -3.622758)
			(xy 313.910549 -3.582546) (xy 313.85092 -3.535731) (xy 313.796604 -3.482843) (xy 313.748218 -3.424481)
			(xy 313.70631 -3.361306) (xy 313.671354 -3.294035) (xy 313.643747 -3.22343) (xy 313.623801 -3.150289)
			(xy 313.611742 -3.075444) (xy 313.607707 -2.99974) (xy 313.031632 -2.99974) (xy 313.031128 -3.037646)
			(xy 313.023069 -3.113027) (xy 313.007044 -3.187125) (xy 312.983234 -3.2591) (xy 312.951908 -3.328136)
			(xy 312.913421 -3.393451) (xy 312.86821 -3.454306) (xy 312.816786 -3.51001) (xy 312.759733 -3.559932)
			(xy 312.697697 -3.603507) (xy 312.63138 -3.640242) (xy 312.561534 -3.669719) (xy 312.488951 -3.691605)
			(xy 312.414453 -3.705652) (xy 312.338883 -3.711701) (xy 312.263099 -3.709682) (xy 312.187959 -3.69962)
			(xy 312.114314 -3.681628) (xy 312.042998 -3.65591) (xy 311.974821 -3.622758) (xy 311.910553 -3.582546)
			(xy 311.850924 -3.535731) (xy 311.796608 -3.482843) (xy 311.748222 -3.424481) (xy 311.706314 -3.361306)
			(xy 311.671358 -3.294035) (xy 311.643751 -3.22343) (xy 311.623805 -3.150289) (xy 311.611746 -3.075444)
			(xy 311.607711 -2.99974) (xy 281.297367 -2.99974) (xy 281.38394 -3.078939) (xy 281.47721 -3.175015)
			(xy 281.564624 -3.276447) (xy 281.645876 -3.38288) (xy 281.72068 -3.493939) (xy 281.788774 -3.609235)
			(xy 281.849917 -3.728362) (xy 281.903897 -3.850902) (xy 281.950521 -3.976425) (xy 281.989629 -4.104489)
			(xy 282.02108 -4.234645) (xy 282.044766 -4.366435) (xy 282.060603 -4.499398) (xy 282.068536 -4.633065)
			(xy 282.069032 -4.700016) (xy 282.069032 -4.999736) (xy 311.607711 -4.999736) (xy 311.611746 -4.924032)
			(xy 311.623805 -4.849187) (xy 311.643751 -4.776046) (xy 311.671358 -4.705441) (xy 311.706314 -4.63817)
			(xy 311.748222 -4.574995) (xy 311.796608 -4.516633) (xy 311.850924 -4.463745) (xy 311.910553 -4.41693)
			(xy 311.974821 -4.376718) (xy 312.042998 -4.343566) (xy 312.114314 -4.317848) (xy 312.187959 -4.299856)
			(xy 312.263099 -4.289794) (xy 312.338883 -4.287775) (xy 312.414453 -4.293824) (xy 312.488951 -4.307871)
			(xy 312.561534 -4.329757) (xy 312.63138 -4.359234) (xy 312.697697 -4.395969) (xy 312.759733 -4.439544)
			(xy 312.816786 -4.489466) (xy 312.86821 -4.54517) (xy 312.913421 -4.606025) (xy 312.951908 -4.67134)
			(xy 312.983234 -4.740376) (xy 313.007044 -4.812351) (xy 313.023069 -4.886449) (xy 313.031128 -4.96183)
			(xy 313.031632 -4.999736) (xy 313.607707 -4.999736) (xy 313.611742 -4.924032) (xy 313.623801 -4.849187)
			(xy 313.643747 -4.776046) (xy 313.671354 -4.705441) (xy 313.70631 -4.63817) (xy 313.748218 -4.574995)
			(xy 313.796604 -4.516633) (xy 313.85092 -4.463745) (xy 313.910549 -4.41693) (xy 313.974817 -4.376718)
			(xy 314.042994 -4.343566) (xy 314.11431 -4.317848) (xy 314.187955 -4.299856) (xy 314.263095 -4.289794)
			(xy 314.338879 -4.287775) (xy 314.414449 -4.293824) (xy 314.488947 -4.307871) (xy 314.56153 -4.329757)
			(xy 314.631376 -4.359234) (xy 314.697693 -4.395969) (xy 314.759729 -4.439544) (xy 314.816782 -4.489466)
			(xy 314.868206 -4.54517) (xy 314.913417 -4.606025) (xy 314.951904 -4.67134) (xy 314.98323 -4.740376)
			(xy 315.00704 -4.812351) (xy 315.023065 -4.886449) (xy 315.031124 -4.96183) (xy 315.031628 -4.999736)
			(xy 315.031124 -5.037642) (xy 315.023065 -5.113023) (xy 315.00704 -5.187121) (xy 314.98323 -5.259096)
			(xy 314.951904 -5.328132) (xy 314.913417 -5.393447) (xy 314.868206 -5.454302) (xy 314.816782 -5.510006)
			(xy 314.759729 -5.559928) (xy 314.697693 -5.603503) (xy 314.631376 -5.640238) (xy 314.56153 -5.669715)
			(xy 314.488947 -5.691601) (xy 314.414449 -5.705648) (xy 314.338879 -5.711697) (xy 314.263095 -5.709678)
			(xy 314.187955 -5.699616) (xy 314.11431 -5.681624) (xy 314.042994 -5.655906) (xy 313.974817 -5.622754)
			(xy 313.910549 -5.582542) (xy 313.85092 -5.535727) (xy 313.796604 -5.482839) (xy 313.748218 -5.424477)
			(xy 313.70631 -5.361302) (xy 313.671354 -5.294031) (xy 313.643747 -5.223426) (xy 313.623801 -5.150285)
			(xy 313.611742 -5.07544) (xy 313.607707 -4.999736) (xy 313.031632 -4.999736) (xy 313.031128 -5.037642)
			(xy 313.023069 -5.113023) (xy 313.007044 -5.187121) (xy 312.983234 -5.259096) (xy 312.951908 -5.328132)
			(xy 312.913421 -5.393447) (xy 312.86821 -5.454302) (xy 312.816786 -5.510006) (xy 312.759733 -5.559928)
			(xy 312.697697 -5.603503) (xy 312.63138 -5.640238) (xy 312.561534 -5.669715) (xy 312.488951 -5.691601)
			(xy 312.414453 -5.705648) (xy 312.338883 -5.711697) (xy 312.263099 -5.709678) (xy 312.187959 -5.699616)
			(xy 312.114314 -5.681624) (xy 312.042998 -5.655906) (xy 311.974821 -5.622754) (xy 311.910553 -5.582542)
			(xy 311.850924 -5.535727) (xy 311.796608 -5.482839) (xy 311.748222 -5.424477) (xy 311.706314 -5.361302)
			(xy 311.671358 -5.294031) (xy 311.643751 -5.223426) (xy 311.623805 -5.150285) (xy 311.611746 -5.07544)
			(xy 311.607711 -4.999736) (xy 282.069032 -4.999736) (xy 282.069032 -6.999732) (xy 311.607711 -6.999732)
			(xy 311.611746 -6.924028) (xy 311.623805 -6.849183) (xy 311.643751 -6.776042) (xy 311.671358 -6.705437)
			(xy 311.706314 -6.638166) (xy 311.748222 -6.574991) (xy 311.796608 -6.516629) (xy 311.850924 -6.463741)
			(xy 311.910553 -6.416926) (xy 311.974821 -6.376714) (xy 312.042998 -6.343562) (xy 312.114314 -6.317844)
			(xy 312.187959 -6.299852) (xy 312.263099 -6.28979) (xy 312.338883 -6.287771) (xy 312.414453 -6.29382)
			(xy 312.488951 -6.307867) (xy 312.561534 -6.329753) (xy 312.63138 -6.35923) (xy 312.697697 -6.395965)
			(xy 312.759733 -6.43954) (xy 312.816786 -6.489462) (xy 312.86821 -6.545166) (xy 312.913421 -6.606021)
			(xy 312.951908 -6.671336) (xy 312.983234 -6.740372) (xy 313.007044 -6.812347) (xy 313.023069 -6.886445)
			(xy 313.031128 -6.961826) (xy 313.031632 -6.999732) (xy 313.607707 -6.999732) (xy 313.611742 -6.924028)
			(xy 313.623801 -6.849183) (xy 313.643747 -6.776042) (xy 313.671354 -6.705437) (xy 313.70631 -6.638166)
			(xy 313.748218 -6.574991) (xy 313.796604 -6.516629) (xy 313.85092 -6.463741) (xy 313.910549 -6.416926)
			(xy 313.974817 -6.376714) (xy 314.042994 -6.343562) (xy 314.11431 -6.317844) (xy 314.187955 -6.299852)
			(xy 314.263095 -6.28979) (xy 314.338879 -6.287771) (xy 314.414449 -6.29382) (xy 314.488947 -6.307867)
			(xy 314.56153 -6.329753) (xy 314.631376 -6.35923) (xy 314.697693 -6.395965) (xy 314.759729 -6.43954)
			(xy 314.816782 -6.489462) (xy 314.868206 -6.545166) (xy 314.913417 -6.606021) (xy 314.951904 -6.671336)
			(xy 314.98323 -6.740372) (xy 315.00704 -6.812347) (xy 315.023065 -6.886445) (xy 315.031124 -6.961826)
			(xy 315.031628 -6.999732) (xy 315.031124 -7.037638) (xy 315.023065 -7.113019) (xy 315.00704 -7.187117)
			(xy 314.98323 -7.259092) (xy 314.951904 -7.328128) (xy 314.913417 -7.393443) (xy 314.868206 -7.454298)
			(xy 314.816782 -7.510002) (xy 314.759729 -7.559924) (xy 314.697693 -7.603499) (xy 314.631376 -7.640234)
			(xy 314.56153 -7.669711) (xy 314.488947 -7.691597) (xy 314.414449 -7.705644) (xy 314.338879 -7.711693)
			(xy 314.263095 -7.709674) (xy 314.187955 -7.699612) (xy 314.11431 -7.68162) (xy 314.042994 -7.655902)
			(xy 313.974817 -7.62275) (xy 313.910549 -7.582538) (xy 313.85092 -7.535723) (xy 313.796604 -7.482835)
			(xy 313.748218 -7.424473) (xy 313.70631 -7.361298) (xy 313.671354 -7.294027) (xy 313.643747 -7.223422)
			(xy 313.623801 -7.150281) (xy 313.611742 -7.075436) (xy 313.607707 -6.999732) (xy 313.031632 -6.999732)
			(xy 313.031128 -7.037638) (xy 313.023069 -7.113019) (xy 313.007044 -7.187117) (xy 312.983234 -7.259092)
			(xy 312.951908 -7.328128) (xy 312.913421 -7.393443) (xy 312.86821 -7.454298) (xy 312.816786 -7.510002)
			(xy 312.759733 -7.559924) (xy 312.697697 -7.603499) (xy 312.63138 -7.640234) (xy 312.561534 -7.669711)
			(xy 312.488951 -7.691597) (xy 312.414453 -7.705644) (xy 312.338883 -7.711693) (xy 312.263099 -7.709674)
			(xy 312.187959 -7.699612) (xy 312.114314 -7.68162) (xy 312.042998 -7.655902) (xy 311.974821 -7.62275)
			(xy 311.910553 -7.582538) (xy 311.850924 -7.535723) (xy 311.796608 -7.482835) (xy 311.748222 -7.424473)
			(xy 311.706314 -7.361298) (xy 311.671358 -7.294027) (xy 311.643751 -7.223422) (xy 311.623805 -7.150281)
			(xy 311.611746 -7.075436) (xy 311.607711 -6.999732) (xy 282.069032 -6.999732) (xy 282.069032 -7.79526)
			(xy 282.069585 -7.828553) (xy 282.078547 -7.894532) (xy 282.096338 -7.958696) (xy 282.122633 -8.019869)
			(xy 282.15695 -8.076929) (xy 282.19866 -8.128831) (xy 282.222448 -8.15213) (xy 282.282842 -8.209987)
			(xy 282.398689 -8.330643) (xy 282.508654 -8.456682) (xy 282.612489 -8.587819) (xy 282.709957 -8.723754)
			(xy 282.800836 -8.86418) (xy 282.88492 -9.008776) (xy 282.962019 -9.157216) (xy 283.031956 -9.30916)
			(xy 283.094573 -9.464265) (xy 283.125883 -9.553905) (xy 308.834016 -9.553905) (xy 308.834016 -9.445295)
			(xy 308.841944 -9.336976) (xy 308.857758 -9.229523) (xy 308.881373 -9.123512) (xy 308.912663 -9.019508)
			(xy 308.951462 -8.918065) (xy 308.997562 -8.819725) (xy 309.050717 -8.725012) (xy 309.110644 -8.634432)
			(xy 309.177023 -8.548468) (xy 309.249501 -8.467578) (xy 309.327689 -8.392195) (xy 309.411171 -8.322721)
			(xy 309.499502 -8.259525) (xy 309.592211 -8.202946) (xy 309.688802 -8.153285) (xy 309.78876 -8.110808)
			(xy 309.891552 -8.07574) (xy 309.99663 -8.048269) (xy 310.103433 -8.028541) (xy 310.211391 -8.016663)
			(xy 310.319928 -8.012696) (xy 310.428465 -8.016663) (xy 310.536423 -8.028541) (xy 310.643226 -8.048269)
			(xy 310.748304 -8.07574) (xy 310.851096 -8.110808) (xy 310.951054 -8.153285) (xy 311.047645 -8.202946)
			(xy 311.140354 -8.259525) (xy 311.228685 -8.322721) (xy 311.312167 -8.392195) (xy 311.390355 -8.467578)
			(xy 311.462833 -8.548468) (xy 311.529212 -8.634432) (xy 311.589139 -8.725012) (xy 311.642294 -8.819725)
			(xy 311.688394 -8.918065) (xy 311.727193 -9.019508) (xy 311.758483 -9.123512) (xy 311.782098 -9.229523)
			(xy 311.797912 -9.336976) (xy 311.80584 -9.445295) (xy 311.806336 -9.4996) (xy 311.80584 -9.553905)
			(xy 311.797912 -9.662224) (xy 311.782098 -9.769677) (xy 311.758483 -9.875688) (xy 311.727193 -9.979692)
			(xy 311.688394 -10.081135) (xy 311.642294 -10.179475) (xy 311.589139 -10.274188) (xy 311.529212 -10.364768)
			(xy 311.462833 -10.450732) (xy 311.390355 -10.531622) (xy 311.312167 -10.607005) (xy 311.228685 -10.676479)
			(xy 311.140354 -10.739675) (xy 311.047645 -10.796254) (xy 310.951054 -10.845915) (xy 310.851096 -10.888392)
			(xy 310.748304 -10.92346) (xy 310.643226 -10.950931) (xy 310.536423 -10.970659) (xy 310.428465 -10.982537)
			(xy 310.319928 -10.986504) (xy 310.211391 -10.982537) (xy 310.103433 -10.970659) (xy 309.99663 -10.950931)
			(xy 309.891552 -10.92346) (xy 309.78876 -10.888392) (xy 309.688802 -10.845915) (xy 309.592211 -10.796254)
			(xy 309.499502 -10.739675) (xy 309.411171 -10.676479) (xy 309.327689 -10.607005) (xy 309.249501 -10.531622)
			(xy 309.177023 -10.450732) (xy 309.110644 -10.364768) (xy 309.050717 -10.274188) (xy 308.997562 -10.179475)
			(xy 308.951462 -10.081135) (xy 308.912663 -9.979692) (xy 308.881373 -9.875688) (xy 308.857758 -9.769677)
			(xy 308.841944 -9.662224) (xy 308.834016 -9.553905) (xy 283.125883 -9.553905) (xy 283.149729 -9.622177)
			(xy 283.197296 -9.782538) (xy 283.237168 -9.944984) (xy 283.269253 -10.109145) (xy 283.29348 -10.274649)
			(xy 283.309792 -10.441119) (xy 283.318153 -10.608177) (xy 283.318543 -10.775444) (xy 283.310963 -10.94254)
			(xy 283.305629 -10.999724) (xy 311.607711 -10.999724) (xy 311.611746 -10.92402) (xy 311.623805 -10.849175)
			(xy 311.643751 -10.776034) (xy 311.671358 -10.705429) (xy 311.706314 -10.638158) (xy 311.748222 -10.574983)
			(xy 311.796608 -10.516621) (xy 311.850924 -10.463733) (xy 311.910553 -10.416918) (xy 311.974821 -10.376706)
			(xy 312.042998 -10.343554) (xy 312.114314 -10.317836) (xy 312.187959 -10.299844) (xy 312.263099 -10.289782)
			(xy 312.338883 -10.287763) (xy 312.414453 -10.293812) (xy 312.488951 -10.307859) (xy 312.561534 -10.329745)
			(xy 312.63138 -10.359222) (xy 312.697697 -10.395957) (xy 312.759733 -10.439532) (xy 312.816786 -10.489454)
			(xy 312.86821 -10.545158) (xy 312.913421 -10.606013) (xy 312.951908 -10.671328) (xy 312.983234 -10.740364)
			(xy 313.007044 -10.812339) (xy 313.023069 -10.886437) (xy 313.031128 -10.961818) (xy 313.031632 -10.999724)
			(xy 313.607707 -10.999724) (xy 313.611742 -10.92402) (xy 313.623801 -10.849175) (xy 313.643747 -10.776034)
			(xy 313.671354 -10.705429) (xy 313.70631 -10.638158) (xy 313.748218 -10.574983) (xy 313.796604 -10.516621)
			(xy 313.85092 -10.463733) (xy 313.910549 -10.416918) (xy 313.974817 -10.376706) (xy 314.042994 -10.343554)
			(xy 314.11431 -10.317836) (xy 314.187955 -10.299844) (xy 314.263095 -10.289782) (xy 314.338879 -10.287763)
			(xy 314.414449 -10.293812) (xy 314.488947 -10.307859) (xy 314.56153 -10.329745) (xy 314.631376 -10.359222)
			(xy 314.697693 -10.395957) (xy 314.759729 -10.439532) (xy 314.816782 -10.489454) (xy 314.868206 -10.545158)
			(xy 314.913417 -10.606013) (xy 314.951904 -10.671328) (xy 314.98323 -10.740364) (xy 315.00704 -10.812339)
			(xy 315.023065 -10.886437) (xy 315.031124 -10.961818) (xy 315.031628 -10.999724) (xy 315.031124 -11.03763)
			(xy 315.023065 -11.113011) (xy 315.00704 -11.187109) (xy 314.98323 -11.259084) (xy 314.951904 -11.32812)
			(xy 314.913417 -11.393435) (xy 314.868206 -11.45429) (xy 314.816782 -11.509994) (xy 314.759729 -11.559916)
			(xy 314.697693 -11.603491) (xy 314.631376 -11.640226) (xy 314.56153 -11.669703) (xy 314.488947 -11.691589)
			(xy 314.414449 -11.705636) (xy 314.338879 -11.711685) (xy 314.263095 -11.709666) (xy 314.187955 -11.699604)
			(xy 314.11431 -11.681612) (xy 314.042994 -11.655894) (xy 313.974817 -11.622742) (xy 313.910549 -11.58253)
			(xy 313.85092 -11.535715) (xy 313.796604 -11.482827) (xy 313.748218 -11.424465) (xy 313.70631 -11.36129)
			(xy 313.671354 -11.294019) (xy 313.643747 -11.223414) (xy 313.623801 -11.150273) (xy 313.611742 -11.075428)
			(xy 313.607707 -10.999724) (xy 313.031632 -10.999724) (xy 313.031128 -11.03763) (xy 313.023069 -11.113011)
			(xy 313.007044 -11.187109) (xy 312.983234 -11.259084) (xy 312.951908 -11.32812) (xy 312.913421 -11.393435)
			(xy 312.86821 -11.45429) (xy 312.816786 -11.509994) (xy 312.759733 -11.559916) (xy 312.697697 -11.603491)
			(xy 312.63138 -11.640226) (xy 312.561534 -11.669703) (xy 312.488951 -11.691589) (xy 312.414453 -11.705636)
			(xy 312.338883 -11.711685) (xy 312.263099 -11.709666) (xy 312.187959 -11.699604) (xy 312.114314 -11.681612)
			(xy 312.042998 -11.655894) (xy 311.974821 -11.622742) (xy 311.910553 -11.58253) (xy 311.850924 -11.535715)
			(xy 311.796608 -11.482827) (xy 311.748222 -11.424465) (xy 311.706314 -11.36129) (xy 311.671358 -11.294019)
			(xy 311.643751 -11.223414) (xy 311.623805 -11.150273) (xy 311.611746 -11.075428) (xy 311.607711 -10.999724)
			(xy 283.305629 -10.999724) (xy 283.295428 -11.109084) (xy 283.271975 -11.274699) (xy 283.240657 -11.439009)
			(xy 283.201544 -11.601639) (xy 283.154727 -11.76222) (xy 283.10031 -11.920389) (xy 283.038417 -12.075784)
			(xy 282.969191 -12.228054) (xy 282.892786 -12.376851) (xy 282.809378 -12.521839) (xy 282.719156 -12.662688)
			(xy 282.622324 -12.799077) (xy 282.519103 -12.930697) (xy 282.459449 -12.99972) (xy 311.607711 -12.99972)
			(xy 311.611746 -12.924016) (xy 311.623805 -12.849171) (xy 311.643751 -12.77603) (xy 311.671358 -12.705425)
			(xy 311.706314 -12.638154) (xy 311.748222 -12.574979) (xy 311.796608 -12.516617) (xy 311.850924 -12.463729)
			(xy 311.910553 -12.416914) (xy 311.974821 -12.376702) (xy 312.042998 -12.34355) (xy 312.114314 -12.317832)
			(xy 312.187959 -12.29984) (xy 312.263099 -12.289778) (xy 312.338883 -12.287759) (xy 312.414453 -12.293808)
			(xy 312.488951 -12.307855) (xy 312.561534 -12.329741) (xy 312.63138 -12.359218) (xy 312.697697 -12.395953)
			(xy 312.759733 -12.439528) (xy 312.816786 -12.48945) (xy 312.86821 -12.545154) (xy 312.913421 -12.606009)
			(xy 312.951908 -12.671324) (xy 312.983234 -12.74036) (xy 313.007044 -12.812335) (xy 313.023069 -12.886433)
			(xy 313.031128 -12.961814) (xy 313.031632 -12.99972) (xy 313.607707 -12.99972) (xy 313.611742 -12.924016)
			(xy 313.623801 -12.849171) (xy 313.643747 -12.77603) (xy 313.671354 -12.705425) (xy 313.70631 -12.638154)
			(xy 313.748218 -12.574979) (xy 313.796604 -12.516617) (xy 313.85092 -12.463729) (xy 313.910549 -12.416914)
			(xy 313.974817 -12.376702) (xy 314.042994 -12.34355) (xy 314.11431 -12.317832) (xy 314.187955 -12.29984)
			(xy 314.263095 -12.289778) (xy 314.338879 -12.287759) (xy 314.414449 -12.293808) (xy 314.488947 -12.307855)
			(xy 314.56153 -12.329741) (xy 314.631376 -12.359218) (xy 314.697693 -12.395953) (xy 314.759729 -12.439528)
			(xy 314.816782 -12.48945) (xy 314.868206 -12.545154) (xy 314.913417 -12.606009) (xy 314.951904 -12.671324)
			(xy 314.98323 -12.74036) (xy 315.00704 -12.812335) (xy 315.023065 -12.886433) (xy 315.031124 -12.961814)
			(xy 315.031628 -12.99972) (xy 315.031124 -13.037626) (xy 315.023065 -13.113007) (xy 315.00704 -13.187105)
			(xy 314.98323 -13.25908) (xy 314.951904 -13.328116) (xy 314.913417 -13.393431) (xy 314.868206 -13.454286)
			(xy 314.816782 -13.50999) (xy 314.759729 -13.559912) (xy 314.697693 -13.603487) (xy 314.631376 -13.640222)
			(xy 314.56153 -13.669699) (xy 314.488947 -13.691585) (xy 314.414449 -13.705632) (xy 314.338879 -13.711681)
			(xy 314.263095 -13.709662) (xy 314.187955 -13.6996) (xy 314.11431 -13.681608) (xy 314.042994 -13.65589)
			(xy 313.974817 -13.622738) (xy 313.910549 -13.582526) (xy 313.85092 -13.535711) (xy 313.796604 -13.482823)
			(xy 313.748218 -13.424461) (xy 313.70631 -13.361286) (xy 313.671354 -13.294015) (xy 313.643747 -13.22341)
			(xy 313.623801 -13.150269) (xy 313.611742 -13.075424) (xy 313.607707 -12.99972) (xy 313.031632 -12.99972)
			(xy 313.031128 -13.037626) (xy 313.023069 -13.113007) (xy 313.007044 -13.187105) (xy 312.983234 -13.25908)
			(xy 312.951908 -13.328116) (xy 312.913421 -13.393431) (xy 312.86821 -13.454286) (xy 312.816786 -13.50999)
			(xy 312.759733 -13.559912) (xy 312.697697 -13.603487) (xy 312.63138 -13.640222) (xy 312.561534 -13.669699)
			(xy 312.488951 -13.691585) (xy 312.414453 -13.705632) (xy 312.338883 -13.711681) (xy 312.263099 -13.709662)
			(xy 312.187959 -13.6996) (xy 312.114314 -13.681608) (xy 312.042998 -13.65589) (xy 311.974821 -13.622738)
			(xy 311.910553 -13.582526) (xy 311.850924 -13.535711) (xy 311.796608 -13.482823) (xy 311.748222 -13.424461)
			(xy 311.706314 -13.361286) (xy 311.671358 -13.294015) (xy 311.643751 -13.22341) (xy 311.623805 -13.150269)
			(xy 311.611746 -13.075424) (xy 311.607711 -12.99972) (xy 282.459449 -12.99972) (xy 282.409728 -13.057249)
			(xy 282.294446 -13.178445) (xy 282.173519 -13.294009) (xy 282.047223 -13.40368) (xy 281.915845 -13.507208)
			(xy 281.779682 -13.604358) (xy 281.639045 -13.694909) (xy 281.494252 -13.778656) (xy 281.345633 -13.855407)
			(xy 281.193526 -13.92499) (xy 281.038275 -13.987245) (xy 280.880235 -14.042031) (xy 280.719763 -14.089223)
			(xy 280.557224 -14.128716) (xy 280.392989 -14.160418) (xy 280.227429 -14.184258) (xy 280.060921 -14.200181)
			(xy 279.893844 -14.208152) (xy 279.726576 -14.208152) (xy 279.559499 -14.200181) (xy 279.392991 -14.184258)
			(xy 279.227431 -14.160418) (xy 279.063196 -14.128716) (xy 278.900657 -14.089223) (xy 278.740185 -14.042031)
			(xy 278.582145 -13.987245) (xy 278.426894 -13.92499) (xy 278.274787 -13.855407) (xy 278.126168 -13.778656)
			(xy 277.981375 -13.694909) (xy 277.840738 -13.604358) (xy 277.704575 -13.507208) (xy 277.573197 -13.40368)
			(xy 277.446901 -13.294009) (xy 277.325974 -13.178445) (xy 277.210692 -13.057249) (xy 277.101317 -12.930697)
			(xy 276.998096 -12.799077) (xy 276.901264 -12.662688) (xy 276.811042 -12.521839) (xy 276.727634 -12.376851)
			(xy 276.651229 -12.228054) (xy 276.582003 -12.075784) (xy 276.52011 -11.920389) (xy 276.465693 -11.76222)
			(xy 276.418876 -11.601639) (xy 276.379763 -11.439009) (xy 276.348445 -11.274699) (xy 276.324992 -11.109084)
			(xy 276.309457 -10.94254) (xy 276.301877 -10.775444) (xy 207.192829 -10.775444) (xy 207.198504 -10.78256)
			(xy 207.23645 -10.842951) (xy 207.267395 -10.90721) (xy 207.290952 -10.97453) (xy 207.306822 -11.044065)
			(xy 207.314808 -11.114939) (xy 207.315308 -11.1506) (xy 207.314808 -11.186261) (xy 207.306822 -11.257135)
			(xy 207.290952 -11.32667) (xy 207.267395 -11.39399) (xy 207.23645 -11.458249) (xy 207.198504 -11.51864)
			(xy 207.154035 -11.574402) (xy 207.135776 -11.592661) (xy 264.286992 -11.592661) (xy 264.286992 -11.521339)
			(xy 264.294978 -11.450465) (xy 264.310848 -11.38093) (xy 264.334405 -11.31361) (xy 264.36535 -11.249351)
			(xy 264.403296 -11.18896) (xy 264.447765 -11.133198) (xy 264.498198 -11.082765) (xy 264.55396 -11.038296)
			(xy 264.614351 -11.00035) (xy 264.67861 -10.969405) (xy 264.74593 -10.945848) (xy 264.815465 -10.929978)
			(xy 264.886339 -10.921992) (xy 264.957661 -10.921992) (xy 265.028535 -10.929978) (xy 265.09807 -10.945848)
			(xy 265.16539 -10.969405) (xy 265.229649 -11.00035) (xy 265.29004 -11.038296) (xy 265.345802 -11.082765)
			(xy 265.396235 -11.133198) (xy 265.440704 -11.18896) (xy 265.47865 -11.249351) (xy 265.509595 -11.31361)
			(xy 265.533152 -11.38093) (xy 265.549022 -11.450465) (xy 265.557008 -11.521339) (xy 265.557508 -11.557)
			(xy 265.557008 -11.592661) (xy 271.906992 -11.592661) (xy 271.906992 -11.521339) (xy 271.914978 -11.450465)
			(xy 271.930848 -11.38093) (xy 271.954405 -11.31361) (xy 271.98535 -11.249351) (xy 272.023296 -11.18896)
			(xy 272.067765 -11.133198) (xy 272.118198 -11.082765) (xy 272.17396 -11.038296) (xy 272.234351 -11.00035)
			(xy 272.29861 -10.969405) (xy 272.36593 -10.945848) (xy 272.435465 -10.929978) (xy 272.506339 -10.921992)
			(xy 272.577661 -10.921992) (xy 272.648535 -10.929978) (xy 272.71807 -10.945848) (xy 272.78539 -10.969405)
			(xy 272.849649 -11.00035) (xy 272.91004 -11.038296) (xy 272.965802 -11.082765) (xy 273.016235 -11.133198)
			(xy 273.060704 -11.18896) (xy 273.09865 -11.249351) (xy 273.129595 -11.31361) (xy 273.153152 -11.38093)
			(xy 273.169022 -11.450465) (xy 273.177008 -11.521339) (xy 273.177508 -11.557) (xy 273.177008 -11.592661)
			(xy 273.169022 -11.663535) (xy 273.153152 -11.73307) (xy 273.129595 -11.80039) (xy 273.09865 -11.864649)
			(xy 273.060704 -11.92504) (xy 273.016235 -11.980802) (xy 272.965802 -12.031235) (xy 272.91004 -12.075704)
			(xy 272.849649 -12.11365) (xy 272.78539 -12.144595) (xy 272.71807 -12.168152) (xy 272.648535 -12.184022)
			(xy 272.577661 -12.192008) (xy 272.506339 -12.192008) (xy 272.435465 -12.184022) (xy 272.36593 -12.168152)
			(xy 272.29861 -12.144595) (xy 272.234351 -12.11365) (xy 272.17396 -12.075704) (xy 272.118198 -12.031235)
			(xy 272.067765 -11.980802) (xy 272.023296 -11.92504) (xy 271.98535 -11.864649) (xy 271.954405 -11.80039)
			(xy 271.930848 -11.73307) (xy 271.914978 -11.663535) (xy 271.906992 -11.592661) (xy 265.557008 -11.592661)
			(xy 265.549022 -11.663535) (xy 265.533152 -11.73307) (xy 265.509595 -11.80039) (xy 265.47865 -11.864649)
			(xy 265.440704 -11.92504) (xy 265.396235 -11.980802) (xy 265.345802 -12.031235) (xy 265.29004 -12.075704)
			(xy 265.229649 -12.11365) (xy 265.16539 -12.144595) (xy 265.09807 -12.168152) (xy 265.028535 -12.184022)
			(xy 264.957661 -12.192008) (xy 264.886339 -12.192008) (xy 264.815465 -12.184022) (xy 264.74593 -12.168152)
			(xy 264.67861 -12.144595) (xy 264.614351 -12.11365) (xy 264.55396 -12.075704) (xy 264.498198 -12.031235)
			(xy 264.447765 -11.980802) (xy 264.403296 -11.92504) (xy 264.36535 -11.864649) (xy 264.334405 -11.80039)
			(xy 264.310848 -11.73307) (xy 264.294978 -11.663535) (xy 264.286992 -11.592661) (xy 207.135776 -11.592661)
			(xy 207.103602 -11.624835) (xy 207.04784 -11.669304) (xy 206.987449 -11.70725) (xy 206.92319 -11.738195)
			(xy 206.85587 -11.761752) (xy 206.786335 -11.777622) (xy 206.715461 -11.785608) (xy 206.644139 -11.785608)
			(xy 206.573265 -11.777622) (xy 206.50373 -11.761752) (xy 206.43641 -11.738195) (xy 206.372151 -11.70725)
			(xy 206.31176 -11.669304) (xy 206.255998 -11.624835) (xy 206.205565 -11.574402) (xy 206.161096 -11.51864)
			(xy 206.12315 -11.458249) (xy 206.092205 -11.39399) (xy 206.068648 -11.32667) (xy 206.052778 -11.257135)
			(xy 206.044792 -11.186261) (xy 203.3016 -11.186261) (xy 203.3016 -14.999716) (xy 311.607711 -14.999716)
			(xy 311.611746 -14.924012) (xy 311.623805 -14.849167) (xy 311.643751 -14.776026) (xy 311.671358 -14.705421)
			(xy 311.706314 -14.63815) (xy 311.748222 -14.574975) (xy 311.796608 -14.516613) (xy 311.850924 -14.463725)
			(xy 311.910553 -14.41691) (xy 311.974821 -14.376698) (xy 312.042998 -14.343546) (xy 312.114314 -14.317828)
			(xy 312.187959 -14.299836) (xy 312.263099 -14.289774) (xy 312.338883 -14.287755) (xy 312.414453 -14.293804)
			(xy 312.488951 -14.307851) (xy 312.561534 -14.329737) (xy 312.63138 -14.359214) (xy 312.697697 -14.395949)
			(xy 312.759733 -14.439524) (xy 312.816786 -14.489446) (xy 312.86821 -14.54515) (xy 312.913421 -14.606005)
			(xy 312.951908 -14.67132) (xy 312.983234 -14.740356) (xy 313.007044 -14.812331) (xy 313.023069 -14.886429)
			(xy 313.031128 -14.96181) (xy 313.031632 -14.999716) (xy 313.607707 -14.999716) (xy 313.611742 -14.924012)
			(xy 313.623801 -14.849167) (xy 313.643747 -14.776026) (xy 313.671354 -14.705421) (xy 313.70631 -14.63815)
			(xy 313.748218 -14.574975) (xy 313.796604 -14.516613) (xy 313.85092 -14.463725) (xy 313.910549 -14.41691)
			(xy 313.974817 -14.376698) (xy 314.042994 -14.343546) (xy 314.11431 -14.317828) (xy 314.187955 -14.299836)
			(xy 314.263095 -14.289774) (xy 314.338879 -14.287755) (xy 314.414449 -14.293804) (xy 314.488947 -14.307851)
			(xy 314.56153 -14.329737) (xy 314.631376 -14.359214) (xy 314.697693 -14.395949) (xy 314.759729 -14.439524)
			(xy 314.816782 -14.489446) (xy 314.868206 -14.54515) (xy 314.913417 -14.606005) (xy 314.951904 -14.67132)
			(xy 314.98323 -14.740356) (xy 315.00704 -14.812331) (xy 315.023065 -14.886429) (xy 315.031124 -14.96181)
			(xy 315.031628 -14.999716) (xy 315.031124 -15.037622) (xy 315.023065 -15.113003) (xy 315.00704 -15.187101)
			(xy 314.98323 -15.259076) (xy 314.951904 -15.328112) (xy 314.913417 -15.393427) (xy 314.868206 -15.454282)
			(xy 314.816782 -15.509986) (xy 314.759729 -15.559908) (xy 314.697693 -15.603483) (xy 314.631376 -15.640218)
			(xy 314.56153 -15.669695) (xy 314.488947 -15.691581) (xy 314.414449 -15.705628) (xy 314.338879 -15.711677)
			(xy 314.263095 -15.709658) (xy 314.187955 -15.699596) (xy 314.11431 -15.681604) (xy 314.042994 -15.655886)
			(xy 313.974817 -15.622734) (xy 313.910549 -15.582522) (xy 313.85092 -15.535707) (xy 313.796604 -15.482819)
			(xy 313.748218 -15.424457) (xy 313.70631 -15.361282) (xy 313.671354 -15.294011) (xy 313.643747 -15.223406)
			(xy 313.623801 -15.150265) (xy 313.611742 -15.07542) (xy 313.607707 -14.999716) (xy 313.031632 -14.999716)
			(xy 313.031128 -15.037622) (xy 313.023069 -15.113003) (xy 313.007044 -15.187101) (xy 312.983234 -15.259076)
			(xy 312.951908 -15.328112) (xy 312.913421 -15.393427) (xy 312.86821 -15.454282) (xy 312.816786 -15.509986)
			(xy 312.759733 -15.559908) (xy 312.697697 -15.603483) (xy 312.63138 -15.640218) (xy 312.561534 -15.669695)
			(xy 312.488951 -15.691581) (xy 312.414453 -15.705628) (xy 312.338883 -15.711677) (xy 312.263099 -15.709658)
			(xy 312.187959 -15.699596) (xy 312.114314 -15.681604) (xy 312.042998 -15.655886) (xy 311.974821 -15.622734)
			(xy 311.910553 -15.582522) (xy 311.850924 -15.535707) (xy 311.796608 -15.482819) (xy 311.748222 -15.424457)
			(xy 311.706314 -15.361282) (xy 311.671358 -15.294011) (xy 311.643751 -15.223406) (xy 311.623805 -15.150265)
			(xy 311.611746 -15.07542) (xy 311.607711 -14.999716) (xy 203.3016 -14.999716) (xy 203.3016 -16.418661)
			(xy 284.073592 -16.418661) (xy 284.073592 -16.347339) (xy 284.081578 -16.276465) (xy 284.097448 -16.20693)
			(xy 284.121005 -16.13961) (xy 284.15195 -16.075351) (xy 284.189896 -16.01496) (xy 284.234365 -15.959198)
			(xy 284.284798 -15.908765) (xy 284.34056 -15.864296) (xy 284.400951 -15.82635) (xy 284.46521 -15.795405)
			(xy 284.53253 -15.771848) (xy 284.602065 -15.755978) (xy 284.672939 -15.747992) (xy 284.744261 -15.747992)
			(xy 284.815135 -15.755978) (xy 284.88467 -15.771848) (xy 284.95199 -15.795405) (xy 285.016249 -15.82635)
			(xy 285.07664 -15.864296) (xy 285.132402 -15.908765) (xy 285.182835 -15.959198) (xy 285.227304 -16.01496)
			(xy 285.26525 -16.075351) (xy 285.296195 -16.13961) (xy 285.319752 -16.20693) (xy 285.335622 -16.276465)
			(xy 285.343608 -16.347339) (xy 285.344108 -16.383) (xy 285.343608 -16.418661) (xy 290.728392 -16.418661)
			(xy 290.728392 -16.347339) (xy 290.736378 -16.276465) (xy 290.752248 -16.20693) (xy 290.775805 -16.13961)
			(xy 290.80675 -16.075351) (xy 290.844696 -16.01496) (xy 290.889165 -15.959198) (xy 290.939598 -15.908765)
			(xy 290.99536 -15.864296) (xy 291.055751 -15.82635) (xy 291.12001 -15.795405) (xy 291.18733 -15.771848)
			(xy 291.256865 -15.755978) (xy 291.327739 -15.747992) (xy 291.399061 -15.747992) (xy 291.469935 -15.755978)
			(xy 291.53947 -15.771848) (xy 291.60679 -15.795405) (xy 291.671049 -15.82635) (xy 291.73144 -15.864296)
			(xy 291.787202 -15.908765) (xy 291.837635 -15.959198) (xy 291.882104 -16.01496) (xy 291.92005 -16.075351)
			(xy 291.950995 -16.13961) (xy 291.974552 -16.20693) (xy 291.990422 -16.276465) (xy 291.998408 -16.347339)
			(xy 291.998908 -16.383) (xy 291.998408 -16.418661) (xy 291.990422 -16.489535) (xy 291.974552 -16.55907)
			(xy 291.950995 -16.62639) (xy 291.92005 -16.690649) (xy 291.882104 -16.75104) (xy 291.837635 -16.806802)
			(xy 291.787202 -16.857235) (xy 291.73144 -16.901704) (xy 291.671049 -16.93965) (xy 291.60679 -16.970595)
			(xy 291.53947 -16.994152) (xy 291.469935 -17.010022) (xy 291.399061 -17.018008) (xy 291.327739 -17.018008)
			(xy 291.256865 -17.010022) (xy 291.18733 -16.994152) (xy 291.12001 -16.970595) (xy 291.055751 -16.93965)
			(xy 290.99536 -16.901704) (xy 290.939598 -16.857235) (xy 290.889165 -16.806802) (xy 290.844696 -16.75104)
			(xy 290.80675 -16.690649) (xy 290.775805 -16.62639) (xy 290.752248 -16.55907) (xy 290.736378 -16.489535)
			(xy 290.728392 -16.418661) (xy 285.343608 -16.418661) (xy 285.335622 -16.489535) (xy 285.319752 -16.55907)
			(xy 285.296195 -16.62639) (xy 285.26525 -16.690649) (xy 285.227304 -16.75104) (xy 285.182835 -16.806802)
			(xy 285.132402 -16.857235) (xy 285.07664 -16.901704) (xy 285.016249 -16.93965) (xy 284.95199 -16.970595)
			(xy 284.88467 -16.994152) (xy 284.815135 -17.010022) (xy 284.744261 -17.018008) (xy 284.672939 -17.018008)
			(xy 284.602065 -17.010022) (xy 284.53253 -16.994152) (xy 284.46521 -16.970595) (xy 284.400951 -16.93965)
			(xy 284.34056 -16.901704) (xy 284.284798 -16.857235) (xy 284.234365 -16.806802) (xy 284.189896 -16.75104)
			(xy 284.15195 -16.690649) (xy 284.121005 -16.62639) (xy 284.097448 -16.55907) (xy 284.081578 -16.489535)
			(xy 284.073592 -16.418661) (xy 203.3016 -16.418661) (xy 203.3016 -22.006661) (xy 205.028792 -22.006661)
			(xy 205.028792 -21.935339) (xy 205.036778 -21.864465) (xy 205.052648 -21.79493) (xy 205.076205 -21.72761)
			(xy 205.10715 -21.663351) (xy 205.145096 -21.60296) (xy 205.189565 -21.547198) (xy 205.239998 -21.496765)
			(xy 205.29576 -21.452296) (xy 205.356151 -21.41435) (xy 205.42041 -21.383405) (xy 205.48773 -21.359848)
			(xy 205.557265 -21.343978) (xy 205.628139 -21.335992) (xy 205.699461 -21.335992) (xy 205.770335 -21.343978)
			(xy 205.83987 -21.359848) (xy 205.90719 -21.383405) (xy 205.971449 -21.41435) (xy 206.03184 -21.452296)
			(xy 206.087602 -21.496765) (xy 206.138035 -21.547198) (xy 206.182504 -21.60296) (xy 206.22045 -21.663351)
			(xy 206.251395 -21.72761) (xy 206.274952 -21.79493) (xy 206.290822 -21.864465) (xy 206.298808 -21.935339)
			(xy 206.299308 -21.971) (xy 206.298808 -22.006661) (xy 212.648792 -22.006661) (xy 212.648792 -21.935339)
			(xy 212.656778 -21.864465) (xy 212.672648 -21.79493) (xy 212.696205 -21.72761) (xy 212.72715 -21.663351)
			(xy 212.765096 -21.60296) (xy 212.809565 -21.547198) (xy 212.859998 -21.496765) (xy 212.91576 -21.452296)
			(xy 212.976151 -21.41435) (xy 213.04041 -21.383405) (xy 213.10773 -21.359848) (xy 213.177265 -21.343978)
			(xy 213.248139 -21.335992) (xy 213.319461 -21.335992) (xy 213.390335 -21.343978) (xy 213.45987 -21.359848)
			(xy 213.52719 -21.383405) (xy 213.591449 -21.41435) (xy 213.65184 -21.452296) (xy 213.707602 -21.496765)
			(xy 213.758035 -21.547198) (xy 213.802504 -21.60296) (xy 213.84045 -21.663351) (xy 213.871395 -21.72761)
			(xy 213.894952 -21.79493) (xy 213.910822 -21.864465) (xy 213.918808 -21.935339) (xy 213.919308 -21.971)
			(xy 213.918808 -22.006661) (xy 220.268792 -22.006661) (xy 220.268792 -21.935339) (xy 220.276778 -21.864465)
			(xy 220.292648 -21.79493) (xy 220.316205 -21.72761) (xy 220.34715 -21.663351) (xy 220.385096 -21.60296)
			(xy 220.429565 -21.547198) (xy 220.479998 -21.496765) (xy 220.53576 -21.452296) (xy 220.596151 -21.41435)
			(xy 220.66041 -21.383405) (xy 220.72773 -21.359848) (xy 220.797265 -21.343978) (xy 220.868139 -21.335992)
			(xy 220.939461 -21.335992) (xy 221.010335 -21.343978) (xy 221.07987 -21.359848) (xy 221.14719 -21.383405)
			(xy 221.211449 -21.41435) (xy 221.27184 -21.452296) (xy 221.327602 -21.496765) (xy 221.378035 -21.547198)
			(xy 221.422504 -21.60296) (xy 221.46045 -21.663351) (xy 221.491395 -21.72761) (xy 221.514952 -21.79493)
			(xy 221.530822 -21.864465) (xy 221.538808 -21.935339) (xy 221.539308 -21.971) (xy 221.538808 -22.006661)
			(xy 227.888792 -22.006661) (xy 227.888792 -21.935339) (xy 227.896778 -21.864465) (xy 227.912648 -21.79493)
			(xy 227.936205 -21.72761) (xy 227.96715 -21.663351) (xy 228.005096 -21.60296) (xy 228.049565 -21.547198)
			(xy 228.099998 -21.496765) (xy 228.15576 -21.452296) (xy 228.216151 -21.41435) (xy 228.28041 -21.383405)
			(xy 228.34773 -21.359848) (xy 228.417265 -21.343978) (xy 228.488139 -21.335992) (xy 228.559461 -21.335992)
			(xy 228.630335 -21.343978) (xy 228.69987 -21.359848) (xy 228.76719 -21.383405) (xy 228.831449 -21.41435)
			(xy 228.89184 -21.452296) (xy 228.947602 -21.496765) (xy 228.998035 -21.547198) (xy 229.042504 -21.60296)
			(xy 229.08045 -21.663351) (xy 229.111395 -21.72761) (xy 229.134952 -21.79493) (xy 229.150822 -21.864465)
			(xy 229.158808 -21.935339) (xy 229.159308 -21.971) (xy 229.158808 -22.006661) (xy 235.508792 -22.006661)
			(xy 235.508792 -21.935339) (xy 235.516778 -21.864465) (xy 235.532648 -21.79493) (xy 235.556205 -21.72761)
			(xy 235.58715 -21.663351) (xy 235.625096 -21.60296) (xy 235.669565 -21.547198) (xy 235.719998 -21.496765)
			(xy 235.77576 -21.452296) (xy 235.836151 -21.41435) (xy 235.90041 -21.383405) (xy 235.96773 -21.359848)
			(xy 236.037265 -21.343978) (xy 236.108139 -21.335992) (xy 236.179461 -21.335992) (xy 236.250335 -21.343978)
			(xy 236.31987 -21.359848) (xy 236.38719 -21.383405) (xy 236.451449 -21.41435) (xy 236.51184 -21.452296)
			(xy 236.567602 -21.496765) (xy 236.618035 -21.547198) (xy 236.662504 -21.60296) (xy 236.70045 -21.663351)
			(xy 236.731395 -21.72761) (xy 236.754952 -21.79493) (xy 236.770822 -21.864465) (xy 236.778808 -21.935339)
			(xy 236.779308 -21.971) (xy 236.778808 -22.006661) (xy 243.128792 -22.006661) (xy 243.128792 -21.935339)
			(xy 243.136778 -21.864465) (xy 243.152648 -21.79493) (xy 243.176205 -21.72761) (xy 243.20715 -21.663351)
			(xy 243.245096 -21.60296) (xy 243.289565 -21.547198) (xy 243.339998 -21.496765) (xy 243.39576 -21.452296)
			(xy 243.456151 -21.41435) (xy 243.52041 -21.383405) (xy 243.58773 -21.359848) (xy 243.657265 -21.343978)
			(xy 243.728139 -21.335992) (xy 243.799461 -21.335992) (xy 243.870335 -21.343978) (xy 243.93987 -21.359848)
			(xy 244.00719 -21.383405) (xy 244.071449 -21.41435) (xy 244.13184 -21.452296) (xy 244.187602 -21.496765)
			(xy 244.238035 -21.547198) (xy 244.282504 -21.60296) (xy 244.32045 -21.663351) (xy 244.351395 -21.72761)
			(xy 244.374952 -21.79493) (xy 244.390822 -21.864465) (xy 244.398808 -21.935339) (xy 244.399308 -21.971)
			(xy 244.398808 -22.006661) (xy 250.748792 -22.006661) (xy 250.748792 -21.935339) (xy 250.756778 -21.864465)
			(xy 250.772648 -21.79493) (xy 250.796205 -21.72761) (xy 250.82715 -21.663351) (xy 250.865096 -21.60296)
			(xy 250.909565 -21.547198) (xy 250.959998 -21.496765) (xy 251.01576 -21.452296) (xy 251.076151 -21.41435)
			(xy 251.14041 -21.383405) (xy 251.20773 -21.359848) (xy 251.277265 -21.343978) (xy 251.348139 -21.335992)
			(xy 251.419461 -21.335992) (xy 251.490335 -21.343978) (xy 251.55987 -21.359848) (xy 251.62719 -21.383405)
			(xy 251.655547 -21.397061) (xy 261.467592 -21.397061) (xy 261.467592 -21.325739) (xy 261.475578 -21.254865)
			(xy 261.491448 -21.18533) (xy 261.515005 -21.11801) (xy 261.54595 -21.053751) (xy 261.583896 -20.99336)
			(xy 261.628365 -20.937598) (xy 261.678798 -20.887165) (xy 261.73456 -20.842696) (xy 261.794951 -20.80475)
			(xy 261.85921 -20.773805) (xy 261.92653 -20.750248) (xy 261.996065 -20.734378) (xy 262.066939 -20.726392)
			(xy 262.138261 -20.726392) (xy 262.209135 -20.734378) (xy 262.27867 -20.750248) (xy 262.34599 -20.773805)
			(xy 262.410249 -20.80475) (xy 262.47064 -20.842696) (xy 262.526402 -20.887165) (xy 262.576835 -20.937598)
			(xy 262.621304 -20.99336) (xy 262.65925 -21.053751) (xy 262.690195 -21.11801) (xy 262.713752 -21.18533)
			(xy 262.729622 -21.254865) (xy 262.737608 -21.325739) (xy 262.738108 -21.3614) (xy 262.737608 -21.397061)
			(xy 269.087592 -21.397061) (xy 269.087592 -21.325739) (xy 269.095578 -21.254865) (xy 269.111448 -21.18533)
			(xy 269.135005 -21.11801) (xy 269.16595 -21.053751) (xy 269.203896 -20.99336) (xy 269.248365 -20.937598)
			(xy 269.298798 -20.887165) (xy 269.35456 -20.842696) (xy 269.414951 -20.80475) (xy 269.47921 -20.773805)
			(xy 269.54653 -20.750248) (xy 269.616065 -20.734378) (xy 269.686939 -20.726392) (xy 269.758261 -20.726392)
			(xy 269.829135 -20.734378) (xy 269.89867 -20.750248) (xy 269.96599 -20.773805) (xy 270.030249 -20.80475)
			(xy 270.09064 -20.842696) (xy 270.146402 -20.887165) (xy 270.196835 -20.937598) (xy 270.241304 -20.99336)
			(xy 270.27925 -21.053751) (xy 270.310195 -21.11801) (xy 270.333752 -21.18533) (xy 270.349622 -21.254865)
			(xy 270.357608 -21.325739) (xy 270.358108 -21.3614) (xy 270.357608 -21.397061) (xy 276.707592 -21.397061)
			(xy 276.707592 -21.325739) (xy 276.715578 -21.254865) (xy 276.731448 -21.18533) (xy 276.755005 -21.11801)
			(xy 276.78595 -21.053751) (xy 276.823896 -20.99336) (xy 276.868365 -20.937598) (xy 276.918798 -20.887165)
			(xy 276.97456 -20.842696) (xy 277.034951 -20.80475) (xy 277.09921 -20.773805) (xy 277.16653 -20.750248)
			(xy 277.236065 -20.734378) (xy 277.306939 -20.726392) (xy 277.378261 -20.726392) (xy 277.449135 -20.734378)
			(xy 277.51867 -20.750248) (xy 277.58599 -20.773805) (xy 277.650249 -20.80475) (xy 277.71064 -20.842696)
			(xy 277.766402 -20.887165) (xy 277.816835 -20.937598) (xy 277.861304 -20.99336) (xy 277.89925 -21.053751)
			(xy 277.930195 -21.11801) (xy 277.953752 -21.18533) (xy 277.969622 -21.254865) (xy 277.977608 -21.325739)
			(xy 277.978108 -21.3614) (xy 277.977608 -21.397061) (xy 284.327592 -21.397061) (xy 284.327592 -21.325739)
			(xy 284.335578 -21.254865) (xy 284.351448 -21.18533) (xy 284.375005 -21.11801) (xy 284.40595 -21.053751)
			(xy 284.443896 -20.99336) (xy 284.488365 -20.937598) (xy 284.538798 -20.887165) (xy 284.59456 -20.842696)
			(xy 284.654951 -20.80475) (xy 284.71921 -20.773805) (xy 284.78653 -20.750248) (xy 284.856065 -20.734378)
			(xy 284.926939 -20.726392) (xy 284.998261 -20.726392) (xy 285.069135 -20.734378) (xy 285.13867 -20.750248)
			(xy 285.20599 -20.773805) (xy 285.270249 -20.80475) (xy 285.33064 -20.842696) (xy 285.386402 -20.887165)
			(xy 285.436835 -20.937598) (xy 285.481304 -20.99336) (xy 285.51925 -21.053751) (xy 285.550195 -21.11801)
			(xy 285.573752 -21.18533) (xy 285.589622 -21.254865) (xy 285.597608 -21.325739) (xy 285.598108 -21.3614)
			(xy 285.597608 -21.397061) (xy 291.947592 -21.397061) (xy 291.947592 -21.325739) (xy 291.955578 -21.254865)
			(xy 291.971448 -21.18533) (xy 291.995005 -21.11801) (xy 292.02595 -21.053751) (xy 292.063896 -20.99336)
			(xy 292.108365 -20.937598) (xy 292.158798 -20.887165) (xy 292.21456 -20.842696) (xy 292.274951 -20.80475)
			(xy 292.33921 -20.773805) (xy 292.40653 -20.750248) (xy 292.476065 -20.734378) (xy 292.546939 -20.726392)
			(xy 292.618261 -20.726392) (xy 292.689135 -20.734378) (xy 292.75867 -20.750248) (xy 292.82599 -20.773805)
			(xy 292.890249 -20.80475) (xy 292.95064 -20.842696) (xy 293.006402 -20.887165) (xy 293.056835 -20.937598)
			(xy 293.101304 -20.99336) (xy 293.13925 -21.053751) (xy 293.170195 -21.11801) (xy 293.193752 -21.18533)
			(xy 293.209622 -21.254865) (xy 293.217608 -21.325739) (xy 293.218108 -21.3614) (xy 293.217608 -21.397061)
			(xy 293.209622 -21.467935) (xy 293.193752 -21.53747) (xy 293.170195 -21.60479) (xy 293.13925 -21.669049)
			(xy 293.101304 -21.72944) (xy 293.056835 -21.785202) (xy 293.006402 -21.835635) (xy 292.95064 -21.880104)
			(xy 292.890249 -21.91805) (xy 292.82599 -21.948995) (xy 292.75867 -21.972552) (xy 292.689135 -21.988422)
			(xy 292.618261 -21.996408) (xy 292.546939 -21.996408) (xy 292.476065 -21.988422) (xy 292.40653 -21.972552)
			(xy 292.33921 -21.948995) (xy 292.274951 -21.91805) (xy 292.21456 -21.880104) (xy 292.158798 -21.835635)
			(xy 292.108365 -21.785202) (xy 292.063896 -21.72944) (xy 292.02595 -21.669049) (xy 291.995005 -21.60479)
			(xy 291.971448 -21.53747) (xy 291.955578 -21.467935) (xy 291.947592 -21.397061) (xy 285.597608 -21.397061)
			(xy 285.589622 -21.467935) (xy 285.573752 -21.53747) (xy 285.550195 -21.60479) (xy 285.51925 -21.669049)
			(xy 285.481304 -21.72944) (xy 285.436835 -21.785202) (xy 285.386402 -21.835635) (xy 285.33064 -21.880104)
			(xy 285.270249 -21.91805) (xy 285.20599 -21.948995) (xy 285.13867 -21.972552) (xy 285.069135 -21.988422)
			(xy 284.998261 -21.996408) (xy 284.926939 -21.996408) (xy 284.856065 -21.988422) (xy 284.78653 -21.972552)
			(xy 284.71921 -21.948995) (xy 284.654951 -21.91805) (xy 284.59456 -21.880104) (xy 284.538798 -21.835635)
			(xy 284.488365 -21.785202) (xy 284.443896 -21.72944) (xy 284.40595 -21.669049) (xy 284.375005 -21.60479)
			(xy 284.351448 -21.53747) (xy 284.335578 -21.467935) (xy 284.327592 -21.397061) (xy 277.977608 -21.397061)
			(xy 277.969622 -21.467935) (xy 277.953752 -21.53747) (xy 277.930195 -21.60479) (xy 277.89925 -21.669049)
			(xy 277.861304 -21.72944) (xy 277.816835 -21.785202) (xy 277.766402 -21.835635) (xy 277.71064 -21.880104)
			(xy 277.650249 -21.91805) (xy 277.58599 -21.948995) (xy 277.51867 -21.972552) (xy 277.449135 -21.988422)
			(xy 277.378261 -21.996408) (xy 277.306939 -21.996408) (xy 277.236065 -21.988422) (xy 277.16653 -21.972552)
			(xy 277.09921 -21.948995) (xy 277.034951 -21.91805) (xy 276.97456 -21.880104) (xy 276.918798 -21.835635)
			(xy 276.868365 -21.785202) (xy 276.823896 -21.72944) (xy 276.78595 -21.669049) (xy 276.755005 -21.60479)
			(xy 276.731448 -21.53747) (xy 276.715578 -21.467935) (xy 276.707592 -21.397061) (xy 270.357608 -21.397061)
			(xy 270.349622 -21.467935) (xy 270.333752 -21.53747) (xy 270.310195 -21.60479) (xy 270.27925 -21.669049)
			(xy 270.241304 -21.72944) (xy 270.196835 -21.785202) (xy 270.146402 -21.835635) (xy 270.09064 -21.880104)
			(xy 270.030249 -21.91805) (xy 269.96599 -21.948995) (xy 269.89867 -21.972552) (xy 269.829135 -21.988422)
			(xy 269.758261 -21.996408) (xy 269.686939 -21.996408) (xy 269.616065 -21.988422) (xy 269.54653 -21.972552)
			(xy 269.47921 -21.948995) (xy 269.414951 -21.91805) (xy 269.35456 -21.880104) (xy 269.298798 -21.835635)
			(xy 269.248365 -21.785202) (xy 269.203896 -21.72944) (xy 269.16595 -21.669049) (xy 269.135005 -21.60479)
			(xy 269.111448 -21.53747) (xy 269.095578 -21.467935) (xy 269.087592 -21.397061) (xy 262.737608 -21.397061)
			(xy 262.729622 -21.467935) (xy 262.713752 -21.53747) (xy 262.690195 -21.60479) (xy 262.65925 -21.669049)
			(xy 262.621304 -21.72944) (xy 262.576835 -21.785202) (xy 262.526402 -21.835635) (xy 262.47064 -21.880104)
			(xy 262.410249 -21.91805) (xy 262.34599 -21.948995) (xy 262.27867 -21.972552) (xy 262.209135 -21.988422)
			(xy 262.138261 -21.996408) (xy 262.066939 -21.996408) (xy 261.996065 -21.988422) (xy 261.92653 -21.972552)
			(xy 261.85921 -21.948995) (xy 261.794951 -21.91805) (xy 261.73456 -21.880104) (xy 261.678798 -21.835635)
			(xy 261.628365 -21.785202) (xy 261.583896 -21.72944) (xy 261.54595 -21.669049) (xy 261.515005 -21.60479)
			(xy 261.491448 -21.53747) (xy 261.475578 -21.467935) (xy 261.467592 -21.397061) (xy 251.655547 -21.397061)
			(xy 251.691449 -21.41435) (xy 251.75184 -21.452296) (xy 251.807602 -21.496765) (xy 251.858035 -21.547198)
			(xy 251.902504 -21.60296) (xy 251.94045 -21.663351) (xy 251.971395 -21.72761) (xy 251.994952 -21.79493)
			(xy 252.010822 -21.864465) (xy 252.018808 -21.935339) (xy 252.019308 -21.971) (xy 252.018808 -22.006661)
			(xy 252.010822 -22.077535) (xy 251.994952 -22.14707) (xy 251.971395 -22.21439) (xy 251.94045 -22.278649)
			(xy 251.902504 -22.33904) (xy 251.858035 -22.394802) (xy 251.807602 -22.445235) (xy 251.75184 -22.489704)
			(xy 251.691449 -22.52765) (xy 251.62719 -22.558595) (xy 251.55987 -22.582152) (xy 251.490335 -22.598022)
			(xy 251.419461 -22.606008) (xy 251.348139 -22.606008) (xy 251.277265 -22.598022) (xy 251.20773 -22.582152)
			(xy 251.14041 -22.558595) (xy 251.076151 -22.52765) (xy 251.01576 -22.489704) (xy 250.959998 -22.445235)
			(xy 250.909565 -22.394802) (xy 250.865096 -22.33904) (xy 250.82715 -22.278649) (xy 250.796205 -22.21439)
			(xy 250.772648 -22.14707) (xy 250.756778 -22.077535) (xy 250.748792 -22.006661) (xy 244.398808 -22.006661)
			(xy 244.390822 -22.077535) (xy 244.374952 -22.14707) (xy 244.351395 -22.21439) (xy 244.32045 -22.278649)
			(xy 244.282504 -22.33904) (xy 244.238035 -22.394802) (xy 244.187602 -22.445235) (xy 244.13184 -22.489704)
			(xy 244.071449 -22.52765) (xy 244.00719 -22.558595) (xy 243.93987 -22.582152) (xy 243.870335 -22.598022)
			(xy 243.799461 -22.606008) (xy 243.728139 -22.606008) (xy 243.657265 -22.598022) (xy 243.58773 -22.582152)
			(xy 243.52041 -22.558595) (xy 243.456151 -22.52765) (xy 243.39576 -22.489704) (xy 243.339998 -22.445235)
			(xy 243.289565 -22.394802) (xy 243.245096 -22.33904) (xy 243.20715 -22.278649) (xy 243.176205 -22.21439)
			(xy 243.152648 -22.14707) (xy 243.136778 -22.077535) (xy 243.128792 -22.006661) (xy 236.778808 -22.006661)
			(xy 236.770822 -22.077535) (xy 236.754952 -22.14707) (xy 236.731395 -22.21439) (xy 236.70045 -22.278649)
			(xy 236.662504 -22.33904) (xy 236.618035 -22.394802) (xy 236.567602 -22.445235) (xy 236.51184 -22.489704)
			(xy 236.451449 -22.52765) (xy 236.38719 -22.558595) (xy 236.31987 -22.582152) (xy 236.250335 -22.598022)
			(xy 236.179461 -22.606008) (xy 236.108139 -22.606008) (xy 236.037265 -22.598022) (xy 235.96773 -22.582152)
			(xy 235.90041 -22.558595) (xy 235.836151 -22.52765) (xy 235.77576 -22.489704) (xy 235.719998 -22.445235)
			(xy 235.669565 -22.394802) (xy 235.625096 -22.33904) (xy 235.58715 -22.278649) (xy 235.556205 -22.21439)
			(xy 235.532648 -22.14707) (xy 235.516778 -22.077535) (xy 235.508792 -22.006661) (xy 229.158808 -22.006661)
			(xy 229.150822 -22.077535) (xy 229.134952 -22.14707) (xy 229.111395 -22.21439) (xy 229.08045 -22.278649)
			(xy 229.042504 -22.33904) (xy 228.998035 -22.394802) (xy 228.947602 -22.445235) (xy 228.89184 -22.489704)
			(xy 228.831449 -22.52765) (xy 228.76719 -22.558595) (xy 228.69987 -22.582152) (xy 228.630335 -22.598022)
			(xy 228.559461 -22.606008) (xy 228.488139 -22.606008) (xy 228.417265 -22.598022) (xy 228.34773 -22.582152)
			(xy 228.28041 -22.558595) (xy 228.216151 -22.52765) (xy 228.15576 -22.489704) (xy 228.099998 -22.445235)
			(xy 228.049565 -22.394802) (xy 228.005096 -22.33904) (xy 227.96715 -22.278649) (xy 227.936205 -22.21439)
			(xy 227.912648 -22.14707) (xy 227.896778 -22.077535) (xy 227.888792 -22.006661) (xy 221.538808 -22.006661)
			(xy 221.530822 -22.077535) (xy 221.514952 -22.14707) (xy 221.491395 -22.21439) (xy 221.46045 -22.278649)
			(xy 221.422504 -22.33904) (xy 221.378035 -22.394802) (xy 221.327602 -22.445235) (xy 221.27184 -22.489704)
			(xy 221.211449 -22.52765) (xy 221.14719 -22.558595) (xy 221.07987 -22.582152) (xy 221.010335 -22.598022)
			(xy 220.939461 -22.606008) (xy 220.868139 -22.606008) (xy 220.797265 -22.598022) (xy 220.72773 -22.582152)
			(xy 220.66041 -22.558595) (xy 220.596151 -22.52765) (xy 220.53576 -22.489704) (xy 220.479998 -22.445235)
			(xy 220.429565 -22.394802) (xy 220.385096 -22.33904) (xy 220.34715 -22.278649) (xy 220.316205 -22.21439)
			(xy 220.292648 -22.14707) (xy 220.276778 -22.077535) (xy 220.268792 -22.006661) (xy 213.918808 -22.006661)
			(xy 213.910822 -22.077535) (xy 213.894952 -22.14707) (xy 213.871395 -22.21439) (xy 213.84045 -22.278649)
			(xy 213.802504 -22.33904) (xy 213.758035 -22.394802) (xy 213.707602 -22.445235) (xy 213.65184 -22.489704)
			(xy 213.591449 -22.52765) (xy 213.52719 -22.558595) (xy 213.45987 -22.582152) (xy 213.390335 -22.598022)
			(xy 213.319461 -22.606008) (xy 213.248139 -22.606008) (xy 213.177265 -22.598022) (xy 213.10773 -22.582152)
			(xy 213.04041 -22.558595) (xy 212.976151 -22.52765) (xy 212.91576 -22.489704) (xy 212.859998 -22.445235)
			(xy 212.809565 -22.394802) (xy 212.765096 -22.33904) (xy 212.72715 -22.278649) (xy 212.696205 -22.21439)
			(xy 212.672648 -22.14707) (xy 212.656778 -22.077535) (xy 212.648792 -22.006661) (xy 206.298808 -22.006661)
			(xy 206.290822 -22.077535) (xy 206.274952 -22.14707) (xy 206.251395 -22.21439) (xy 206.22045 -22.278649)
			(xy 206.182504 -22.33904) (xy 206.138035 -22.394802) (xy 206.087602 -22.445235) (xy 206.03184 -22.489704)
			(xy 205.971449 -22.52765) (xy 205.90719 -22.558595) (xy 205.83987 -22.582152) (xy 205.770335 -22.598022)
			(xy 205.699461 -22.606008) (xy 205.628139 -22.606008) (xy 205.557265 -22.598022) (xy 205.48773 -22.582152)
			(xy 205.42041 -22.558595) (xy 205.356151 -22.52765) (xy 205.29576 -22.489704) (xy 205.239998 -22.445235)
			(xy 205.189565 -22.394802) (xy 205.145096 -22.33904) (xy 205.10715 -22.278649) (xy 205.076205 -22.21439)
			(xy 205.052648 -22.14707) (xy 205.036778 -22.077535) (xy 205.028792 -22.006661) (xy 203.3016 -22.006661)
			(xy 203.3016 -22.1234) (xy 199.39 -26.035) (xy 199.39 -33.655) (xy 200.136252 -34.401252)
		)
		(stroke
			(width 0)
			(type solid)
		)
		(fill yes)
		(layer "In5.Cu")
		(net "GND")
	)
	(gr_poly
		(pts
			(xy 355.1174 -47.9044) (xy 372.1862 -47.9044) (xy 374.6754 -50.3936) (xy 379.1966 -50.3936) (xy 381.1016 -48.4886)
			(xy 424.8404 -48.4886) (xy 425.5516 -47.7774) (xy 425.5516 -42.926) (xy 423.418 -40.7924) (xy 423.418 -26.4414)
			(xy 423.0116 -26.035) (xy 419.9636 -26.035) (xy 418.3126 -27.686) (xy 418.3126 -32.117284) (xy 418.313056 -32.13877)
			(xy 418.320298 -32.181127) (xy 418.334562 -32.221662) (xy 418.35544 -32.25922) (xy 418.382339 -32.292732)
			(xy 418.414491 -32.321242) (xy 418.450981 -32.343937) (xy 418.490768 -32.360171) (xy 418.532719 -32.369481)
			(xy 418.554154 -32.37103) (xy 418.603871 -32.373938) (xy 418.702628 -32.386859) (xy 418.800004 -32.407788)
			(xy 418.895349 -32.436584) (xy 418.98803 -32.473057) (xy 419.077429 -32.516963) (xy 419.162952 -32.568011)
			(xy 419.244028 -32.62586) (xy 419.32012 -32.690126) (xy 419.390719 -32.76038) (xy 419.455357 -32.836156)
			(xy 419.513603 -32.916948) (xy 419.565069 -33.00222) (xy 419.609413 -33.091402) (xy 419.64634 -33.183903)
			(xy 419.675603 -33.279106) (xy 419.697009 -33.376378) (xy 419.710414 -33.475071) (xy 419.715729 -33.574528)
			(xy 419.71292 -33.674087) (xy 419.702004 -33.773087) (xy 419.683055 -33.870866) (xy 419.656198 -33.966776)
			(xy 419.621612 -34.060177) (xy 419.579528 -34.150449) (xy 419.530226 -34.236989) (xy 419.474033 -34.319222)
			(xy 419.411324 -34.396602) (xy 419.342515 -34.468611) (xy 419.268066 -34.534773) (xy 419.188472 -34.594645)
			(xy 419.104262 -34.64783) (xy 419.015997 -34.693974) (xy 418.924264 -34.732769) (xy 418.829674 -34.763957)
			(xy 418.732856 -34.787331) (xy 418.634456 -34.802735) (xy 418.535127 -34.810066) (xy 418.435531 -34.809277)
			(xy 418.336331 -34.800371) (xy 418.238187 -34.783409) (xy 418.141752 -34.758503) (xy 418.047668 -34.725818)
			(xy 417.956562 -34.685574) (xy 417.86904 -34.638036) (xy 417.785684 -34.583523) (xy 417.707048 -34.522396)
			(xy 417.66998 -34.489136) (xy 417.653775 -34.474904) (xy 417.617522 -34.45155) (xy 417.577848 -34.434647)
			(xy 417.535891 -34.424679) (xy 417.492855 -34.421931) (xy 417.449971 -34.426482) (xy 417.40847 -34.438202)
			(xy 417.36954 -34.456755) (xy 417.334298 -34.48161) (xy 417.318698 -34.496502) (xy 416.814 -35.0012)
			(xy 387.5024 -35.0012) (xy 387.296914 -34.795714) (xy 387.258306 -34.788348) (xy 387.21057 -34.778837)
			(xy 387.116669 -34.753184) (xy 387.025111 -34.720126) (xy 386.93648 -34.679874) (xy 386.85134 -34.632685)
			(xy 386.770233 -34.578859) (xy 386.693675 -34.518738) (xy 386.622154 -34.452705) (xy 386.556124 -34.38118)
			(xy 386.496007 -34.30462) (xy 386.442185 -34.22351) (xy 386.394999 -34.138368) (xy 386.354752 -34.049735)
			(xy 386.321699 -33.958176) (xy 386.29605 -33.864273) (xy 386.286502 -33.816544) (xy 386.279136 -33.777936)
			(xy 380.5174 -28.0162) (xy 377.491752 -28.0162) (xy 377.405138 -28.051252) (xy 377.389136 -28.064968)
			(xy 377.369148 -28.081704) (xy 377.325473 -28.110167) (xy 377.278329 -28.13242) (xy 377.228595 -28.148047)
			(xy 377.177197 -28.156759) (xy 377.125091 -28.158393) (xy 377.073248 -28.152918) (xy 377.022633 -28.140436)
			(xy 376.99823 -28.131262) (xy 376.975624 -28.122372) (xy 371.219222 -28.122372) (xy 371.11305 -28.0162)
			(xy 368.9604 -28.0162) (xy 365.4298 -24.4856) (xy 358.77881 -24.4856) (xy 358.762167 -24.48612) (xy 358.730026 -24.494785)
			(xy 358.701224 -24.511474) (xy 358.689148 -24.522938) (xy 357.948738 -25.263348) (xy 355.762052 -25.263348)
			(xy 351.663 -29.3624) (xy 351.663 -29.859732) (xy 378.662182 -29.859732) (xy 378.666253 -29.80411)
			(xy 378.678379 -29.749673) (xy 378.698302 -29.697582) (xy 378.725598 -29.648947) (xy 378.759684 -29.604804)
			(xy 378.799833 -29.566095) (xy 378.845191 -29.533644) (xy 378.894791 -29.508143) (xy 378.947575 -29.490136)
			(xy 379.002418 -29.480006) (xy 379.058152 -29.477969) (xy 379.113589 -29.484069) (xy 379.167546 -29.498175)
			(xy 379.218875 -29.519987) (xy 379.266481 -29.549041) (xy 379.309349 -29.584716) (xy 379.346566 -29.626253)
			(xy 379.377339 -29.672766) (xy 379.401011 -29.723263) (xy 379.417079 -29.77667) (xy 379.425199 -29.831846)
			(xy 379.425708 -29.859732) (xy 379.425199 -29.887618) (xy 379.417079 -29.942794) (xy 379.401011 -29.996201)
			(xy 379.377339 -30.046698) (xy 379.346566 -30.093211) (xy 379.309349 -30.134748) (xy 379.266481 -30.170423)
			(xy 379.218875 -30.199477) (xy 379.167546 -30.221289) (xy 379.113589 -30.235395) (xy 379.058152 -30.241495)
			(xy 379.002418 -30.239458) (xy 378.947575 -30.229328) (xy 378.894791 -30.211321) (xy 378.845191 -30.18582)
			(xy 378.799833 -30.153369) (xy 378.759684 -30.11466) (xy 378.725598 -30.070517) (xy 378.698302 -30.021882)
			(xy 378.678379 -29.969791) (xy 378.666253 -29.915354) (xy 378.662182 -29.859732) (xy 351.663 -29.859732)
			(xy 351.663 -32.094932) (xy 378.59665 -32.094932) (xy 378.600721 -32.03931) (xy 378.612847 -31.984873)
			(xy 378.63277 -31.932782) (xy 378.660066 -31.884147) (xy 378.694152 -31.840004) (xy 378.734301 -31.801295)
			(xy 378.779659 -31.768844) (xy 378.829259 -31.743343) (xy 378.882043 -31.725336) (xy 378.936886 -31.715206)
			(xy 378.99262 -31.713169) (xy 379.048057 -31.719269) (xy 379.102014 -31.733375) (xy 379.153343 -31.755187)
			(xy 379.200949 -31.784241) (xy 379.243817 -31.819916) (xy 379.281034 -31.861453) (xy 379.311807 -31.907966)
			(xy 379.335479 -31.958463) (xy 379.351547 -32.01187) (xy 379.359667 -32.067046) (xy 379.360176 -32.094932)
			(xy 379.359667 -32.122818) (xy 379.351547 -32.177994) (xy 379.335479 -32.231401) (xy 379.311807 -32.281898)
			(xy 379.281034 -32.328411) (xy 379.243817 -32.369948) (xy 379.200949 -32.405623) (xy 379.153343 -32.434677)
			(xy 379.102014 -32.456489) (xy 379.048057 -32.470595) (xy 378.99262 -32.476695) (xy 378.936886 -32.474658)
			(xy 378.882043 -32.464528) (xy 378.829259 -32.446521) (xy 378.779659 -32.42102) (xy 378.734301 -32.388569)
			(xy 378.694152 -32.34986) (xy 378.660066 -32.305717) (xy 378.63277 -32.257082) (xy 378.612847 -32.204991)
			(xy 378.600721 -32.150554) (xy 378.59665 -32.094932) (xy 351.663 -32.094932) (xy 351.663 -37.338)
			(xy 377.468382 -37.338) (xy 377.472453 -37.282378) (xy 377.484579 -37.227941) (xy 377.504502 -37.17585)
			(xy 377.531798 -37.127215) (xy 377.565884 -37.083072) (xy 377.606033 -37.044363) (xy 377.651391 -37.011912)
			(xy 377.700991 -36.986411) (xy 377.753775 -36.968404) (xy 377.808618 -36.958274) (xy 377.864352 -36.956237)
			(xy 377.919789 -36.962337) (xy 377.973746 -36.976443) (xy 378.025075 -36.998255) (xy 378.072681 -37.027309)
			(xy 378.115549 -37.062984) (xy 378.152766 -37.104521) (xy 378.183539 -37.151034) (xy 378.207211 -37.201531)
			(xy 378.223279 -37.254938) (xy 378.231399 -37.310114) (xy 378.231908 -37.338) (xy 378.231399 -37.365886)
			(xy 378.223279 -37.421062) (xy 378.207211 -37.474469) (xy 378.183539 -37.524966) (xy 378.172799 -37.5412)
			(xy 379.551182 -37.5412) (xy 379.555253 -37.485578) (xy 379.567379 -37.431141) (xy 379.587302 -37.37905)
			(xy 379.614598 -37.330415) (xy 379.648684 -37.286272) (xy 379.688833 -37.247563) (xy 379.734191 -37.215112)
			(xy 379.783791 -37.189611) (xy 379.836575 -37.171604) (xy 379.891418 -37.161474) (xy 379.947152 -37.159437)
			(xy 380.002589 -37.165537) (xy 380.056546 -37.179643) (xy 380.107875 -37.201455) (xy 380.155481 -37.230509)
			(xy 380.198349 -37.266184) (xy 380.235566 -37.307721) (xy 380.266339 -37.354234) (xy 380.290011 -37.404731)
			(xy 380.306079 -37.458138) (xy 380.314199 -37.513314) (xy 380.314708 -37.5412) (xy 380.314199 -37.569086)
			(xy 380.306079 -37.624262) (xy 380.290011 -37.677669) (xy 380.266339 -37.728166) (xy 380.235566 -37.774679)
			(xy 380.198349 -37.816216) (xy 380.155481 -37.851891) (xy 380.107875 -37.880945) (xy 380.056546 -37.902757)
			(xy 380.002589 -37.916863) (xy 379.947152 -37.922963) (xy 379.891418 -37.920926) (xy 379.836575 -37.910796)
			(xy 379.783791 -37.892789) (xy 379.734191 -37.867288) (xy 379.688833 -37.834837) (xy 379.648684 -37.796128)
			(xy 379.614598 -37.751985) (xy 379.587302 -37.70335) (xy 379.567379 -37.651259) (xy 379.555253 -37.596822)
			(xy 379.551182 -37.5412) (xy 378.172799 -37.5412) (xy 378.152766 -37.571479) (xy 378.115549 -37.613016)
			(xy 378.072681 -37.648691) (xy 378.025075 -37.677745) (xy 377.973746 -37.699557) (xy 377.919789 -37.713663)
			(xy 377.864352 -37.719763) (xy 377.808618 -37.717726) (xy 377.753775 -37.707596) (xy 377.700991 -37.689589)
			(xy 377.651391 -37.664088) (xy 377.606033 -37.631637) (xy 377.565884 -37.592928) (xy 377.531798 -37.548785)
			(xy 377.504502 -37.50015) (xy 377.484579 -37.448059) (xy 377.472453 -37.393622) (xy 377.468382 -37.338)
			(xy 351.663 -37.338) (xy 351.663 -38.7604) (xy 350.0882 -40.3352) (xy 341.3506 -40.3352) (xy 336.9564 -35.941)
			(xy 335.153 -35.941) (xy 331.541628 -32.329628) (xy 322.184776 -32.329628) (xy 318.237616 -36.276788)
			(xy 309.856124 -36.276788) (xy 309.833531 -36.277285) (xy 309.789057 -36.285282) (xy 309.746697 -36.301012)
			(xy 309.707782 -36.32398) (xy 309.673538 -36.353462) (xy 309.645042 -36.388531) (xy 309.623191 -36.428083)
			(xy 309.608672 -36.470874) (xy 309.601943 -36.515557) (xy 309.602124 -36.538154) (xy 309.602438 -36.565911)
			(xy 309.596005 -36.621044) (xy 309.581648 -36.674663) (xy 309.55967 -36.725635) (xy 309.530536 -36.772882)
			(xy 309.494862 -36.815408) (xy 309.4534 -36.852313) (xy 309.407026 -36.882819) (xy 309.35672 -36.90628)
			(xy 309.303545 -36.922202) (xy 309.248624 -36.930248) (xy 309.193116 -36.930248) (xy 309.138195 -36.922202)
			(xy 309.08502 -36.90628) (xy 309.034714 -36.882819) (xy 308.98834 -36.852313) (xy 308.946878 -36.815408)
			(xy 308.911204 -36.772882) (xy 308.88207 -36.725635) (xy 308.860092 -36.674663) (xy 308.845735 -36.621044)
			(xy 308.839302 -36.565911) (xy 308.839616 -36.538154) (xy 308.839787 -36.51555) (xy 308.833099 -36.470849)
			(xy 308.818607 -36.428036) (xy 308.796768 -36.388463) (xy 308.768273 -36.353379) (xy 308.734018 -36.32389)
			(xy 308.695087 -36.300928) (xy 308.652707 -36.285216) (xy 308.608216 -36.277251) (xy 308.585616 -36.276788)
			(xy 308.218332 -36.276788) (xy 308.19502 -36.277284) (xy 308.149169 -36.28573) (xy 308.105628 -36.302401)
			(xy 308.065861 -36.326735) (xy 308.0312 -36.357918) (xy 308.002811 -36.3949) (xy 307.981646 -36.436442)
			(xy 307.968415 -36.481148) (xy 307.963564 -36.527518) (xy 307.967254 -36.573994) (xy 307.979362 -36.619017)
			(xy 307.98897 -36.640262) (xy 308.000377 -36.665264) (xy 308.016693 -36.71774) (xy 308.025309 -36.772014)
			(xy 308.026047 -36.826963) (xy 308.01889 -36.881449) (xy 308.003988 -36.934343) (xy 307.981648 -36.984552)
			(xy 307.952334 -37.031034) (xy 307.916651 -37.072828) (xy 307.87534 -37.109067) (xy 307.829256 -37.139003)
			(xy 307.779352 -37.162014) (xy 307.726662 -37.177625) (xy 307.672277 -37.185512) (xy 307.617323 -37.185512)
			(xy 307.562938 -37.177625) (xy 307.510248 -37.162014) (xy 307.460344 -37.139003) (xy 307.41426 -37.109067)
			(xy 307.372949 -37.072828) (xy 307.337266 -37.031034) (xy 307.307952 -36.984552) (xy 307.285612 -36.934343)
			(xy 307.27071 -36.881449) (xy 307.263553 -36.826963) (xy 307.264291 -36.772014) (xy 307.272907 -36.71774)
			(xy 307.289223 -36.665264) (xy 307.30063 -36.640262) (xy 307.310198 -36.619006) (xy 307.322278 -36.573989)
			(xy 307.325947 -36.527525) (xy 307.321084 -36.48117) (xy 307.30785 -36.43648) (xy 307.28669 -36.394951)
			(xy 307.258314 -36.357975) (xy 307.223671 -36.326794) (xy 307.183924 -36.302451) (xy 307.140405 -36.285763)
			(xy 307.094573 -36.277289) (xy 307.071268 -36.276788) (xy 206.563976 -36.276788) (xy 204.095503 -38.745261)
			(xy 216.636592 -38.745261) (xy 216.636592 -38.673939) (xy 216.644578 -38.603065) (xy 216.660448 -38.53353)
			(xy 216.684005 -38.46621) (xy 216.71495 -38.401951) (xy 216.752896 -38.34156) (xy 216.797365 -38.285798)
			(xy 216.847798 -38.235365) (xy 216.90356 -38.190896) (xy 216.963951 -38.15295) (xy 217.02821 -38.122005)
			(xy 217.09553 -38.098448) (xy 217.165065 -38.082578) (xy 217.235939 -38.074592) (xy 217.307261 -38.074592)
			(xy 217.378135 -38.082578) (xy 217.44767 -38.098448) (xy 217.51499 -38.122005) (xy 217.579249 -38.15295)
			(xy 217.63964 -38.190896) (xy 217.695402 -38.235365) (xy 217.745835 -38.285798) (xy 217.790304 -38.34156)
			(xy 217.82825 -38.401951) (xy 217.859195 -38.46621) (xy 217.882752 -38.53353) (xy 217.898622 -38.603065)
			(xy 217.906608 -38.673939) (xy 217.907108 -38.7096) (xy 217.906608 -38.745261) (xy 224.256592 -38.745261)
			(xy 224.256592 -38.673939) (xy 224.264578 -38.603065) (xy 224.280448 -38.53353) (xy 224.304005 -38.46621)
			(xy 224.33495 -38.401951) (xy 224.372896 -38.34156) (xy 224.417365 -38.285798) (xy 224.467798 -38.235365)
			(xy 224.52356 -38.190896) (xy 224.583951 -38.15295) (xy 224.64821 -38.122005) (xy 224.71553 -38.098448)
			(xy 224.785065 -38.082578) (xy 224.855939 -38.074592) (xy 224.927261 -38.074592) (xy 224.998135 -38.082578)
			(xy 225.06767 -38.098448) (xy 225.13499 -38.122005) (xy 225.199249 -38.15295) (xy 225.25964 -38.190896)
			(xy 225.315402 -38.235365) (xy 225.365835 -38.285798) (xy 225.410304 -38.34156) (xy 225.44825 -38.401951)
			(xy 225.479195 -38.46621) (xy 225.502752 -38.53353) (xy 225.518622 -38.603065) (xy 225.526608 -38.673939)
			(xy 225.527108 -38.7096) (xy 225.526608 -38.745261) (xy 231.876592 -38.745261) (xy 231.876592 -38.673939)
			(xy 231.884578 -38.603065) (xy 231.900448 -38.53353) (xy 231.924005 -38.46621) (xy 231.95495 -38.401951)
			(xy 231.992896 -38.34156) (xy 232.037365 -38.285798) (xy 232.087798 -38.235365) (xy 232.14356 -38.190896)
			(xy 232.203951 -38.15295) (xy 232.26821 -38.122005) (xy 232.33553 -38.098448) (xy 232.405065 -38.082578)
			(xy 232.475939 -38.074592) (xy 232.547261 -38.074592) (xy 232.618135 -38.082578) (xy 232.68767 -38.098448)
			(xy 232.75499 -38.122005) (xy 232.819249 -38.15295) (xy 232.87964 -38.190896) (xy 232.935402 -38.235365)
			(xy 232.985835 -38.285798) (xy 233.030304 -38.34156) (xy 233.06825 -38.401951) (xy 233.099195 -38.46621)
			(xy 233.122752 -38.53353) (xy 233.138622 -38.603065) (xy 233.146608 -38.673939) (xy 233.147108 -38.7096)
			(xy 233.146608 -38.745261) (xy 239.496592 -38.745261) (xy 239.496592 -38.673939) (xy 239.504578 -38.603065)
			(xy 239.520448 -38.53353) (xy 239.544005 -38.46621) (xy 239.57495 -38.401951) (xy 239.612896 -38.34156)
			(xy 239.657365 -38.285798) (xy 239.707798 -38.235365) (xy 239.76356 -38.190896) (xy 239.823951 -38.15295)
			(xy 239.88821 -38.122005) (xy 239.95553 -38.098448) (xy 240.025065 -38.082578) (xy 240.095939 -38.074592)
			(xy 240.167261 -38.074592) (xy 240.238135 -38.082578) (xy 240.30767 -38.098448) (xy 240.37499 -38.122005)
			(xy 240.439249 -38.15295) (xy 240.49964 -38.190896) (xy 240.555402 -38.235365) (xy 240.605835 -38.285798)
			(xy 240.650304 -38.34156) (xy 240.68825 -38.401951) (xy 240.719195 -38.46621) (xy 240.742752 -38.53353)
			(xy 240.758622 -38.603065) (xy 240.766608 -38.673939) (xy 240.767108 -38.7096) (xy 240.766608 -38.745261)
			(xy 247.116592 -38.745261) (xy 247.116592 -38.673939) (xy 247.124578 -38.603065) (xy 247.140448 -38.53353)
			(xy 247.164005 -38.46621) (xy 247.19495 -38.401951) (xy 247.232896 -38.34156) (xy 247.277365 -38.285798)
			(xy 247.327798 -38.235365) (xy 247.38356 -38.190896) (xy 247.443951 -38.15295) (xy 247.50821 -38.122005)
			(xy 247.57553 -38.098448) (xy 247.645065 -38.082578) (xy 247.715939 -38.074592) (xy 247.787261 -38.074592)
			(xy 247.858135 -38.082578) (xy 247.92767 -38.098448) (xy 247.99499 -38.122005) (xy 248.059249 -38.15295)
			(xy 248.11964 -38.190896) (xy 248.175402 -38.235365) (xy 248.225835 -38.285798) (xy 248.270304 -38.34156)
			(xy 248.30825 -38.401951) (xy 248.339195 -38.46621) (xy 248.362752 -38.53353) (xy 248.378622 -38.603065)
			(xy 248.386608 -38.673939) (xy 248.387108 -38.7096) (xy 248.386608 -38.745261) (xy 254.736592 -38.745261)
			(xy 254.736592 -38.673939) (xy 254.744578 -38.603065) (xy 254.760448 -38.53353) (xy 254.784005 -38.46621)
			(xy 254.81495 -38.401951) (xy 254.852896 -38.34156) (xy 254.897365 -38.285798) (xy 254.947798 -38.235365)
			(xy 255.00356 -38.190896) (xy 255.063951 -38.15295) (xy 255.12821 -38.122005) (xy 255.19553 -38.098448)
			(xy 255.265065 -38.082578) (xy 255.335939 -38.074592) (xy 255.407261 -38.074592) (xy 255.478135 -38.082578)
			(xy 255.54767 -38.098448) (xy 255.61499 -38.122005) (xy 255.679249 -38.15295) (xy 255.73964 -38.190896)
			(xy 255.795402 -38.235365) (xy 255.845835 -38.285798) (xy 255.890304 -38.34156) (xy 255.92825 -38.401951)
			(xy 255.959195 -38.46621) (xy 255.982752 -38.53353) (xy 255.998622 -38.603065) (xy 256.006608 -38.673939)
			(xy 256.007108 -38.7096) (xy 256.006608 -38.745261) (xy 262.356592 -38.745261) (xy 262.356592 -38.673939)
			(xy 262.364578 -38.603065) (xy 262.380448 -38.53353) (xy 262.404005 -38.46621) (xy 262.43495 -38.401951)
			(xy 262.472896 -38.34156) (xy 262.517365 -38.285798) (xy 262.567798 -38.235365) (xy 262.62356 -38.190896)
			(xy 262.683951 -38.15295) (xy 262.74821 -38.122005) (xy 262.81553 -38.098448) (xy 262.885065 -38.082578)
			(xy 262.955939 -38.074592) (xy 263.027261 -38.074592) (xy 263.098135 -38.082578) (xy 263.16767 -38.098448)
			(xy 263.23499 -38.122005) (xy 263.299249 -38.15295) (xy 263.35964 -38.190896) (xy 263.415402 -38.235365)
			(xy 263.465835 -38.285798) (xy 263.510304 -38.34156) (xy 263.54825 -38.401951) (xy 263.579195 -38.46621)
			(xy 263.602752 -38.53353) (xy 263.618622 -38.603065) (xy 263.626608 -38.673939) (xy 263.627108 -38.7096)
			(xy 263.626608 -38.745261) (xy 269.976592 -38.745261) (xy 269.976592 -38.673939) (xy 269.984578 -38.603065)
			(xy 270.000448 -38.53353) (xy 270.024005 -38.46621) (xy 270.05495 -38.401951) (xy 270.092896 -38.34156)
			(xy 270.137365 -38.285798) (xy 270.187798 -38.235365) (xy 270.24356 -38.190896) (xy 270.303951 -38.15295)
			(xy 270.36821 -38.122005) (xy 270.43553 -38.098448) (xy 270.505065 -38.082578) (xy 270.575939 -38.074592)
			(xy 270.647261 -38.074592) (xy 270.718135 -38.082578) (xy 270.78767 -38.098448) (xy 270.85499 -38.122005)
			(xy 270.919249 -38.15295) (xy 270.97964 -38.190896) (xy 271.035402 -38.235365) (xy 271.085835 -38.285798)
			(xy 271.130304 -38.34156) (xy 271.16825 -38.401951) (xy 271.199195 -38.46621) (xy 271.222752 -38.53353)
			(xy 271.238622 -38.603065) (xy 271.246608 -38.673939) (xy 271.247108 -38.7096) (xy 271.246608 -38.745261)
			(xy 277.596592 -38.745261) (xy 277.596592 -38.673939) (xy 277.604578 -38.603065) (xy 277.620448 -38.53353)
			(xy 277.644005 -38.46621) (xy 277.67495 -38.401951) (xy 277.712896 -38.34156) (xy 277.757365 -38.285798)
			(xy 277.807798 -38.235365) (xy 277.86356 -38.190896) (xy 277.923951 -38.15295) (xy 277.98821 -38.122005)
			(xy 278.05553 -38.098448) (xy 278.125065 -38.082578) (xy 278.195939 -38.074592) (xy 278.267261 -38.074592)
			(xy 278.338135 -38.082578) (xy 278.40767 -38.098448) (xy 278.47499 -38.122005) (xy 278.539249 -38.15295)
			(xy 278.59964 -38.190896) (xy 278.655402 -38.235365) (xy 278.705835 -38.285798) (xy 278.750304 -38.34156)
			(xy 278.78825 -38.401951) (xy 278.819195 -38.46621) (xy 278.842752 -38.53353) (xy 278.858622 -38.603065)
			(xy 278.866608 -38.673939) (xy 278.867108 -38.7096) (xy 278.866608 -38.745261) (xy 285.216592 -38.745261)
			(xy 285.216592 -38.673939) (xy 285.224578 -38.603065) (xy 285.240448 -38.53353) (xy 285.264005 -38.46621)
			(xy 285.29495 -38.401951) (xy 285.332896 -38.34156) (xy 285.377365 -38.285798) (xy 285.427798 -38.235365)
			(xy 285.48356 -38.190896) (xy 285.543951 -38.15295) (xy 285.60821 -38.122005) (xy 285.67553 -38.098448)
			(xy 285.745065 -38.082578) (xy 285.815939 -38.074592) (xy 285.887261 -38.074592) (xy 285.958135 -38.082578)
			(xy 286.02767 -38.098448) (xy 286.09499 -38.122005) (xy 286.159249 -38.15295) (xy 286.21964 -38.190896)
			(xy 286.275402 -38.235365) (xy 286.325835 -38.285798) (xy 286.370304 -38.34156) (xy 286.40825 -38.401951)
			(xy 286.439195 -38.46621) (xy 286.462752 -38.53353) (xy 286.478622 -38.603065) (xy 286.486608 -38.673939)
			(xy 286.487108 -38.7096) (xy 286.486608 -38.745261) (xy 292.836592 -38.745261) (xy 292.836592 -38.673939)
			(xy 292.844578 -38.603065) (xy 292.860448 -38.53353) (xy 292.884005 -38.46621) (xy 292.91495 -38.401951)
			(xy 292.952896 -38.34156) (xy 292.997365 -38.285798) (xy 293.047798 -38.235365) (xy 293.10356 -38.190896)
			(xy 293.163951 -38.15295) (xy 293.22821 -38.122005) (xy 293.29553 -38.098448) (xy 293.365065 -38.082578)
			(xy 293.435939 -38.074592) (xy 293.507261 -38.074592) (xy 293.578135 -38.082578) (xy 293.64767 -38.098448)
			(xy 293.71499 -38.122005) (xy 293.779249 -38.15295) (xy 293.83964 -38.190896) (xy 293.895402 -38.235365)
			(xy 293.945835 -38.285798) (xy 293.990304 -38.34156) (xy 294.02825 -38.401951) (xy 294.059195 -38.46621)
			(xy 294.082752 -38.53353) (xy 294.098622 -38.603065) (xy 294.106608 -38.673939) (xy 294.107108 -38.7096)
			(xy 294.106608 -38.745261) (xy 294.098622 -38.816135) (xy 294.082752 -38.88567) (xy 294.059195 -38.95299)
			(xy 294.02825 -39.017249) (xy 293.990304 -39.07764) (xy 293.945835 -39.133402) (xy 293.895402 -39.183835)
			(xy 293.83964 -39.228304) (xy 293.779249 -39.26625) (xy 293.71499 -39.297195) (xy 293.64767 -39.320752)
			(xy 293.578135 -39.336622) (xy 293.507261 -39.344608) (xy 293.435939 -39.344608) (xy 293.365065 -39.336622)
			(xy 293.29553 -39.320752) (xy 293.22821 -39.297195) (xy 293.163951 -39.26625) (xy 293.10356 -39.228304)
			(xy 293.047798 -39.183835) (xy 292.997365 -39.133402) (xy 292.952896 -39.07764) (xy 292.91495 -39.017249)
			(xy 292.884005 -38.95299) (xy 292.860448 -38.88567) (xy 292.844578 -38.816135) (xy 292.836592 -38.745261)
			(xy 286.486608 -38.745261) (xy 286.478622 -38.816135) (xy 286.462752 -38.88567) (xy 286.439195 -38.95299)
			(xy 286.40825 -39.017249) (xy 286.370304 -39.07764) (xy 286.325835 -39.133402) (xy 286.275402 -39.183835)
			(xy 286.21964 -39.228304) (xy 286.159249 -39.26625) (xy 286.09499 -39.297195) (xy 286.02767 -39.320752)
			(xy 285.958135 -39.336622) (xy 285.887261 -39.344608) (xy 285.815939 -39.344608) (xy 285.745065 -39.336622)
			(xy 285.67553 -39.320752) (xy 285.60821 -39.297195) (xy 285.543951 -39.26625) (xy 285.48356 -39.228304)
			(xy 285.427798 -39.183835) (xy 285.377365 -39.133402) (xy 285.332896 -39.07764) (xy 285.29495 -39.017249)
			(xy 285.264005 -38.95299) (xy 285.240448 -38.88567) (xy 285.224578 -38.816135) (xy 285.216592 -38.745261)
			(xy 278.866608 -38.745261) (xy 278.858622 -38.816135) (xy 278.842752 -38.88567) (xy 278.819195 -38.95299)
			(xy 278.78825 -39.017249) (xy 278.750304 -39.07764) (xy 278.705835 -39.133402) (xy 278.655402 -39.183835)
			(xy 278.59964 -39.228304) (xy 278.539249 -39.26625) (xy 278.47499 -39.297195) (xy 278.40767 -39.320752)
			(xy 278.338135 -39.336622) (xy 278.267261 -39.344608) (xy 278.195939 -39.344608) (xy 278.125065 -39.336622)
			(xy 278.05553 -39.320752) (xy 277.98821 -39.297195) (xy 277.923951 -39.26625) (xy 277.86356 -39.228304)
			(xy 277.807798 -39.183835) (xy 277.757365 -39.133402) (xy 277.712896 -39.07764) (xy 277.67495 -39.017249)
			(xy 277.644005 -38.95299) (xy 277.620448 -38.88567) (xy 277.604578 -38.816135) (xy 277.596592 -38.745261)
			(xy 271.246608 -38.745261) (xy 271.238622 -38.816135) (xy 271.222752 -38.88567) (xy 271.199195 -38.95299)
			(xy 271.16825 -39.017249) (xy 271.130304 -39.07764) (xy 271.085835 -39.133402) (xy 271.035402 -39.183835)
			(xy 270.97964 -39.228304) (xy 270.919249 -39.26625) (xy 270.85499 -39.297195) (xy 270.78767 -39.320752)
			(xy 270.718135 -39.336622) (xy 270.647261 -39.344608) (xy 270.575939 -39.344608) (xy 270.505065 -39.336622)
			(xy 270.43553 -39.320752) (xy 270.36821 -39.297195) (xy 270.303951 -39.26625) (xy 270.24356 -39.228304)
			(xy 270.187798 -39.183835) (xy 270.137365 -39.133402) (xy 270.092896 -39.07764) (xy 270.05495 -39.017249)
			(xy 270.024005 -38.95299) (xy 270.000448 -38.88567) (xy 269.984578 -38.816135) (xy 269.976592 -38.745261)
			(xy 263.626608 -38.745261) (xy 263.618622 -38.816135) (xy 263.602752 -38.88567) (xy 263.579195 -38.95299)
			(xy 263.54825 -39.017249) (xy 263.510304 -39.07764) (xy 263.465835 -39.133402) (xy 263.415402 -39.183835)
			(xy 263.35964 -39.228304) (xy 263.299249 -39.26625) (xy 263.23499 -39.297195) (xy 263.16767 -39.320752)
			(xy 263.098135 -39.336622) (xy 263.027261 -39.344608) (xy 262.955939 -39.344608) (xy 262.885065 -39.336622)
			(xy 262.81553 -39.320752) (xy 262.74821 -39.297195) (xy 262.683951 -39.26625) (xy 262.62356 -39.228304)
			(xy 262.567798 -39.183835) (xy 262.517365 -39.133402) (xy 262.472896 -39.07764) (xy 262.43495 -39.017249)
			(xy 262.404005 -38.95299) (xy 262.380448 -38.88567) (xy 262.364578 -38.816135) (xy 262.356592 -38.745261)
			(xy 256.006608 -38.745261) (xy 255.998622 -38.816135) (xy 255.982752 -38.88567) (xy 255.959195 -38.95299)
			(xy 255.92825 -39.017249) (xy 255.890304 -39.07764) (xy 255.845835 -39.133402) (xy 255.795402 -39.183835)
			(xy 255.73964 -39.228304) (xy 255.679249 -39.26625) (xy 255.61499 -39.297195) (xy 255.54767 -39.320752)
			(xy 255.478135 -39.336622) (xy 255.407261 -39.344608) (xy 255.335939 -39.344608) (xy 255.265065 -39.336622)
			(xy 255.19553 -39.320752) (xy 255.12821 -39.297195) (xy 255.063951 -39.26625) (xy 255.00356 -39.228304)
			(xy 254.947798 -39.183835) (xy 254.897365 -39.133402) (xy 254.852896 -39.07764) (xy 254.81495 -39.017249)
			(xy 254.784005 -38.95299) (xy 254.760448 -38.88567) (xy 254.744578 -38.816135) (xy 254.736592 -38.745261)
			(xy 248.386608 -38.745261) (xy 248.378622 -38.816135) (xy 248.362752 -38.88567) (xy 248.339195 -38.95299)
			(xy 248.30825 -39.017249) (xy 248.270304 -39.07764) (xy 248.225835 -39.133402) (xy 248.175402 -39.183835)
			(xy 248.11964 -39.228304) (xy 248.059249 -39.26625) (xy 247.99499 -39.297195) (xy 247.92767 -39.320752)
			(xy 247.858135 -39.336622) (xy 247.787261 -39.344608) (xy 247.715939 -39.344608) (xy 247.645065 -39.336622)
			(xy 247.57553 -39.320752) (xy 247.50821 -39.297195) (xy 247.443951 -39.26625) (xy 247.38356 -39.228304)
			(xy 247.327798 -39.183835) (xy 247.277365 -39.133402) (xy 247.232896 -39.07764) (xy 247.19495 -39.017249)
			(xy 247.164005 -38.95299) (xy 247.140448 -38.88567) (xy 247.124578 -38.816135) (xy 247.116592 -38.745261)
			(xy 240.766608 -38.745261) (xy 240.758622 -38.816135) (xy 240.742752 -38.88567) (xy 240.719195 -38.95299)
			(xy 240.68825 -39.017249) (xy 240.650304 -39.07764) (xy 240.605835 -39.133402) (xy 240.555402 -39.183835)
			(xy 240.49964 -39.228304) (xy 240.439249 -39.26625) (xy 240.37499 -39.297195) (xy 240.30767 -39.320752)
			(xy 240.238135 -39.336622) (xy 240.167261 -39.344608) (xy 240.095939 -39.344608) (xy 240.025065 -39.336622)
			(xy 239.95553 -39.320752) (xy 239.88821 -39.297195) (xy 239.823951 -39.26625) (xy 239.76356 -39.228304)
			(xy 239.707798 -39.183835) (xy 239.657365 -39.133402) (xy 239.612896 -39.07764) (xy 239.57495 -39.017249)
			(xy 239.544005 -38.95299) (xy 239.520448 -38.88567) (xy 239.504578 -38.816135) (xy 239.496592 -38.745261)
			(xy 233.146608 -38.745261) (xy 233.138622 -38.816135) (xy 233.122752 -38.88567) (xy 233.099195 -38.95299)
			(xy 233.06825 -39.017249) (xy 233.030304 -39.07764) (xy 232.985835 -39.133402) (xy 232.935402 -39.183835)
			(xy 232.87964 -39.228304) (xy 232.819249 -39.26625) (xy 232.75499 -39.297195) (xy 232.68767 -39.320752)
			(xy 232.618135 -39.336622) (xy 232.547261 -39.344608) (xy 232.475939 -39.344608) (xy 232.405065 -39.336622)
			(xy 232.33553 -39.320752) (xy 232.26821 -39.297195) (xy 232.203951 -39.26625) (xy 232.14356 -39.228304)
			(xy 232.087798 -39.183835) (xy 232.037365 -39.133402) (xy 231.992896 -39.07764) (xy 231.95495 -39.017249)
			(xy 231.924005 -38.95299) (xy 231.900448 -38.88567) (xy 231.884578 -38.816135) (xy 231.876592 -38.745261)
			(xy 225.526608 -38.745261) (xy 225.518622 -38.816135) (xy 225.502752 -38.88567) (xy 225.479195 -38.95299)
			(xy 225.44825 -39.017249) (xy 225.410304 -39.07764) (xy 225.365835 -39.133402) (xy 225.315402 -39.183835)
			(xy 225.25964 -39.228304) (xy 225.199249 -39.26625) (xy 225.13499 -39.297195) (xy 225.06767 -39.320752)
			(xy 224.998135 -39.336622) (xy 224.927261 -39.344608) (xy 224.855939 -39.344608) (xy 224.785065 -39.336622)
			(xy 224.71553 -39.320752) (xy 224.64821 -39.297195) (xy 224.583951 -39.26625) (xy 224.52356 -39.228304)
			(xy 224.467798 -39.183835) (xy 224.417365 -39.133402) (xy 224.372896 -39.07764) (xy 224.33495 -39.017249)
			(xy 224.304005 -38.95299) (xy 224.280448 -38.88567) (xy 224.264578 -38.816135) (xy 224.256592 -38.745261)
			(xy 217.906608 -38.745261) (xy 217.898622 -38.816135) (xy 217.882752 -38.88567) (xy 217.859195 -38.95299)
			(xy 217.82825 -39.017249) (xy 217.790304 -39.07764) (xy 217.745835 -39.133402) (xy 217.695402 -39.183835)
			(xy 217.63964 -39.228304) (xy 217.579249 -39.26625) (xy 217.51499 -39.297195) (xy 217.44767 -39.320752)
			(xy 217.378135 -39.336622) (xy 217.307261 -39.344608) (xy 217.235939 -39.344608) (xy 217.165065 -39.336622)
			(xy 217.09553 -39.320752) (xy 217.02821 -39.297195) (xy 216.963951 -39.26625) (xy 216.90356 -39.228304)
			(xy 216.847798 -39.183835) (xy 216.797365 -39.133402) (xy 216.752896 -39.07764) (xy 216.71495 -39.017249)
			(xy 216.684005 -38.95299) (xy 216.660448 -38.88567) (xy 216.644578 -38.816135) (xy 216.636592 -38.745261)
			(xy 204.095503 -38.745261) (xy 203.338176 -39.502588) (xy 203.3016 -39.53891) (xy 202.95489 -39.53891)
			(xy 202.946 -39.5478) (xy 136.0424 -39.5478) (xy 132.1562 -43.434) (xy 131.20878 -43.434) (xy 131.186398 -43.434466)
			(xy 131.142326 -43.442298) (xy 131.100308 -43.457732) (xy 131.061645 -43.480292) (xy 131.027535 -43.509279)
			(xy 130.999034 -43.543796) (xy 130.977023 -43.582773) (xy 130.962184 -43.625005) (xy 130.954976 -43.669184)
			(xy 130.955623 -43.713943) (xy 130.964105 -43.757895) (xy 130.980159 -43.79968) (xy 130.991356 -43.819064)
			(xy 131.024053 -43.874251) (xy 131.083246 -43.988066) (xy 131.135146 -44.105387) (xy 131.179546 -44.225747)
			(xy 131.216268 -44.348667) (xy 131.245169 -44.473657) (xy 131.266131 -44.600221) (xy 131.279073 -44.727854)
			(xy 131.283941 -44.85605) (xy 131.280718 -44.984297) (xy 131.269416 -45.112087) (xy 131.250079 -45.238909)
			(xy 131.222785 -45.36426) (xy 131.187643 -45.487641) (xy 131.144791 -45.60856) (xy 131.094402 -45.726538)
			(xy 131.036674 -45.841104) (xy 130.971838 -45.951802) (xy 130.900153 -46.058193) (xy 130.821902 -46.159852)
			(xy 130.737397 -46.256375) (xy 130.646976 -46.347379) (xy 130.550996 -46.432501) (xy 130.449841 -46.511403)
			(xy 130.343913 -46.58377) (xy 130.233633 -46.649314) (xy 130.11944 -46.707776) (xy 130.001788 -46.758922)
			(xy 129.881146 -46.802548) (xy 129.757993 -46.838481) (xy 129.63282 -46.866579) (xy 129.506124 -46.886729)
			(xy 129.37841 -46.898851) (xy 129.250186 -46.902897) (xy 129.121962 -46.898851) (xy 128.994248 -46.886729)
			(xy 128.867552 -46.866579) (xy 128.742379 -46.838481) (xy 128.619226 -46.802548) (xy 128.498584 -46.758922)
			(xy 128.380932 -46.707776) (xy 128.266739 -46.649314) (xy 128.156459 -46.58377) (xy 128.050531 -46.511403)
			(xy 127.949376 -46.432501) (xy 127.853396 -46.347379) (xy 127.762975 -46.256375) (xy 127.67847 -46.159852)
			(xy 127.600219 -46.058193) (xy 127.528534 -45.951802) (xy 127.463698 -45.841104) (xy 127.40597 -45.726538)
			(xy 127.355581 -45.60856) (xy 127.312729 -45.487641) (xy 127.277587 -45.36426) (xy 127.250293 -45.238909)
			(xy 127.230956 -45.112087) (xy 127.219654 -44.984297) (xy 127.216431 -44.85605) (xy 127.221299 -44.727854)
			(xy 127.234241 -44.600221) (xy 127.255203 -44.473657) (xy 127.284104 -44.348667) (xy 127.320826 -44.225747)
			(xy 127.365226 -44.105387) (xy 127.417126 -43.988066) (xy 127.476319 -43.874251) (xy 127.509016 -43.819064)
			(xy 127.520155 -43.799655) (xy 127.536172 -43.757875) (xy 127.544625 -43.713935) (xy 127.545254 -43.669193)
			(xy 127.538039 -43.625033) (xy 127.523203 -43.582819) (xy 127.501204 -43.543854) (xy 127.472722 -43.509344)
			(xy 127.438637 -43.480354) (xy 127.400003 -43.45778) (xy 127.358013 -43.442321) (xy 127.313965 -43.434452)
			(xy 127.291592 -43.434) (xy 119.780812 -43.434) (xy 119.758428 -43.434464) (xy 119.714351 -43.442291)
			(xy 119.672328 -43.457723) (xy 119.63366 -43.480282) (xy 119.599545 -43.509269) (xy 119.571039 -43.543788)
			(xy 119.549025 -43.582768) (xy 119.534184 -43.625004) (xy 119.526976 -43.669187) (xy 119.527624 -43.713949)
			(xy 119.536108 -43.757905) (xy 119.552165 -43.799693) (xy 119.563388 -43.819064) (xy 119.596077 -43.874301)
			(xy 119.65525 -43.988216) (xy 119.707124 -44.105634) (xy 119.751494 -44.226088) (xy 119.788184 -44.3491)
			(xy 119.817047 -44.474179) (xy 119.837968 -44.600829) (xy 119.850866 -44.728546) (xy 119.855687 -44.856822)
			(xy 119.852413 -44.985147) (xy 119.841058 -45.11301) (xy 119.821665 -45.239903) (xy 119.794313 -45.365322)
			(xy 119.75911 -45.488767) (xy 119.716197 -45.609748) (xy 119.665742 -45.727783) (xy 119.607949 -45.842403)
			(xy 119.543045 -45.953153) (xy 119.47129 -46.059592) (xy 119.392969 -46.161296) (xy 119.308393 -46.257861)
			(xy 119.217898 -46.348903) (xy 119.121845 -46.43406) (xy 119.020615 -46.512993) (xy 118.914611 -46.585389)
			(xy 118.804255 -46.650959) (xy 118.689985 -46.709443) (xy 118.572257 -46.760609) (xy 118.451537 -46.804251)
			(xy 118.328306 -46.840198) (xy 118.203055 -46.868306) (xy 118.076281 -46.888464) (xy 117.948489 -46.90059)
			(xy 117.820186 -46.904638) (xy 117.691883 -46.90059) (xy 117.564091 -46.888464) (xy 117.437317 -46.868306)
			(xy 117.312066 -46.840198) (xy 117.188835 -46.804251) (xy 117.068115 -46.760609) (xy 116.950387 -46.709443)
			(xy 116.836117 -46.650959) (xy 116.725761 -46.585389) (xy 116.619757 -46.512993) (xy 116.518527 -46.43406)
			(xy 116.422474 -46.348903) (xy 116.331979 -46.257861) (xy 116.247403 -46.161296) (xy 116.169082 -46.059592)
			(xy 116.097327 -45.953153) (xy 116.032423 -45.842403) (xy 115.97463 -45.727783) (xy 115.924175 -45.609748)
			(xy 115.881262 -45.488767) (xy 115.846059 -45.365322) (xy 115.818707 -45.239903) (xy 115.799314 -45.11301)
			(xy 115.787959 -44.985147) (xy 115.784685 -44.856822) (xy 115.789506 -44.728546) (xy 115.802404 -44.600829)
			(xy 115.823325 -44.474179) (xy 115.852188 -44.3491) (xy 115.888878 -44.226088) (xy 115.933248 -44.105634)
			(xy 115.985122 -43.988216) (xy 116.044295 -43.874301) (xy 116.076984 -43.819064) (xy 116.088124 -43.799656)
			(xy 116.104142 -43.757877) (xy 116.112597 -43.713938) (xy 116.113227 -43.669198) (xy 116.106012 -43.625038)
			(xy 116.091176 -43.582825) (xy 116.069176 -43.543862) (xy 116.040693 -43.509353) (xy 116.006607 -43.480366)
			(xy 115.967972 -43.457796) (xy 115.925981 -43.44234) (xy 115.881932 -43.434477) (xy 115.85956 -43.434)
			(xy 113.2332 -43.434) (xy 109.388148 -39.588948) (xy 86.497668 -39.588948) (xy 80.884268 -33.975548)
			(xy 30.566614 -33.975548) (xy 30.544262 -33.984438) (xy 30.51776 -33.994381) (xy 30.462631 -34.007219)
			(xy 30.406211 -34.011769) (xy 30.349738 -34.007932) (xy 30.294452 -33.995791) (xy 30.241568 -33.975613)
			(xy 30.192245 -33.947842) (xy 30.169612 -33.930844) (xy 30.151172 -33.91712) (xy 30.110414 -33.895873)
			(xy 30.0665 -33.882301) (xy 30.020862 -33.876847) (xy 29.974987 -33.879689) (xy 29.930371 -33.890734)
			(xy 29.888468 -33.909622) (xy 29.850645 -33.935738) (xy 29.834078 -33.951672) (xy 29.391864 -34.393886)
			(xy 29.382212 -34.416238) (xy 29.37097 -34.440978) (xy 29.34251 -34.48727) (xy 29.307769 -34.529054)
			(xy 29.267449 -34.565486) (xy 29.222367 -34.595826) (xy 29.173436 -34.619461) (xy 29.121646 -34.635913)
			(xy 29.068045 -34.644849) (xy 29.013718 -34.646087) (xy 28.959766 -34.639603) (xy 28.90728 -34.625528)
			(xy 28.857323 -34.604147) (xy 28.810905 -34.575892) (xy 28.78963 -34.558986) (xy 28.77121 -34.544504)
			(xy 28.730202 -34.521846) (xy 28.685735 -34.507093) (xy 28.639316 -34.500745) (xy 28.59252 -34.503016)
			(xy 28.546935 -34.513831) (xy 28.504106 -34.532821) (xy 28.465485 -34.559344) (xy 28.448508 -34.575496)
			(xy 28.020264 -35.003486) (xy 28.010612 -35.025838) (xy 27.999227 -35.050902) (xy 27.970309 -35.097745)
			(xy 27.934958 -35.139944) (xy 27.893908 -35.176622) (xy 27.848012 -35.207019) (xy 27.798222 -35.230503)
			(xy 27.745575 -35.246586) (xy 27.691162 -35.254933) (xy 27.636114 -35.255372) (xy 27.581575 -35.247894)
			(xy 27.528677 -35.232653) (xy 27.47852 -35.209966) (xy 27.432145 -35.180305) (xy 27.390515 -35.144285)
			(xy 27.354495 -35.102655) (xy 27.324834 -35.05628) (xy 27.302147 -35.006123) (xy 27.286906 -34.953225)
			(xy 27.279428 -34.898686) (xy 27.279867 -34.843638) (xy 27.288214 -34.789225) (xy 27.304297 -34.736578)
			(xy 27.327781 -34.686788) (xy 27.358178 -34.640892) (xy 27.394856 -34.599842) (xy 27.437055 -34.564491)
			(xy 27.483898 -34.535573) (xy 27.508962 -34.524188) (xy 27.531314 -34.514536) (xy 28.276804 -33.769046)
			(xy 28.292753 -33.752381) (xy 28.318939 -33.714411) (xy 28.337842 -33.67234) (xy 28.348841 -33.627547)
			(xy 28.351576 -33.581505) (xy 28.345955 -33.535725) (xy 28.332165 -33.491711) (xy 28.310657 -33.45091)
			(xy 28.282138 -33.41466) (xy 28.247545 -33.384153) (xy 28.208013 -33.36039) (xy 28.186634 -33.351724)
			(xy 28.160322 -33.341279) (xy 28.110864 -33.31374) (xy 28.066018 -33.279194) (xy 28.02677 -33.2384)
			(xy 27.993983 -33.192253) (xy 27.968376 -33.141767) (xy 27.950512 -33.088051) (xy 27.940782 -33.032284)
			(xy 27.939402 -32.975692) (xy 27.946401 -32.919518) (xy 27.961625 -32.864995) (xy 27.98474 -32.81332)
			(xy 28.015239 -32.76563) (xy 28.052451 -32.722971) (xy 28.095559 -32.686279) (xy 28.143616 -32.656362)
			(xy 28.169362 -32.644588) (xy 28.191714 -32.634936) (xy 29.6418 -31.18485) (xy 29.6418 -31.1658)
			(xy 29.66085 -31.1658) (xy 29.715206 -31.11119) (xy 29.726574 -31.099027) (xy 29.743183 -31.070188)
			(xy 29.751765 -31.038035) (xy 29.751738 -31.004756) (xy 29.743102 -30.972616) (xy 29.726446 -30.943805)
			(xy 29.702903 -30.920284) (xy 29.674077 -30.903654) (xy 29.64193 -30.895047) (xy 29.62529 -30.894528)
			(xy 29.474414 -30.894528) (xy 29.452062 -30.903418) (xy 29.427172 -30.912781) (xy 29.375491 -30.925306)
			(xy 29.322571 -30.930531) (xy 29.269438 -30.928354) (xy 29.217123 -30.918817) (xy 29.166639 -30.902106)
			(xy 29.118967 -30.878544) (xy 29.075029 -30.848589) (xy 29.05506 -30.831028) (xy 29.038844 -30.816913)
			(xy 29.002608 -30.793786) (xy 28.962997 -30.777087) (xy 28.92114 -30.767294) (xy 28.878232 -30.764686)
			(xy 28.835497 -30.769337) (xy 28.794154 -30.781114) (xy 28.755384 -30.799682) (xy 28.720292 -30.824511)
			(xy 28.704794 -30.83941) (xy 27.636724 -31.907226) (xy 27.627072 -31.929578) (xy 27.615685 -31.954638)
			(xy 27.586765 -32.00147) (xy 27.551413 -32.04366) (xy 27.510364 -32.08033) (xy 27.464471 -32.110718)
			(xy 27.414686 -32.134195) (xy 27.362043 -32.150272) (xy 27.307637 -32.158614) (xy 27.252596 -32.15905)
			(xy 27.198064 -32.15157) (xy 27.145173 -32.136329) (xy 27.095023 -32.113644) (xy 27.048654 -32.083986)
			(xy 27.00703 -32.04797) (xy 26.971014 -32.006346) (xy 26.941356 -31.959977) (xy 26.918671 -31.909827)
			(xy 26.90343 -31.856936) (xy 26.89595 -31.802404) (xy 26.896386 -31.747363) (xy 26.904728 -31.692957)
			(xy 26.920805 -31.640314) (xy 26.944282 -31.590529) (xy 26.97467 -31.544636) (xy 27.01134 -31.503587)
			(xy 27.05353 -31.468235) (xy 27.100362 -31.439315) (xy 27.125422 -31.427928) (xy 27.147774 -31.418276)
			(xy 28.429712 -30.136084) (xy 28.441152 -30.123966) (xy 28.457836 -30.095129) (xy 28.466486 -30.062955)
			(xy 28.466511 -30.029639) (xy 28.457911 -29.997453) (xy 28.441272 -29.96859) (xy 28.417728 -29.945018)
			(xy 28.388884 -29.928345) (xy 28.356708 -29.919708) (xy 28.34005 -29.919168) (xy 28.118816 -29.919168)
			(xy 25.531064 -32.506666) (xy 25.521412 -32.529018) (xy 25.510028 -32.554083) (xy 25.481112 -32.600926)
			(xy 25.445763 -32.643127) (xy 25.404715 -32.679807) (xy 25.35882 -32.710206) (xy 25.309032 -32.733691)
			(xy 25.256385 -32.749775) (xy 25.201972 -32.758124) (xy 25.146925 -32.758565) (xy 25.092385 -32.751088)
			(xy 25.039488 -32.735848) (xy 24.98933 -32.713162) (xy 24.942954 -32.683502) (xy 24.901324 -32.647483)
			(xy 24.865304 -32.605854) (xy 24.835643 -32.559479) (xy 24.812956 -32.509322) (xy 24.797715 -32.456425)
			(xy 24.790236 -32.401886) (xy 24.790675 -32.346838) (xy 24.799022 -32.292426) (xy 24.815105 -32.239778)
			(xy 24.838589 -32.189989) (xy 24.868987 -32.144093) (xy 24.905666 -32.103044) (xy 24.947865 -32.067694)
			(xy 24.994708 -32.038777) (xy 25.019762 -32.027368) (xy 25.042114 -32.017716) (xy 27.832304 -29.227272)
			(xy 32.038798 -29.227272) (xy 32.060939 -29.226818) (xy 32.104558 -29.21919) (xy 32.146193 -29.204114)
			(xy 32.184582 -29.182045) (xy 32.218562 -29.153652) (xy 32.247104 -29.119797) (xy 32.269341 -29.081505)
			(xy 32.2846 -29.039937) (xy 32.288988 -29.01823) (xy 32.294068 -28.994862) (xy 32.294068 -28.994354)
			(xy 32.297624 -28.979368) (xy 32.297624 -28.964128) (xy 32.297133 -28.94747) (xy 32.288517 -28.915287)
			(xy 32.271865 -28.88643) (xy 32.248311 -28.862867) (xy 32.219462 -28.846203) (xy 32.187282 -28.837574)
			(xy 32.170624 -28.837128) (xy 27.092656 -28.837128) (xy 26.417524 -29.512006) (xy 26.407872 -29.534358)
			(xy 26.396486 -29.559418) (xy 26.367568 -29.606252) (xy 26.332218 -29.648443) (xy 26.291171 -29.685114)
			(xy 26.245279 -29.715505) (xy 26.195495 -29.738983) (xy 26.142853 -29.755061) (xy 26.088447 -29.763406)
			(xy 26.033406 -29.763843) (xy 25.978874 -29.756364) (xy 25.925984 -29.741124) (xy 25.875833 -29.71844)
			(xy 25.829464 -29.688783) (xy 25.787839 -29.652768) (xy 25.751823 -29.611145) (xy 25.722165 -29.564776)
			(xy 25.699479 -29.514626) (xy 25.684238 -29.461736) (xy 25.676758 -29.407204) (xy 25.677194 -29.352163)
			(xy 25.685537 -29.297757) (xy 25.701613 -29.245115) (xy 25.72509 -29.19533) (xy 25.755479 -29.149437)
			(xy 25.79215 -29.108389) (xy 25.834339 -29.073038) (xy 25.881173 -29.044119) (xy 25.906222 -29.032708)
			(xy 25.928574 -29.023056) (xy 26.806144 -28.145232) (xy 33.02381 -28.145232) (xy 33.0469 -28.144725)
			(xy 33.092318 -28.136378) (xy 33.13548 -28.11996) (xy 33.174965 -28.096012) (xy 33.209471 -28.065323)
			(xy 33.237864 -28.028904) (xy 33.259207 -27.987952) (xy 33.272798 -27.943818) (xy 33.276032 -27.92095)
			(xy 33.27962 -27.8943) (xy 33.293316 -27.842301) (xy 33.314176 -27.792739) (xy 33.341786 -27.746596)
			(xy 33.3756 -27.704785) (xy 33.414947 -27.668134) (xy 33.45905 -27.637368) (xy 33.507033 -27.613098)
			(xy 33.557949 -27.595802) (xy 33.610788 -27.585825) (xy 33.664505 -27.583363) (xy 33.718035 -27.588465)
			(xy 33.770319 -27.60103) (xy 33.795462 -27.610562) (xy 33.817814 -27.619452) (xy 83.277456 -27.619452)
			(xy 85.262466 -29.604716) (xy 85.274614 -29.616067) (xy 85.303409 -29.632659) (xy 85.335512 -29.641256)
			(xy 85.352128 -29.6418) (xy 88.1634 -29.6418) (xy 88.4936 -29.3116) (xy 88.4936 -27.2542) (xy 89.3445 -26.4033)
			(xy 89.3445 -24.1173) (xy 95.3516 -18.1102) (xy 95.3516 -2.667) (xy 94.2086 -1.524) (xy 9.6266 -1.524)
			(xy 8.9916 -2.159) (xy 8.9916 -2.99974) (xy 90.607899 -2.99974) (xy 90.611934 -2.924036) (xy 90.623993 -2.849191)
			(xy 90.643939 -2.77605) (xy 90.671546 -2.705445) (xy 90.706502 -2.638174) (xy 90.74841 -2.574999)
			(xy 90.796796 -2.516637) (xy 90.851112 -2.463749) (xy 90.910741 -2.416934) (xy 90.975009 -2.376722)
			(xy 91.043186 -2.34357) (xy 91.114502 -2.317852) (xy 91.188147 -2.29986) (xy 91.263287 -2.289798)
			(xy 91.339071 -2.287779) (xy 91.414641 -2.293828) (xy 91.489139 -2.307875) (xy 91.561722 -2.329761)
			(xy 91.631568 -2.359238) (xy 91.697885 -2.395973) (xy 91.759921 -2.439548) (xy 91.816974 -2.48947)
			(xy 91.868398 -2.545174) (xy 91.913609 -2.606029) (xy 91.952096 -2.671344) (xy 91.983422 -2.74038)
			(xy 92.007232 -2.812355) (xy 92.023257 -2.886453) (xy 92.031316 -2.961834) (xy 92.03182 -2.99974)
			(xy 92.607895 -2.99974) (xy 92.61193 -2.924036) (xy 92.623989 -2.849191) (xy 92.643935 -2.77605)
			(xy 92.671542 -2.705445) (xy 92.706498 -2.638174) (xy 92.748406 -2.574999) (xy 92.796792 -2.516637)
			(xy 92.851108 -2.463749) (xy 92.910737 -2.416934) (xy 92.975005 -2.376722) (xy 93.043182 -2.34357)
			(xy 93.114498 -2.317852) (xy 93.188143 -2.29986) (xy 93.263283 -2.289798) (xy 93.339067 -2.287779)
			(xy 93.414637 -2.293828) (xy 93.489135 -2.307875) (xy 93.561718 -2.329761) (xy 93.631564 -2.359238)
			(xy 93.697881 -2.395973) (xy 93.759917 -2.439548) (xy 93.81697 -2.48947) (xy 93.868394 -2.545174)
			(xy 93.913605 -2.606029) (xy 93.952092 -2.671344) (xy 93.983418 -2.74038) (xy 94.007228 -2.812355)
			(xy 94.023253 -2.886453) (xy 94.031312 -2.961834) (xy 94.031816 -2.99974) (xy 94.031312 -3.037646)
			(xy 94.023253 -3.113027) (xy 94.007228 -3.187125) (xy 93.983418 -3.2591) (xy 93.952092 -3.328136)
			(xy 93.913605 -3.393451) (xy 93.868394 -3.454306) (xy 93.81697 -3.51001) (xy 93.759917 -3.559932)
			(xy 93.697881 -3.603507) (xy 93.631564 -3.640242) (xy 93.561718 -3.669719) (xy 93.489135 -3.691605)
			(xy 93.414637 -3.705652) (xy 93.339067 -3.711701) (xy 93.263283 -3.709682) (xy 93.188143 -3.69962)
			(xy 93.114498 -3.681628) (xy 93.043182 -3.65591) (xy 92.975005 -3.622758) (xy 92.910737 -3.582546)
			(xy 92.851108 -3.535731) (xy 92.796792 -3.482843) (xy 92.748406 -3.424481) (xy 92.706498 -3.361306)
			(xy 92.671542 -3.294035) (xy 92.643935 -3.22343) (xy 92.623989 -3.150289) (xy 92.61193 -3.075444)
			(xy 92.607895 -2.99974) (xy 92.03182 -2.99974) (xy 92.031316 -3.037646) (xy 92.023257 -3.113027)
			(xy 92.007232 -3.187125) (xy 91.983422 -3.2591) (xy 91.952096 -3.328136) (xy 91.913609 -3.393451)
			(xy 91.868398 -3.454306) (xy 91.816974 -3.51001) (xy 91.759921 -3.559932) (xy 91.697885 -3.603507)
			(xy 91.631568 -3.640242) (xy 91.561722 -3.669719) (xy 91.489139 -3.691605) (xy 91.414641 -3.705652)
			(xy 91.339071 -3.711701) (xy 91.263287 -3.709682) (xy 91.188147 -3.69962) (xy 91.114502 -3.681628)
			(xy 91.043186 -3.65591) (xy 90.975009 -3.622758) (xy 90.910741 -3.582546) (xy 90.851112 -3.535731)
			(xy 90.796796 -3.482843) (xy 90.74841 -3.424481) (xy 90.706502 -3.361306) (xy 90.671546 -3.294035)
			(xy 90.643939 -3.22343) (xy 90.623993 -3.150289) (xy 90.611934 -3.075444) (xy 90.607899 -2.99974)
			(xy 8.9916 -2.99974) (xy 8.9916 -5.166461) (xy 18.897592 -5.166461) (xy 18.897592 -5.095139) (xy 18.905578 -5.024265)
			(xy 18.921448 -4.95473) (xy 18.945005 -4.88741) (xy 18.97595 -4.823151) (xy 19.013896 -4.76276) (xy 19.058365 -4.706998)
			(xy 19.108798 -4.656565) (xy 19.16456 -4.612096) (xy 19.224951 -4.57415) (xy 19.28921 -4.543205)
			(xy 19.35653 -4.519648) (xy 19.426065 -4.503778) (xy 19.496939 -4.495792) (xy 19.568261 -4.495792)
			(xy 19.639135 -4.503778) (xy 19.70867 -4.519648) (xy 19.77599 -4.543205) (xy 19.840249 -4.57415)
			(xy 19.90064 -4.612096) (xy 19.956402 -4.656565) (xy 20.006835 -4.706998) (xy 20.051304 -4.76276)
			(xy 20.08925 -4.823151) (xy 20.120195 -4.88741) (xy 20.137849 -4.937861) (xy 26.593792 -4.937861)
			(xy 26.593792 -4.866539) (xy 26.601778 -4.795665) (xy 26.617648 -4.72613) (xy 26.641205 -4.65881)
			(xy 26.67215 -4.594551) (xy 26.710096 -4.53416) (xy 26.754565 -4.478398) (xy 26.804998 -4.427965)
			(xy 26.86076 -4.383496) (xy 26.921151 -4.34555) (xy 26.98541 -4.314605) (xy 27.05273 -4.291048) (xy 27.122265 -4.275178)
			(xy 27.193139 -4.267192) (xy 27.264461 -4.267192) (xy 27.335335 -4.275178) (xy 27.40487 -4.291048)
			(xy 27.47219 -4.314605) (xy 27.536449 -4.34555) (xy 27.59684 -4.383496) (xy 27.652602 -4.427965)
			(xy 27.703035 -4.478398) (xy 27.747504 -4.53416) (xy 27.78545 -4.594551) (xy 27.816395 -4.65881)
			(xy 27.839952 -4.72613) (xy 27.855822 -4.795665) (xy 27.863808 -4.866539) (xy 27.864308 -4.9022)
			(xy 27.863808 -4.937861) (xy 27.860946 -4.963261) (xy 41.427392 -4.963261) (xy 41.427392 -4.891939)
			(xy 41.435378 -4.821065) (xy 41.451248 -4.75153) (xy 41.474805 -4.68421) (xy 41.50575 -4.619951)
			(xy 41.543696 -4.55956) (xy 41.588165 -4.503798) (xy 41.638598 -4.453365) (xy 41.69436 -4.408896)
			(xy 41.754751 -4.37095) (xy 41.81901 -4.340005) (xy 41.88633 -4.316448) (xy 41.955865 -4.300578)
			(xy 42.026739 -4.292592) (xy 42.098061 -4.292592) (xy 42.168935 -4.300578) (xy 42.23847 -4.316448)
			(xy 42.30579 -4.340005) (xy 42.370049 -4.37095) (xy 42.43044 -4.408896) (xy 42.486202 -4.453365)
			(xy 42.536635 -4.503798) (xy 42.581104 -4.55956) (xy 42.61905 -4.619951) (xy 42.649995 -4.68421)
			(xy 42.673552 -4.75153) (xy 42.689422 -4.821065) (xy 42.697408 -4.891939) (xy 42.697908 -4.9276)
			(xy 42.697408 -4.963261) (xy 42.689422 -5.034135) (xy 42.673552 -5.10367) (xy 42.65158 -5.166461)
			(xy 48.742592 -5.166461) (xy 48.742592 -5.095139) (xy 48.750578 -5.024265) (xy 48.766448 -4.95473)
			(xy 48.790005 -4.88741) (xy 48.82095 -4.823151) (xy 48.858896 -4.76276) (xy 48.903365 -4.706998)
			(xy 48.953798 -4.656565) (xy 49.00956 -4.612096) (xy 49.069951 -4.57415) (xy 49.13421 -4.543205)
			(xy 49.20153 -4.519648) (xy 49.271065 -4.503778) (xy 49.341939 -4.495792) (xy 49.413261 -4.495792)
			(xy 49.484135 -4.503778) (xy 49.55367 -4.519648) (xy 49.62099 -4.543205) (xy 49.685249 -4.57415)
			(xy 49.74564 -4.612096) (xy 49.801402 -4.656565) (xy 49.851835 -4.706998) (xy 49.896304 -4.76276)
			(xy 49.93425 -4.823151) (xy 49.965195 -4.88741) (xy 49.988752 -4.95473) (xy 50.002293 -5.014061)
			(xy 56.718192 -5.014061) (xy 56.718192 -4.942739) (xy 56.726178 -4.871865) (xy 56.742048 -4.80233)
			(xy 56.765605 -4.73501) (xy 56.79655 -4.670751) (xy 56.834496 -4.61036) (xy 56.878965 -4.554598)
			(xy 56.929398 -4.504165) (xy 56.98516 -4.459696) (xy 57.045551 -4.42175) (xy 57.10981 -4.390805)
			(xy 57.17713 -4.367248) (xy 57.246665 -4.351378) (xy 57.317539 -4.343392) (xy 57.388861 -4.343392)
			(xy 57.459735 -4.351378) (xy 57.52927 -4.367248) (xy 57.59659 -4.390805) (xy 57.660849 -4.42175)
			(xy 57.72124 -4.459696) (xy 57.777002 -4.504165) (xy 57.827435 -4.554598) (xy 57.871904 -4.61036)
			(xy 57.90985 -4.670751) (xy 57.940795 -4.73501) (xy 57.964352 -4.80233) (xy 57.980222 -4.871865)
			(xy 57.984796 -4.912461) (xy 63.982592 -4.912461) (xy 63.982592 -4.841139) (xy 63.990578 -4.770265)
			(xy 64.006448 -4.70073) (xy 64.030005 -4.63341) (xy 64.06095 -4.569151) (xy 64.098896 -4.50876) (xy 64.143365 -4.452998)
			(xy 64.193798 -4.402565) (xy 64.24956 -4.358096) (xy 64.309951 -4.32015) (xy 64.37421 -4.289205)
			(xy 64.44153 -4.265648) (xy 64.511065 -4.249778) (xy 64.581939 -4.241792) (xy 64.653261 -4.241792)
			(xy 64.724135 -4.249778) (xy 64.79367 -4.265648) (xy 64.86099 -4.289205) (xy 64.925249 -4.32015)
			(xy 64.98564 -4.358096) (xy 65.041402 -4.402565) (xy 65.091835 -4.452998) (xy 65.136304 -4.50876)
			(xy 65.17425 -4.569151) (xy 65.205195 -4.63341) (xy 65.228752 -4.70073) (xy 65.244622 -4.770265)
			(xy 65.252608 -4.841139) (xy 65.253108 -4.8768) (xy 65.252608 -4.912461) (xy 65.244622 -4.983335)
			(xy 65.240879 -4.999736) (xy 90.607899 -4.999736) (xy 90.611934 -4.924032) (xy 90.623993 -4.849187)
			(xy 90.643939 -4.776046) (xy 90.671546 -4.705441) (xy 90.706502 -4.63817) (xy 90.74841 -4.574995)
			(xy 90.796796 -4.516633) (xy 90.851112 -4.463745) (xy 90.910741 -4.41693) (xy 90.975009 -4.376718)
			(xy 91.043186 -4.343566) (xy 91.114502 -4.317848) (xy 91.188147 -4.299856) (xy 91.263287 -4.289794)
			(xy 91.339071 -4.287775) (xy 91.414641 -4.293824) (xy 91.489139 -4.307871) (xy 91.561722 -4.329757)
			(xy 91.631568 -4.359234) (xy 91.697885 -4.395969) (xy 91.759921 -4.439544) (xy 91.816974 -4.489466)
			(xy 91.868398 -4.54517) (xy 91.913609 -4.606025) (xy 91.952096 -4.67134) (xy 91.983422 -4.740376)
			(xy 92.007232 -4.812351) (xy 92.023257 -4.886449) (xy 92.031316 -4.96183) (xy 92.03182 -4.999736)
			(xy 92.607895 -4.999736) (xy 92.61193 -4.924032) (xy 92.623989 -4.849187) (xy 92.643935 -4.776046)
			(xy 92.671542 -4.705441) (xy 92.706498 -4.63817) (xy 92.748406 -4.574995) (xy 92.796792 -4.516633)
			(xy 92.851108 -4.463745) (xy 92.910737 -4.41693) (xy 92.975005 -4.376718) (xy 93.043182 -4.343566)
			(xy 93.114498 -4.317848) (xy 93.188143 -4.299856) (xy 93.263283 -4.289794) (xy 93.339067 -4.287775)
			(xy 93.414637 -4.293824) (xy 93.489135 -4.307871) (xy 93.561718 -4.329757) (xy 93.631564 -4.359234)
			(xy 93.697881 -4.395969) (xy 93.759917 -4.439544) (xy 93.81697 -4.489466) (xy 93.868394 -4.54517)
			(xy 93.913605 -4.606025) (xy 93.952092 -4.67134) (xy 93.983418 -4.740376) (xy 94.007228 -4.812351)
			(xy 94.023253 -4.886449) (xy 94.031312 -4.96183) (xy 94.031816 -4.999736) (xy 94.031312 -5.037642)
			(xy 94.023253 -5.113023) (xy 94.007228 -5.187121) (xy 93.983418 -5.259096) (xy 93.952092 -5.328132)
			(xy 93.913605 -5.393447) (xy 93.868394 -5.454302) (xy 93.81697 -5.510006) (xy 93.759917 -5.559928)
			(xy 93.697881 -5.603503) (xy 93.631564 -5.640238) (xy 93.561718 -5.669715) (xy 93.489135 -5.691601)
			(xy 93.414637 -5.705648) (xy 93.339067 -5.711697) (xy 93.263283 -5.709678) (xy 93.188143 -5.699616)
			(xy 93.114498 -5.681624) (xy 93.043182 -5.655906) (xy 92.975005 -5.622754) (xy 92.910737 -5.582542)
			(xy 92.851108 -5.535727) (xy 92.796792 -5.482839) (xy 92.748406 -5.424477) (xy 92.706498 -5.361302)
			(xy 92.671542 -5.294031) (xy 92.643935 -5.223426) (xy 92.623989 -5.150285) (xy 92.61193 -5.07544)
			(xy 92.607895 -4.999736) (xy 92.03182 -4.999736) (xy 92.031316 -5.037642) (xy 92.023257 -5.113023)
			(xy 92.007232 -5.187121) (xy 91.983422 -5.259096) (xy 91.952096 -5.328132) (xy 91.913609 -5.393447)
			(xy 91.868398 -5.454302) (xy 91.816974 -5.510006) (xy 91.759921 -5.559928) (xy 91.697885 -5.603503)
			(xy 91.631568 -5.640238) (xy 91.561722 -5.669715) (xy 91.489139 -5.691601) (xy 91.414641 -5.705648)
			(xy 91.339071 -5.711697) (xy 91.263287 -5.709678) (xy 91.188147 -5.699616) (xy 91.114502 -5.681624)
			(xy 91.043186 -5.655906) (xy 90.975009 -5.622754) (xy 90.910741 -5.582542) (xy 90.851112 -5.535727)
			(xy 90.796796 -5.482839) (xy 90.74841 -5.424477) (xy 90.706502 -5.361302) (xy 90.671546 -5.294031)
			(xy 90.643939 -5.223426) (xy 90.623993 -5.150285) (xy 90.611934 -5.07544) (xy 90.607899 -4.999736)
			(xy 65.240879 -4.999736) (xy 65.228752 -5.05287) (xy 65.205195 -5.12019) (xy 65.17425 -5.184449)
			(xy 65.136304 -5.24484) (xy 65.091835 -5.300602) (xy 65.041402 -5.351035) (xy 64.98564 -5.395504)
			(xy 64.925249 -5.43345) (xy 64.86099 -5.464395) (xy 64.79367 -5.487952) (xy 64.724135 -5.503822)
			(xy 64.653261 -5.511808) (xy 64.581939 -5.511808) (xy 64.511065 -5.503822) (xy 64.44153 -5.487952)
			(xy 64.37421 -5.464395) (xy 64.309951 -5.43345) (xy 64.24956 -5.395504) (xy 64.193798 -5.351035)
			(xy 64.143365 -5.300602) (xy 64.098896 -5.24484) (xy 64.06095 -5.184449) (xy 64.030005 -5.12019)
			(xy 64.006448 -5.05287) (xy 63.990578 -4.983335) (xy 63.982592 -4.912461) (xy 57.984796 -4.912461)
			(xy 57.988208 -4.942739) (xy 57.988708 -4.9784) (xy 57.988208 -5.014061) (xy 57.980222 -5.084935)
			(xy 57.964352 -5.15447) (xy 57.940795 -5.22179) (xy 57.90985 -5.286049) (xy 57.871904 -5.34644) (xy 57.827435 -5.402202)
			(xy 57.777002 -5.452635) (xy 57.72124 -5.497104) (xy 57.660849 -5.53505) (xy 57.59659 -5.565995)
			(xy 57.52927 -5.589552) (xy 57.459735 -5.605422) (xy 57.388861 -5.613408) (xy 57.317539 -5.613408)
			(xy 57.246665 -5.605422) (xy 57.17713 -5.589552) (xy 57.10981 -5.565995) (xy 57.045551 -5.53505)
			(xy 56.98516 -5.497104) (xy 56.929398 -5.452635) (xy 56.878965 -5.402202) (xy 56.834496 -5.34644)
			(xy 56.79655 -5.286049) (xy 56.765605 -5.22179) (xy 56.742048 -5.15447) (xy 56.726178 -5.084935)
			(xy 56.718192 -5.014061) (xy 50.002293 -5.014061) (xy 50.004622 -5.024265) (xy 50.012608 -5.095139)
			(xy 50.013108 -5.1308) (xy 50.012608 -5.166461) (xy 50.004622 -5.237335) (xy 49.988752 -5.30687)
			(xy 49.965195 -5.37419) (xy 49.93425 -5.438449) (xy 49.896304 -5.49884) (xy 49.851835 -5.554602)
			(xy 49.801402 -5.605035) (xy 49.74564 -5.649504) (xy 49.685249 -5.68745) (xy 49.62099 -5.718395)
			(xy 49.55367 -5.741952) (xy 49.484135 -5.757822) (xy 49.413261 -5.765808) (xy 49.341939 -5.765808)
			(xy 49.271065 -5.757822) (xy 49.20153 -5.741952) (xy 49.13421 -5.718395) (xy 49.069951 -5.68745)
			(xy 49.00956 -5.649504) (xy 48.953798 -5.605035) (xy 48.903365 -5.554602) (xy 48.858896 -5.49884)
			(xy 48.82095 -5.438449) (xy 48.790005 -5.37419) (xy 48.766448 -5.30687) (xy 48.750578 -5.237335)
			(xy 48.742592 -5.166461) (xy 42.65158 -5.166461) (xy 42.649995 -5.17099) (xy 42.61905 -5.235249)
			(xy 42.581104 -5.29564) (xy 42.536635 -5.351402) (xy 42.486202 -5.401835) (xy 42.43044 -5.446304)
			(xy 42.370049 -5.48425) (xy 42.30579 -5.515195) (xy 42.23847 -5.538752) (xy 42.168935 -5.554622)
			(xy 42.098061 -5.562608) (xy 42.026739 -5.562608) (xy 41.955865 -5.554622) (xy 41.88633 -5.538752)
			(xy 41.81901 -5.515195) (xy 41.754751 -5.48425) (xy 41.69436 -5.446304) (xy 41.638598 -5.401835)
			(xy 41.588165 -5.351402) (xy 41.543696 -5.29564) (xy 41.50575 -5.235249) (xy 41.474805 -5.17099)
			(xy 41.451248 -5.10367) (xy 41.435378 -5.034135) (xy 41.427392 -4.963261) (xy 27.860946 -4.963261)
			(xy 27.855822 -5.008735) (xy 27.839952 -5.07827) (xy 27.816395 -5.14559) (xy 27.78545 -5.209849)
			(xy 27.747504 -5.27024) (xy 27.703035 -5.326002) (xy 27.652602 -5.376435) (xy 27.59684 -5.420904)
			(xy 27.536449 -5.45885) (xy 27.47219 -5.489795) (xy 27.40487 -5.513352) (xy 27.335335 -5.529222)
			(xy 27.264461 -5.537208) (xy 27.193139 -5.537208) (xy 27.122265 -5.529222) (xy 27.05273 -5.513352)
			(xy 26.98541 -5.489795) (xy 26.921151 -5.45885) (xy 26.86076 -5.420904) (xy 26.804998 -5.376435)
			(xy 26.754565 -5.326002) (xy 26.710096 -5.27024) (xy 26.67215 -5.209849) (xy 26.641205 -5.14559)
			(xy 26.617648 -5.07827) (xy 26.601778 -5.008735) (xy 26.593792 -4.937861) (xy 20.137849 -4.937861)
			(xy 20.143752 -4.95473) (xy 20.159622 -5.024265) (xy 20.167608 -5.095139) (xy 20.168108 -5.1308)
			(xy 20.167608 -5.166461) (xy 20.159622 -5.237335) (xy 20.143752 -5.30687) (xy 20.120195 -5.37419)
			(xy 20.08925 -5.438449) (xy 20.051304 -5.49884) (xy 20.006835 -5.554602) (xy 19.956402 -5.605035)
			(xy 19.90064 -5.649504) (xy 19.840249 -5.68745) (xy 19.77599 -5.718395) (xy 19.756369 -5.725261)
			(xy 22.275792 -5.725261) (xy 22.275792 -5.653939) (xy 22.283778 -5.583065) (xy 22.299648 -5.51353)
			(xy 22.323205 -5.44621) (xy 22.35415 -5.381951) (xy 22.392096 -5.32156) (xy 22.436565 -5.265798)
			(xy 22.486998 -5.215365) (xy 22.54276 -5.170896) (xy 22.603151 -5.13295) (xy 22.66741 -5.102005)
			(xy 22.73473 -5.078448) (xy 22.804265 -5.062578) (xy 22.875139 -5.054592) (xy 22.946461 -5.054592)
			(xy 23.017335 -5.062578) (xy 23.08687 -5.078448) (xy 23.15419 -5.102005) (xy 23.218449 -5.13295)
			(xy 23.27884 -5.170896) (xy 23.334602 -5.215365) (xy 23.385035 -5.265798) (xy 23.429504 -5.32156)
			(xy 23.46745 -5.381951) (xy 23.498395 -5.44621) (xy 23.521952 -5.51353) (xy 23.537822 -5.583065)
			(xy 23.545808 -5.653939) (xy 23.546308 -5.6896) (xy 23.545808 -5.725261) (xy 23.537822 -5.796135)
			(xy 23.521952 -5.86567) (xy 23.498395 -5.93299) (xy 23.46745 -5.997249) (xy 23.429504 -6.05764) (xy 23.385035 -6.113402)
			(xy 23.334602 -6.163835) (xy 23.27884 -6.208304) (xy 23.218449 -6.24625) (xy 23.15419 -6.277195)
			(xy 23.08687 -6.300752) (xy 23.017335 -6.316622) (xy 22.946461 -6.324608) (xy 22.875139 -6.324608)
			(xy 22.804265 -6.316622) (xy 22.73473 -6.300752) (xy 22.66741 -6.277195) (xy 22.603151 -6.24625)
			(xy 22.54276 -6.208304) (xy 22.486998 -6.163835) (xy 22.436565 -6.113402) (xy 22.392096 -6.05764)
			(xy 22.35415 -5.997249) (xy 22.323205 -5.93299) (xy 22.299648 -5.86567) (xy 22.283778 -5.796135)
			(xy 22.275792 -5.725261) (xy 19.756369 -5.725261) (xy 19.70867 -5.741952) (xy 19.639135 -5.757822)
			(xy 19.568261 -5.765808) (xy 19.496939 -5.765808) (xy 19.426065 -5.757822) (xy 19.35653 -5.741952)
			(xy 19.28921 -5.718395) (xy 19.224951 -5.68745) (xy 19.16456 -5.649504) (xy 19.108798 -5.605035)
			(xy 19.058365 -5.554602) (xy 19.013896 -5.49884) (xy 18.97595 -5.438449) (xy 18.945005 -5.37419)
			(xy 18.921448 -5.30687) (xy 18.905578 -5.237335) (xy 18.897592 -5.166461) (xy 8.9916 -5.166461) (xy 8.9916 -6.5532)
			(xy 8.044688 -7.500112) (xy 9.403595 -7.500112) (xy 9.407599 -7.412227) (xy 9.419579 -7.32507) (xy 9.439434 -7.239363)
			(xy 9.467001 -7.155818) (xy 9.502051 -7.075125) (xy 9.544293 -6.997953) (xy 9.593378 -6.924943) (xy 9.648899 -6.856699)
			(xy 9.710396 -6.793786) (xy 9.777358 -6.736726) (xy 9.849232 -6.685992) (xy 9.925422 -6.642004) (xy 10.005296 -6.605126)
			(xy 10.088193 -6.575665) (xy 10.173425 -6.553863) (xy 10.260287 -6.539903) (xy 10.348058 -6.533899)
			(xy 10.436012 -6.535902) (xy 10.523419 -6.545894) (xy 10.609555 -6.563794) (xy 10.693707 -6.589452)
			(xy 10.775177 -6.622656) (xy 10.85329 -6.66313) (xy 10.927398 -6.710541) (xy 10.996889 -6.764494)
			(xy 11.061185 -6.824542) (xy 11.119754 -6.890189) (xy 11.172111 -6.960889) (xy 11.217823 -7.036058)
			(xy 11.256509 -7.115072) (xy 11.28785 -7.197277) (xy 11.311585 -7.281991) (xy 11.327519 -7.368512)
			(xy 11.335519 -7.456124) (xy 11.33602 -7.500112) (xy 11.335984 -7.503261) (xy 25.399992 -7.503261)
			(xy 25.399992 -7.431939) (xy 25.407978 -7.361065) (xy 25.423848 -7.29153) (xy 25.447405 -7.22421)
			(xy 25.47835 -7.159951) (xy 25.516296 -7.09956) (xy 25.560765 -7.043798) (xy 25.611198 -6.993365)
			(xy 25.66696 -6.948896) (xy 25.727351 -6.91095) (xy 25.79161 -6.880005) (xy 25.85893 -6.856448) (xy 25.928465 -6.840578)
			(xy 25.999339 -6.832592) (xy 26.070661 -6.832592) (xy 26.141535 -6.840578) (xy 26.21107 -6.856448)
			(xy 26.27839 -6.880005) (xy 26.342649 -6.91095) (xy 26.40304 -6.948896) (xy 26.458802 -6.993365)
			(xy 26.465169 -6.999732) (xy 90.607899 -6.999732) (xy 90.611934 -6.924028) (xy 90.623993 -6.849183)
			(xy 90.643939 -6.776042) (xy 90.671546 -6.705437) (xy 90.706502 -6.638166) (xy 90.74841 -6.574991)
			(xy 90.796796 -6.516629) (xy 90.851112 -6.463741) (xy 90.910741 -6.416926) (xy 90.975009 -6.376714)
			(xy 91.043186 -6.343562) (xy 91.114502 -6.317844) (xy 91.188147 -6.299852) (xy 91.263287 -6.28979)
			(xy 91.339071 -6.287771) (xy 91.414641 -6.29382) (xy 91.489139 -6.307867) (xy 91.561722 -6.329753)
			(xy 91.631568 -6.35923) (xy 91.697885 -6.395965) (xy 91.759921 -6.43954) (xy 91.816974 -6.489462)
			(xy 91.868398 -6.545166) (xy 91.913609 -6.606021) (xy 91.952096 -6.671336) (xy 91.983422 -6.740372)
			(xy 92.007232 -6.812347) (xy 92.023257 -6.886445) (xy 92.031316 -6.961826) (xy 92.03182 -6.999732)
			(xy 92.607895 -6.999732) (xy 92.61193 -6.924028) (xy 92.623989 -6.849183) (xy 92.643935 -6.776042)
			(xy 92.671542 -6.705437) (xy 92.706498 -6.638166) (xy 92.748406 -6.574991) (xy 92.796792 -6.516629)
			(xy 92.851108 -6.463741) (xy 92.910737 -6.416926) (xy 92.975005 -6.376714) (xy 93.043182 -6.343562)
			(xy 93.114498 -6.317844) (xy 93.188143 -6.299852) (xy 93.263283 -6.28979) (xy 93.339067 -6.287771)
			(xy 93.414637 -6.29382) (xy 93.489135 -6.307867) (xy 93.561718 -6.329753) (xy 93.631564 -6.35923)
			(xy 93.697881 -6.395965) (xy 93.759917 -6.43954) (xy 93.81697 -6.489462) (xy 93.868394 -6.545166)
			(xy 93.913605 -6.606021) (xy 93.952092 -6.671336) (xy 93.983418 -6.740372) (xy 94.007228 -6.812347)
			(xy 94.023253 -6.886445) (xy 94.031312 -6.961826) (xy 94.031816 -6.999732) (xy 94.031312 -7.037638)
			(xy 94.023253 -7.113019) (xy 94.007228 -7.187117) (xy 93.983418 -7.259092) (xy 93.952092 -7.328128)
			(xy 93.913605 -7.393443) (xy 93.868394 -7.454298) (xy 93.81697 -7.510002) (xy 93.759917 -7.559924)
			(xy 93.697881 -7.603499) (xy 93.631564 -7.640234) (xy 93.561718 -7.669711) (xy 93.489135 -7.691597)
			(xy 93.414637 -7.705644) (xy 93.339067 -7.711693) (xy 93.263283 -7.709674) (xy 93.188143 -7.699612)
			(xy 93.114498 -7.68162) (xy 93.043182 -7.655902) (xy 92.975005 -7.62275) (xy 92.910737 -7.582538)
			(xy 92.851108 -7.535723) (xy 92.796792 -7.482835) (xy 92.748406 -7.424473) (xy 92.706498 -7.361298)
			(xy 92.671542 -7.294027) (xy 92.643935 -7.223422) (xy 92.623989 -7.150281) (xy 92.61193 -7.075436)
			(xy 92.607895 -6.999732) (xy 92.03182 -6.999732) (xy 92.031316 -7.037638) (xy 92.023257 -7.113019)
			(xy 92.007232 -7.187117) (xy 91.983422 -7.259092) (xy 91.952096 -7.328128) (xy 91.913609 -7.393443)
			(xy 91.868398 -7.454298) (xy 91.816974 -7.510002) (xy 91.759921 -7.559924) (xy 91.697885 -7.603499)
			(xy 91.631568 -7.640234) (xy 91.561722 -7.669711) (xy 91.489139 -7.691597) (xy 91.414641 -7.705644)
			(xy 91.339071 -7.711693) (xy 91.263287 -7.709674) (xy 91.188147 -7.699612) (xy 91.114502 -7.68162)
			(xy 91.043186 -7.655902) (xy 90.975009 -7.62275) (xy 90.910741 -7.582538) (xy 90.851112 -7.535723)
			(xy 90.796796 -7.482835) (xy 90.74841 -7.424473) (xy 90.706502 -7.361298) (xy 90.671546 -7.294027)
			(xy 90.643939 -7.223422) (xy 90.623993 -7.150281) (xy 90.611934 -7.075436) (xy 90.607899 -6.999732)
			(xy 26.465169 -6.999732) (xy 26.509235 -7.043798) (xy 26.553704 -7.09956) (xy 26.59165 -7.159951)
			(xy 26.622595 -7.22421) (xy 26.646152 -7.29153) (xy 26.662022 -7.361065) (xy 26.670008 -7.431939)
			(xy 26.670508 -7.4676) (xy 26.670008 -7.503261) (xy 26.662022 -7.574135) (xy 26.646152 -7.64367)
			(xy 26.622595 -7.71099) (xy 26.59165 -7.775249) (xy 26.553704 -7.83564) (xy 26.51493 -7.884261) (xy 49.606192 -7.884261)
			(xy 49.606192 -7.812939) (xy 49.614178 -7.742065) (xy 49.630048 -7.67253) (xy 49.653605 -7.60521)
			(xy 49.68455 -7.540951) (xy 49.722496 -7.48056) (xy 49.766965 -7.424798) (xy 49.817398 -7.374365)
			(xy 49.87316 -7.329896) (xy 49.933551 -7.29195) (xy 49.99781 -7.261005) (xy 50.06513 -7.237448) (xy 50.134665 -7.221578)
			(xy 50.205539 -7.213592) (xy 50.276861 -7.213592) (xy 50.347735 -7.221578) (xy 50.41727 -7.237448)
			(xy 50.48459 -7.261005) (xy 50.548849 -7.29195) (xy 50.60924 -7.329896) (xy 50.665002 -7.374365)
			(xy 50.715435 -7.424798) (xy 50.759904 -7.48056) (xy 50.79785 -7.540951) (xy 50.828795 -7.60521)
			(xy 50.852352 -7.67253) (xy 50.868222 -7.742065) (xy 50.876208 -7.812939) (xy 50.876708 -7.8486)
			(xy 50.876208 -7.884261) (xy 57.581792 -7.884261) (xy 57.581792 -7.812939) (xy 57.589778 -7.742065)
			(xy 57.605648 -7.67253) (xy 57.629205 -7.60521) (xy 57.66015 -7.540951) (xy 57.698096 -7.48056) (xy 57.742565 -7.424798)
			(xy 57.792998 -7.374365) (xy 57.84876 -7.329896) (xy 57.909151 -7.29195) (xy 57.97341 -7.261005)
			(xy 58.04073 -7.237448) (xy 58.110265 -7.221578) (xy 58.181139 -7.213592) (xy 58.252461 -7.213592)
			(xy 58.323335 -7.221578) (xy 58.39287 -7.237448) (xy 58.46019 -7.261005) (xy 58.524449 -7.29195)
			(xy 58.58484 -7.329896) (xy 58.640602 -7.374365) (xy 58.691035 -7.424798) (xy 58.735504 -7.48056)
			(xy 58.77345 -7.540951) (xy 58.804395 -7.60521) (xy 58.827952 -7.67253) (xy 58.843822 -7.742065)
			(xy 58.851808 -7.812939) (xy 58.852308 -7.8486) (xy 58.851808 -7.884261) (xy 58.843822 -7.955135)
			(xy 58.827952 -8.02467) (xy 58.804395 -8.09199) (xy 58.77345 -8.156249) (xy 58.735504 -8.21664) (xy 58.691035 -8.272402)
			(xy 58.640602 -8.322835) (xy 58.58484 -8.367304) (xy 58.524449 -8.40525) (xy 58.46019 -8.436195)
			(xy 58.39287 -8.459752) (xy 58.323335 -8.475622) (xy 58.252461 -8.483608) (xy 58.181139 -8.483608)
			(xy 58.110265 -8.475622) (xy 58.04073 -8.459752) (xy 57.97341 -8.436195) (xy 57.909151 -8.40525)
			(xy 57.84876 -8.367304) (xy 57.792998 -8.322835) (xy 57.742565 -8.272402) (xy 57.698096 -8.21664)
			(xy 57.66015 -8.156249) (xy 57.629205 -8.09199) (xy 57.605648 -8.02467) (xy 57.589778 -7.955135)
			(xy 57.581792 -7.884261) (xy 50.876208 -7.884261) (xy 50.868222 -7.955135) (xy 50.852352 -8.02467)
			(xy 50.828795 -8.09199) (xy 50.79785 -8.156249) (xy 50.759904 -8.21664) (xy 50.715435 -8.272402)
			(xy 50.665002 -8.322835) (xy 50.60924 -8.367304) (xy 50.548849 -8.40525) (xy 50.48459 -8.436195)
			(xy 50.41727 -8.459752) (xy 50.347735 -8.475622) (xy 50.276861 -8.483608) (xy 50.205539 -8.483608)
			(xy 50.134665 -8.475622) (xy 50.06513 -8.459752) (xy 49.99781 -8.436195) (xy 49.933551 -8.40525)
			(xy 49.87316 -8.367304) (xy 49.817398 -8.322835) (xy 49.766965 -8.272402) (xy 49.722496 -8.21664)
			(xy 49.68455 -8.156249) (xy 49.653605 -8.09199) (xy 49.630048 -8.02467) (xy 49.614178 -7.955135)
			(xy 49.606192 -7.884261) (xy 26.51493 -7.884261) (xy 26.509235 -7.891402) (xy 26.458802 -7.941835)
			(xy 26.40304 -7.986304) (xy 26.342649 -8.02425) (xy 26.27839 -8.055195) (xy 26.21107 -8.078752) (xy 26.141535 -8.094622)
			(xy 26.070661 -8.102608) (xy 25.999339 -8.102608) (xy 25.928465 -8.094622) (xy 25.85893 -8.078752)
			(xy 25.79161 -8.055195) (xy 25.727351 -8.02425) (xy 25.66696 -7.986304) (xy 25.611198 -7.941835)
			(xy 25.560765 -7.891402) (xy 25.516296 -7.83564) (xy 25.47835 -7.775249) (xy 25.447405 -7.71099)
			(xy 25.423848 -7.64367) (xy 25.407978 -7.574135) (xy 25.399992 -7.503261) (xy 11.335984 -7.503261)
			(xy 11.335519 -7.5441) (xy 11.327519 -7.631712) (xy 11.311585 -7.718233) (xy 11.28785 -7.802947)
			(xy 11.256509 -7.885152) (xy 11.217823 -7.964166) (xy 11.172111 -8.039335) (xy 11.119754 -8.110035)
			(xy 11.061185 -8.175682) (xy 10.996889 -8.23573) (xy 10.927398 -8.289683) (xy 10.85329 -8.337094)
			(xy 10.775177 -8.377568) (xy 10.693707 -8.410772) (xy 10.609555 -8.43643) (xy 10.523419 -8.45433)
			(xy 10.436012 -8.464322) (xy 10.348058 -8.466325) (xy 10.260287 -8.460321) (xy 10.173425 -8.446361)
			(xy 10.088193 -8.424559) (xy 10.005296 -8.395098) (xy 9.925422 -8.35822) (xy 9.849232 -8.314232)
			(xy 9.777358 -8.263498) (xy 9.710396 -8.206438) (xy 9.648899 -8.143525) (xy 9.593378 -8.075281) (xy 9.544293 -8.002271)
			(xy 9.502051 -7.925099) (xy 9.467001 -7.844406) (xy 9.439434 -7.760861) (xy 9.419579 -7.675154) (xy 9.407599 -7.587997)
			(xy 9.403595 -7.500112) (xy 8.044688 -7.500112) (xy 6.898539 -8.646261) (xy 30.149792 -8.646261)
			(xy 30.149792 -8.574939) (xy 30.157778 -8.504065) (xy 30.173648 -8.43453) (xy 30.197205 -8.36721)
			(xy 30.22815 -8.302951) (xy 30.266096 -8.24256) (xy 30.310565 -8.186798) (xy 30.360998 -8.136365)
			(xy 30.41676 -8.091896) (xy 30.477151 -8.05395) (xy 30.54141 -8.023005) (xy 30.60873 -7.999448) (xy 30.678265 -7.983578)
			(xy 30.749139 -7.975592) (xy 30.820461 -7.975592) (xy 30.891335 -7.983578) (xy 30.96087 -7.999448)
			(xy 31.02819 -8.023005) (xy 31.092449 -8.05395) (xy 31.15284 -8.091896) (xy 31.208602 -8.136365)
			(xy 31.259035 -8.186798) (xy 31.303504 -8.24256) (xy 31.34145 -8.302951) (xy 31.372395 -8.36721)
			(xy 31.395952 -8.43453) (xy 31.411822 -8.504065) (xy 31.419808 -8.574939) (xy 31.420308 -8.6106)
			(xy 31.419808 -8.646261) (xy 31.411822 -8.717135) (xy 31.395952 -8.78667) (xy 31.372395 -8.85399)
			(xy 31.34145 -8.918249) (xy 31.303504 -8.97864) (xy 31.259035 -9.034402) (xy 31.208602 -9.084835)
			(xy 31.153396 -9.128861) (xy 37.845992 -9.128861) (xy 37.845992 -9.057539) (xy 37.853978 -8.986665)
			(xy 37.869848 -8.91713) (xy 37.893405 -8.84981) (xy 37.92435 -8.785551) (xy 37.962296 -8.72516) (xy 38.006765 -8.669398)
			(xy 38.057198 -8.618965) (xy 38.11296 -8.574496) (xy 38.173351 -8.53655) (xy 38.23761 -8.505605)
			(xy 38.30493 -8.482048) (xy 38.374465 -8.466178) (xy 38.445339 -8.458192) (xy 38.516661 -8.458192)
			(xy 38.587535 -8.466178) (xy 38.65707 -8.482048) (xy 38.72439 -8.505605) (xy 38.788649 -8.53655)
			(xy 38.84904 -8.574496) (xy 38.904802 -8.618965) (xy 38.955235 -8.669398) (xy 38.999704 -8.72516)
			(xy 39.03765 -8.785551) (xy 39.068595 -8.84981) (xy 39.092152 -8.91713) (xy 39.108022 -8.986665)
			(xy 39.116008 -9.057539) (xy 39.116508 -9.0932) (xy 39.116008 -9.128861) (xy 39.108022 -9.199735)
			(xy 39.092152 -9.26927) (xy 39.07018 -9.332061) (xy 46.126392 -9.332061) (xy 46.126392 -9.260739)
			(xy 46.134378 -9.189865) (xy 46.150248 -9.12033) (xy 46.173805 -9.05301) (xy 46.20475 -8.988751)
			(xy 46.242696 -8.92836) (xy 46.287165 -8.872598) (xy 46.337598 -8.822165) (xy 46.39336 -8.777696)
			(xy 46.453751 -8.73975) (xy 46.51801 -8.708805) (xy 46.58533 -8.685248) (xy 46.654865 -8.669378)
			(xy 46.725739 -8.661392) (xy 46.797061 -8.661392) (xy 46.867935 -8.669378) (xy 46.93747 -8.685248)
			(xy 47.00479 -8.708805) (xy 47.069049 -8.73975) (xy 47.12944 -8.777696) (xy 47.185202 -8.822165)
			(xy 47.235635 -8.872598) (xy 47.280104 -8.92836) (xy 47.31805 -8.988751) (xy 47.348995 -9.05301)
			(xy 47.372552 -9.12033) (xy 47.374499 -9.128861) (xy 53.898792 -9.128861) (xy 53.898792 -9.057539)
			(xy 53.906778 -8.986665) (xy 53.922648 -8.91713) (xy 53.946205 -8.84981) (xy 53.97715 -8.785551)
			(xy 54.015096 -8.72516) (xy 54.059565 -8.669398) (xy 54.109998 -8.618965) (xy 54.16576 -8.574496)
			(xy 54.226151 -8.53655) (xy 54.29041 -8.505605) (xy 54.35773 -8.482048) (xy 54.427265 -8.466178)
			(xy 54.498139 -8.458192) (xy 54.569461 -8.458192) (xy 54.640335 -8.466178) (xy 54.70987 -8.482048)
			(xy 54.77719 -8.505605) (xy 54.841449 -8.53655) (xy 54.90184 -8.574496) (xy 54.957602 -8.618965)
			(xy 55.008035 -8.669398) (xy 55.052504 -8.72516) (xy 55.09045 -8.785551) (xy 55.121395 -8.84981)
			(xy 55.144952 -8.91713) (xy 55.160822 -8.986665) (xy 55.168808 -9.057539) (xy 55.169308 -9.0932)
			(xy 55.168808 -9.128861) (xy 55.160822 -9.199735) (xy 55.144952 -9.26927) (xy 55.12298 -9.332061)
			(xy 61.569592 -9.332061) (xy 61.569592 -9.260739) (xy 61.577578 -9.189865) (xy 61.593448 -9.12033)
			(xy 61.617005 -9.05301) (xy 61.64795 -8.988751) (xy 61.685896 -8.92836) (xy 61.730365 -8.872598)
			(xy 61.780798 -8.822165) (xy 61.83656 -8.777696) (xy 61.896951 -8.73975) (xy 61.96121 -8.708805)
			(xy 62.02853 -8.685248) (xy 62.098065 -8.669378) (xy 62.168939 -8.661392) (xy 62.240261 -8.661392)
			(xy 62.311135 -8.669378) (xy 62.38067 -8.685248) (xy 62.44799 -8.708805) (xy 62.512249 -8.73975)
			(xy 62.57264 -8.777696) (xy 62.628402 -8.822165) (xy 62.678835 -8.872598) (xy 62.723304 -8.92836)
			(xy 62.76125 -8.988751) (xy 62.792195 -9.05301) (xy 62.815752 -9.12033) (xy 62.831622 -9.189865)
			(xy 62.836196 -9.230461) (xy 67.513192 -9.230461) (xy 67.513192 -9.159139) (xy 67.521178 -9.088265)
			(xy 67.537048 -9.01873) (xy 67.560605 -8.95141) (xy 67.59155 -8.887151) (xy 67.629496 -8.82676) (xy 67.673965 -8.770998)
			(xy 67.724398 -8.720565) (xy 67.78016 -8.676096) (xy 67.840551 -8.63815) (xy 67.90481 -8.607205)
			(xy 67.97213 -8.583648) (xy 68.041665 -8.567778) (xy 68.112539 -8.559792) (xy 68.183861 -8.559792)
			(xy 68.254735 -8.567778) (xy 68.32427 -8.583648) (xy 68.39159 -8.607205) (xy 68.455849 -8.63815)
			(xy 68.51624 -8.676096) (xy 68.572002 -8.720565) (xy 68.622435 -8.770998) (xy 68.666904 -8.82676)
			(xy 68.70485 -8.887151) (xy 68.735795 -8.95141) (xy 68.759352 -9.01873) (xy 68.775222 -9.088265)
			(xy 68.783208 -9.159139) (xy 68.783708 -9.1948) (xy 68.783208 -9.230461) (xy 68.775222 -9.301335)
			(xy 68.759352 -9.37087) (xy 68.735795 -9.43819) (xy 68.70485 -9.502449) (xy 68.672353 -9.554168)
			(xy 87.83395 -9.554168) (xy 87.83395 -9.44554) (xy 87.841879 -9.337202) (xy 87.857696 -9.229731)
			(xy 87.881315 -9.123702) (xy 87.912611 -9.01968) (xy 87.951416 -8.918219) (xy 87.997524 -8.819862)
			(xy 88.050688 -8.725133) (xy 88.110626 -8.634538) (xy 88.177016 -8.548559) (xy 88.249506 -8.467656)
			(xy 88.327707 -8.39226) (xy 88.411204 -8.322774) (xy 88.49955 -8.259567) (xy 88.592274 -8.202979)
			(xy 88.688882 -8.153309) (xy 88.788857 -8.110824) (xy 88.891667 -8.075751) (xy 88.996763 -8.048275)
			(xy 89.103584 -8.028544) (xy 89.21156 -8.016663) (xy 89.320116 -8.012696) (xy 89.428672 -8.016663)
			(xy 89.536648 -8.028544) (xy 89.643469 -8.048275) (xy 89.748565 -8.075751) (xy 89.851375 -8.110824)
			(xy 89.95135 -8.153309) (xy 90.047958 -8.202979) (xy 90.140682 -8.259567) (xy 90.229028 -8.322774)
			(xy 90.312525 -8.39226) (xy 90.390726 -8.467656) (xy 90.463216 -8.548559) (xy 90.529606 -8.634538)
			(xy 90.589544 -8.725133) (xy 90.642708 -8.819862) (xy 90.688816 -8.918219) (xy 90.727621 -9.01968)
			(xy 90.758917 -9.123702) (xy 90.782536 -9.229731) (xy 90.798353 -9.337202) (xy 90.806282 -9.44554)
			(xy 90.806778 -9.499854) (xy 90.806282 -9.554168) (xy 90.798353 -9.662506) (xy 90.782536 -9.769977)
			(xy 90.758917 -9.876006) (xy 90.727621 -9.980028) (xy 90.688816 -10.081489) (xy 90.642708 -10.179846)
			(xy 90.589544 -10.274575) (xy 90.529606 -10.36517) (xy 90.463216 -10.451149) (xy 90.390726 -10.532052)
			(xy 90.312525 -10.607448) (xy 90.229028 -10.676934) (xy 90.140682 -10.740141) (xy 90.047958 -10.796729)
			(xy 89.95135 -10.846399) (xy 89.851375 -10.888884) (xy 89.748565 -10.923957) (xy 89.643469 -10.951433)
			(xy 89.536648 -10.971164) (xy 89.428672 -10.983045) (xy 89.320116 -10.987012) (xy 89.21156 -10.983045)
			(xy 89.103584 -10.971164) (xy 88.996763 -10.951433) (xy 88.891667 -10.923957) (xy 88.788857 -10.888884)
			(xy 88.688882 -10.846399) (xy 88.592274 -10.796729) (xy 88.49955 -10.740141) (xy 88.411204 -10.676934)
			(xy 88.327707 -10.607448) (xy 88.249506 -10.532052) (xy 88.177016 -10.451149) (xy 88.110626 -10.36517)
			(xy 88.050688 -10.274575) (xy 87.997524 -10.179846) (xy 87.951416 -10.081489) (xy 87.912611 -9.980028)
			(xy 87.881315 -9.876006) (xy 87.857696 -9.769977) (xy 87.841879 -9.662506) (xy 87.83395 -9.554168)
			(xy 68.672353 -9.554168) (xy 68.666904 -9.56284) (xy 68.622435 -9.618602) (xy 68.572002 -9.669035)
			(xy 68.51624 -9.713504) (xy 68.455849 -9.75145) (xy 68.39159 -9.782395) (xy 68.32427 -9.805952) (xy 68.254735 -9.821822)
			(xy 68.183861 -9.829808) (xy 68.112539 -9.829808) (xy 68.041665 -9.821822) (xy 67.97213 -9.805952)
			(xy 67.90481 -9.782395) (xy 67.840551 -9.75145) (xy 67.78016 -9.713504) (xy 67.724398 -9.669035)
			(xy 67.673965 -9.618602) (xy 67.629496 -9.56284) (xy 67.59155 -9.502449) (xy 67.560605 -9.43819)
			(xy 67.537048 -9.37087) (xy 67.521178 -9.301335) (xy 67.513192 -9.230461) (xy 62.836196 -9.230461)
			(xy 62.839608 -9.260739) (xy 62.840108 -9.2964) (xy 62.839608 -9.332061) (xy 62.831622 -9.402935)
			(xy 62.815752 -9.47247) (xy 62.792195 -9.53979) (xy 62.76125 -9.604049) (xy 62.723304 -9.66444) (xy 62.678835 -9.720202)
			(xy 62.628402 -9.770635) (xy 62.57264 -9.815104) (xy 62.512249 -9.85305) (xy 62.44799 -9.883995)
			(xy 62.38067 -9.907552) (xy 62.311135 -9.923422) (xy 62.240261 -9.931408) (xy 62.168939 -9.931408)
			(xy 62.098065 -9.923422) (xy 62.02853 -9.907552) (xy 61.96121 -9.883995) (xy 61.896951 -9.85305)
			(xy 61.83656 -9.815104) (xy 61.780798 -9.770635) (xy 61.730365 -9.720202) (xy 61.685896 -9.66444)
			(xy 61.64795 -9.604049) (xy 61.617005 -9.53979) (xy 61.593448 -9.47247) (xy 61.577578 -9.402935)
			(xy 61.569592 -9.332061) (xy 55.12298 -9.332061) (xy 55.121395 -9.33659) (xy 55.09045 -9.400849)
			(xy 55.052504 -9.46124) (xy 55.008035 -9.517002) (xy 54.957602 -9.567435) (xy 54.90184 -9.611904)
			(xy 54.841449 -9.64985) (xy 54.77719 -9.680795) (xy 54.70987 -9.704352) (xy 54.640335 -9.720222)
			(xy 54.569461 -9.728208) (xy 54.498139 -9.728208) (xy 54.427265 -9.720222) (xy 54.35773 -9.704352)
			(xy 54.29041 -9.680795) (xy 54.226151 -9.64985) (xy 54.16576 -9.611904) (xy 54.109998 -9.567435)
			(xy 54.059565 -9.517002) (xy 54.015096 -9.46124) (xy 53.97715 -9.400849) (xy 53.946205 -9.33659)
			(xy 53.922648 -9.26927) (xy 53.906778 -9.199735) (xy 53.898792 -9.128861) (xy 47.374499 -9.128861)
			(xy 47.388422 -9.189865) (xy 47.396408 -9.260739) (xy 47.396908 -9.2964) (xy 47.396408 -9.332061)
			(xy 47.388422 -9.402935) (xy 47.372552 -9.47247) (xy 47.348995 -9.53979) (xy 47.31805 -9.604049)
			(xy 47.280104 -9.66444) (xy 47.235635 -9.720202) (xy 47.185202 -9.770635) (xy 47.12944 -9.815104)
			(xy 47.069049 -9.85305) (xy 47.00479 -9.883995) (xy 46.93747 -9.907552) (xy 46.867935 -9.923422)
			(xy 46.797061 -9.931408) (xy 46.725739 -9.931408) (xy 46.654865 -9.923422) (xy 46.58533 -9.907552)
			(xy 46.51801 -9.883995) (xy 46.453751 -9.85305) (xy 46.39336 -9.815104) (xy 46.337598 -9.770635)
			(xy 46.287165 -9.720202) (xy 46.242696 -9.66444) (xy 46.20475 -9.604049) (xy 46.173805 -9.53979)
			(xy 46.150248 -9.47247) (xy 46.134378 -9.402935) (xy 46.126392 -9.332061) (xy 39.07018 -9.332061)
			(xy 39.068595 -9.33659) (xy 39.03765 -9.400849) (xy 38.999704 -9.46124) (xy 38.955235 -9.517002)
			(xy 38.904802 -9.567435) (xy 38.84904 -9.611904) (xy 38.788649 -9.64985) (xy 38.72439 -9.680795)
			(xy 38.65707 -9.704352) (xy 38.587535 -9.720222) (xy 38.516661 -9.728208) (xy 38.445339 -9.728208)
			(xy 38.374465 -9.720222) (xy 38.30493 -9.704352) (xy 38.23761 -9.680795) (xy 38.173351 -9.64985)
			(xy 38.11296 -9.611904) (xy 38.057198 -9.567435) (xy 38.006765 -9.517002) (xy 37.962296 -9.46124)
			(xy 37.92435 -9.400849) (xy 37.893405 -9.33659) (xy 37.869848 -9.26927) (xy 37.853978 -9.199735)
			(xy 37.845992 -9.128861) (xy 31.153396 -9.128861) (xy 31.15284 -9.129304) (xy 31.092449 -9.16725)
			(xy 31.02819 -9.198195) (xy 30.96087 -9.221752) (xy 30.891335 -9.237622) (xy 30.820461 -9.245608)
			(xy 30.749139 -9.245608) (xy 30.678265 -9.237622) (xy 30.60873 -9.221752) (xy 30.54141 -9.198195)
			(xy 30.477151 -9.16725) (xy 30.41676 -9.129304) (xy 30.360998 -9.084835) (xy 30.310565 -9.034402)
			(xy 30.266096 -8.97864) (xy 30.22815 -8.918249) (xy 30.197205 -8.85399) (xy 30.173648 -8.78667) (xy 30.157778 -8.717135)
			(xy 30.149792 -8.646261) (xy 6.898539 -8.646261) (xy 5.3086 -10.2362) (xy 3.81 -10.2362) (xy 3.503231 -10.542969)
			(xy 10.382999 -10.542969) (xy 10.382999 -10.457243) (xy 10.390909 -10.371883) (xy 10.406661 -10.287616)
			(xy 10.430121 -10.205163) (xy 10.461089 -10.125226) (xy 10.4993 -10.048487) (xy 10.544429 -9.975601)
			(xy 10.59609 -9.90719) (xy 10.653844 -9.843838) (xy 10.717196 -9.786084) (xy 10.785607 -9.734423)
			(xy 10.858493 -9.689294) (xy 10.935232 -9.651083) (xy 11.015169 -9.620115) (xy 11.097622 -9.596655)
			(xy 11.181889 -9.580903) (xy 11.267249 -9.572993) (xy 11.352975 -9.572993) (xy 11.438335 -9.580903)
			(xy 11.522602 -9.596655) (xy 11.605055 -9.620115) (xy 11.684992 -9.651083) (xy 11.761731 -9.689294)
			(xy 11.834617 -9.734423) (xy 11.903028 -9.786084) (xy 11.96638 -9.843838) (xy 12.024134 -9.90719)
			(xy 12.075795 -9.975601) (xy 12.120924 -10.048487) (xy 12.159135 -10.125226) (xy 12.190103 -10.205163)
			(xy 12.213563 -10.287616) (xy 12.229315 -10.371883) (xy 12.236522 -10.449661) (xy 30.835592 -10.449661)
			(xy 30.835592 -10.378339) (xy 30.843578 -10.307465) (xy 30.859448 -10.23793) (xy 30.883005 -10.17061)
			(xy 30.91395 -10.106351) (xy 30.951896 -10.04596) (xy 30.996365 -9.990198) (xy 31.046798 -9.939765)
			(xy 31.10256 -9.895296) (xy 31.162951 -9.85735) (xy 31.22721 -9.826405) (xy 31.29453 -9.802848) (xy 31.364065 -9.786978)
			(xy 31.434939 -9.778992) (xy 31.506261 -9.778992) (xy 31.577135 -9.786978) (xy 31.64667 -9.802848)
			(xy 31.71399 -9.826405) (xy 31.778249 -9.85735) (xy 31.83864 -9.895296) (xy 31.894402 -9.939765)
			(xy 31.944835 -9.990198) (xy 31.989304 -10.04596) (xy 32.02725 -10.106351) (xy 32.058195 -10.17061)
			(xy 32.081752 -10.23793) (xy 32.097622 -10.307465) (xy 32.105608 -10.378339) (xy 32.106108 -10.414)
			(xy 32.105608 -10.449661) (xy 32.097622 -10.520535) (xy 32.081752 -10.59007) (xy 32.058195 -10.65739)
			(xy 32.02725 -10.721649) (xy 31.989304 -10.78204) (xy 31.944835 -10.837802) (xy 31.894402 -10.888235)
			(xy 31.83864 -10.932704) (xy 31.778249 -10.97065) (xy 31.717875 -10.999724) (xy 90.607899 -10.999724)
			(xy 90.611934 -10.92402) (xy 90.623993 -10.849175) (xy 90.643939 -10.776034) (xy 90.671546 -10.705429)
			(xy 90.706502 -10.638158) (xy 90.74841 -10.574983) (xy 90.796796 -10.516621) (xy 90.851112 -10.463733)
			(xy 90.910741 -10.416918) (xy 90.975009 -10.376706) (xy 91.043186 -10.343554) (xy 91.114502 -10.317836)
			(xy 91.188147 -10.299844) (xy 91.263287 -10.289782) (xy 91.339071 -10.287763) (xy 91.414641 -10.293812)
			(xy 91.489139 -10.307859) (xy 91.561722 -10.329745) (xy 91.631568 -10.359222) (xy 91.697885 -10.395957)
			(xy 91.759921 -10.439532) (xy 91.816974 -10.489454) (xy 91.868398 -10.545158) (xy 91.913609 -10.606013)
			(xy 91.952096 -10.671328) (xy 91.983422 -10.740364) (xy 92.007232 -10.812339) (xy 92.023257 -10.886437)
			(xy 92.031316 -10.961818) (xy 92.03182 -10.999724) (xy 92.607895 -10.999724) (xy 92.61193 -10.92402)
			(xy 92.623989 -10.849175) (xy 92.643935 -10.776034) (xy 92.671542 -10.705429) (xy 92.706498 -10.638158)
			(xy 92.748406 -10.574983) (xy 92.796792 -10.516621) (xy 92.851108 -10.463733) (xy 92.910737 -10.416918)
			(xy 92.975005 -10.376706) (xy 93.043182 -10.343554) (xy 93.114498 -10.317836) (xy 93.188143 -10.299844)
			(xy 93.263283 -10.289782) (xy 93.339067 -10.287763) (xy 93.414637 -10.293812) (xy 93.489135 -10.307859)
			(xy 93.561718 -10.329745) (xy 93.631564 -10.359222) (xy 93.697881 -10.395957) (xy 93.759917 -10.439532)
			(xy 93.81697 -10.489454) (xy 93.868394 -10.545158) (xy 93.913605 -10.606013) (xy 93.952092 -10.671328)
			(xy 93.983418 -10.740364) (xy 94.007228 -10.812339) (xy 94.023253 -10.886437) (xy 94.031312 -10.961818)
			(xy 94.031816 -10.999724) (xy 94.031312 -11.03763) (xy 94.023253 -11.113011) (xy 94.007228 -11.187109)
			(xy 93.983418 -11.259084) (xy 93.952092 -11.32812) (xy 93.913605 -11.393435) (xy 93.868394 -11.45429)
			(xy 93.81697 -11.509994) (xy 93.759917 -11.559916) (xy 93.697881 -11.603491) (xy 93.631564 -11.640226)
			(xy 93.561718 -11.669703) (xy 93.489135 -11.691589) (xy 93.414637 -11.705636) (xy 93.339067 -11.711685)
			(xy 93.263283 -11.709666) (xy 93.188143 -11.699604) (xy 93.114498 -11.681612) (xy 93.043182 -11.655894)
			(xy 92.975005 -11.622742) (xy 92.910737 -11.58253) (xy 92.851108 -11.535715) (xy 92.796792 -11.482827)
			(xy 92.748406 -11.424465) (xy 92.706498 -11.36129) (xy 92.671542 -11.294019) (xy 92.643935 -11.223414)
			(xy 92.623989 -11.150273) (xy 92.61193 -11.075428) (xy 92.607895 -10.999724) (xy 92.03182 -10.999724)
			(xy 92.031316 -11.03763) (xy 92.023257 -11.113011) (xy 92.007232 -11.187109) (xy 91.983422 -11.259084)
			(xy 91.952096 -11.32812) (xy 91.913609 -11.393435) (xy 91.868398 -11.45429) (xy 91.816974 -11.509994)
			(xy 91.759921 -11.559916) (xy 91.697885 -11.603491) (xy 91.631568 -11.640226) (xy 91.561722 -11.669703)
			(xy 91.489139 -11.691589) (xy 91.414641 -11.705636) (xy 91.339071 -11.711685) (xy 91.263287 -11.709666)
			(xy 91.188147 -11.699604) (xy 91.114502 -11.681612) (xy 91.043186 -11.655894) (xy 90.975009 -11.622742)
			(xy 90.910741 -11.58253) (xy 90.851112 -11.535715) (xy 90.796796 -11.482827) (xy 90.74841 -11.424465)
			(xy 90.706502 -11.36129) (xy 90.671546 -11.294019) (xy 90.643939 -11.223414) (xy 90.623993 -11.150273)
			(xy 90.611934 -11.075428) (xy 90.607899 -10.999724) (xy 31.717875 -10.999724) (xy 31.71399 -11.001595)
			(xy 31.64667 -11.025152) (xy 31.577135 -11.041022) (xy 31.506261 -11.049008) (xy 31.434939 -11.049008)
			(xy 31.364065 -11.041022) (xy 31.29453 -11.025152) (xy 31.22721 -11.001595) (xy 31.162951 -10.97065)
			(xy 31.10256 -10.932704) (xy 31.046798 -10.888235) (xy 30.996365 -10.837802) (xy 30.951896 -10.78204)
			(xy 30.91395 -10.721649) (xy 30.883005 -10.65739) (xy 30.859448 -10.59007) (xy 30.843578 -10.520535)
			(xy 30.835592 -10.449661) (xy 12.236522 -10.449661) (xy 12.237225 -10.457243) (xy 12.23772 -10.500106)
			(xy 12.237225 -10.542969) (xy 12.229315 -10.628329) (xy 12.213563 -10.712596) (xy 12.190103 -10.795049)
			(xy 12.159135 -10.874986) (xy 12.120924 -10.951725) (xy 12.075795 -11.024611) (xy 12.024134 -11.093022)
			(xy 11.96638 -11.156374) (xy 11.903028 -11.214128) (xy 11.834617 -11.265789) (xy 11.761731 -11.310918)
			(xy 11.684992 -11.349129) (xy 11.605055 -11.380097) (xy 11.522602 -11.403557) (xy 11.438335 -11.419309)
			(xy 11.352975 -11.427219) (xy 11.267249 -11.427219) (xy 11.181889 -11.419309) (xy 11.097622 -11.403557)
			(xy 11.015169 -11.380097) (xy 10.935232 -11.349129) (xy 10.858493 -11.310918) (xy 10.785607 -11.265789)
			(xy 10.717196 -11.214128) (xy 10.653844 -11.156374) (xy 10.59609 -11.093022) (xy 10.544429 -11.024611)
			(xy 10.4993 -10.951725) (xy 10.461089 -10.874986) (xy 10.430121 -10.795049) (xy 10.406661 -10.712596)
			(xy 10.390909 -10.628329) (xy 10.382999 -10.542969) (xy 3.503231 -10.542969) (xy 2.1844 -11.8618)
			(xy 2.1844 -12.329261) (xy 42.062392 -12.329261) (xy 42.062392 -12.257939) (xy 42.070378 -12.187065)
			(xy 42.086248 -12.11753) (xy 42.109805 -12.05021) (xy 42.14075 -11.985951) (xy 42.178696 -11.92556)
			(xy 42.223165 -11.869798) (xy 42.273598 -11.819365) (xy 42.32936 -11.774896) (xy 42.389751 -11.73695)
			(xy 42.45401 -11.706005) (xy 42.52133 -11.682448) (xy 42.590865 -11.666578) (xy 42.661739 -11.658592)
			(xy 42.733061 -11.658592) (xy 42.803935 -11.666578) (xy 42.87347 -11.682448) (xy 42.94079 -11.706005)
			(xy 43.005049 -11.73695) (xy 43.06544 -11.774896) (xy 43.121202 -11.819365) (xy 43.171635 -11.869798)
			(xy 43.216104 -11.92556) (xy 43.25405 -11.985951) (xy 43.284995 -12.05021) (xy 43.308552 -12.11753)
			(xy 43.324422 -12.187065) (xy 43.328996 -12.227661) (xy 49.606192 -12.227661) (xy 49.606192 -12.156339)
			(xy 49.614178 -12.085465) (xy 49.630048 -12.01593) (xy 49.653605 -11.94861) (xy 49.68455 -11.884351)
			(xy 49.722496 -11.82396) (xy 49.766965 -11.768198) (xy 49.817398 -11.717765) (xy 49.87316 -11.673296)
			(xy 49.933551 -11.63535) (xy 49.99781 -11.604405) (xy 50.06513 -11.580848) (xy 50.134665 -11.564978)
			(xy 50.205539 -11.556992) (xy 50.276861 -11.556992) (xy 50.347735 -11.564978) (xy 50.41727 -11.580848)
			(xy 50.48459 -11.604405) (xy 50.548849 -11.63535) (xy 50.60924 -11.673296) (xy 50.665002 -11.717765)
			(xy 50.715435 -11.768198) (xy 50.759904 -11.82396) (xy 50.79785 -11.884351) (xy 50.828795 -11.94861)
			(xy 50.852352 -12.01593) (xy 50.868222 -12.085465) (xy 50.876208 -12.156339) (xy 50.876708 -12.192)
			(xy 50.876208 -12.227661) (xy 50.868222 -12.298535) (xy 50.852352 -12.36807) (xy 50.828795 -12.43539)
			(xy 50.79785 -12.499649) (xy 50.759904 -12.56004) (xy 50.715435 -12.615802) (xy 50.665002 -12.666235)
			(xy 50.60924 -12.710704) (xy 50.548849 -12.74865) (xy 50.48459 -12.779595) (xy 50.41727 -12.803152)
			(xy 50.347735 -12.819022) (xy 50.276861 -12.827008) (xy 50.205539 -12.827008) (xy 50.134665 -12.819022)
			(xy 50.06513 -12.803152) (xy 49.99781 -12.779595) (xy 49.933551 -12.74865) (xy 49.87316 -12.710704)
			(xy 49.817398 -12.666235) (xy 49.766965 -12.615802) (xy 49.722496 -12.56004) (xy 49.68455 -12.499649)
			(xy 49.653605 -12.43539) (xy 49.630048 -12.36807) (xy 49.614178 -12.298535) (xy 49.606192 -12.227661)
			(xy 43.328996 -12.227661) (xy 43.332408 -12.257939) (xy 43.332908 -12.2936) (xy 43.332408 -12.329261)
			(xy 43.324422 -12.400135) (xy 43.308552 -12.46967) (xy 43.284995 -12.53699) (xy 43.25405 -12.601249)
			(xy 43.216104 -12.66164) (xy 43.171635 -12.717402) (xy 43.121202 -12.767835) (xy 43.06544 -12.812304)
			(xy 43.005049 -12.85025) (xy 42.94079 -12.881195) (xy 42.87347 -12.904752) (xy 42.803935 -12.920622)
			(xy 42.733061 -12.928608) (xy 42.661739 -12.928608) (xy 42.590865 -12.920622) (xy 42.52133 -12.904752)
			(xy 42.45401 -12.881195) (xy 42.389751 -12.85025) (xy 42.32936 -12.812304) (xy 42.273598 -12.767835)
			(xy 42.223165 -12.717402) (xy 42.178696 -12.66164) (xy 42.14075 -12.601249) (xy 42.109805 -12.53699)
			(xy 42.086248 -12.46967) (xy 42.070378 -12.400135) (xy 42.062392 -12.329261) (xy 2.1844 -12.329261)
			(xy 2.1844 -13.542963) (xy 10.382999 -13.542963) (xy 10.382999 -13.457237) (xy 10.390909 -13.371877)
			(xy 10.406661 -13.28761) (xy 10.430121 -13.205157) (xy 10.461089 -13.12522) (xy 10.4993 -13.048481)
			(xy 10.544429 -12.975595) (xy 10.59609 -12.907184) (xy 10.653844 -12.843832) (xy 10.717196 -12.786078)
			(xy 10.785607 -12.734417) (xy 10.858493 -12.689288) (xy 10.935232 -12.651077) (xy 11.015169 -12.620109)
			(xy 11.097622 -12.596649) (xy 11.181889 -12.580897) (xy 11.267249 -12.572987) (xy 11.352975 -12.572987)
			(xy 11.438335 -12.580897) (xy 11.522602 -12.596649) (xy 11.605055 -12.620109) (xy 11.684992 -12.651077)
			(xy 11.761731 -12.689288) (xy 11.834617 -12.734417) (xy 11.903028 -12.786078) (xy 11.96638 -12.843832)
			(xy 12.024134 -12.907184) (xy 12.075795 -12.975595) (xy 12.115958 -13.040461) (xy 64.846192 -13.040461)
			(xy 64.846192 -12.969139) (xy 64.854178 -12.898265) (xy 64.870048 -12.82873) (xy 64.893605 -12.76141)
			(xy 64.92455 -12.697151) (xy 64.962496 -12.63676) (xy 65.006965 -12.580998) (xy 65.057398 -12.530565)
			(xy 65.11316 -12.486096) (xy 65.173551 -12.44815) (xy 65.23781 -12.417205) (xy 65.30513 -12.393648)
			(xy 65.374665 -12.377778) (xy 65.445539 -12.369792) (xy 65.516861 -12.369792) (xy 65.587735 -12.377778)
			(xy 65.65727 -12.393648) (xy 65.72459 -12.417205) (xy 65.788849 -12.44815) (xy 65.84924 -12.486096)
			(xy 65.905002 -12.530565) (xy 65.955435 -12.580998) (xy 65.999904 -12.63676) (xy 66.03785 -12.697151)
			(xy 66.068795 -12.76141) (xy 66.092352 -12.82873) (xy 66.108222 -12.898265) (xy 66.116208 -12.969139)
			(xy 66.116637 -12.99972) (xy 90.607899 -12.99972) (xy 90.611934 -12.924016) (xy 90.623993 -12.849171)
			(xy 90.643939 -12.77603) (xy 90.671546 -12.705425) (xy 90.706502 -12.638154) (xy 90.74841 -12.574979)
			(xy 90.796796 -12.516617) (xy 90.851112 -12.463729) (xy 90.910741 -12.416914) (xy 90.975009 -12.376702)
			(xy 91.043186 -12.34355) (xy 91.114502 -12.317832) (xy 91.188147 -12.29984) (xy 91.263287 -12.289778)
			(xy 91.339071 -12.287759) (xy 91.414641 -12.293808) (xy 91.489139 -12.307855) (xy 91.561722 -12.329741)
			(xy 91.631568 -12.359218) (xy 91.697885 -12.395953) (xy 91.759921 -12.439528) (xy 91.816974 -12.48945)
			(xy 91.868398 -12.545154) (xy 91.913609 -12.606009) (xy 91.952096 -12.671324) (xy 91.983422 -12.74036)
			(xy 92.007232 -12.812335) (xy 92.023257 -12.886433) (xy 92.031316 -12.961814) (xy 92.03182 -12.99972)
			(xy 92.607895 -12.99972) (xy 92.61193 -12.924016) (xy 92.623989 -12.849171) (xy 92.643935 -12.77603)
			(xy 92.671542 -12.705425) (xy 92.706498 -12.638154) (xy 92.748406 -12.574979) (xy 92.796792 -12.516617)
			(xy 92.851108 -12.463729) (xy 92.910737 -12.416914) (xy 92.975005 -12.376702) (xy 93.043182 -12.34355)
			(xy 93.114498 -12.317832) (xy 93.188143 -12.29984) (xy 93.263283 -12.289778) (xy 93.339067 -12.287759)
			(xy 93.414637 -12.293808) (xy 93.489135 -12.307855) (xy 93.561718 -12.329741) (xy 93.631564 -12.359218)
			(xy 93.697881 -12.395953) (xy 93.759917 -12.439528) (xy 93.81697 -12.48945) (xy 93.868394 -12.545154)
			(xy 93.913605 -12.606009) (xy 93.952092 -12.671324) (xy 93.983418 -12.74036) (xy 94.007228 -12.812335)
			(xy 94.023253 -12.886433) (xy 94.031312 -12.961814) (xy 94.031816 -12.99972) (xy 94.031312 -13.037626)
			(xy 94.023253 -13.113007) (xy 94.007228 -13.187105) (xy 93.983418 -13.25908) (xy 93.952092 -13.328116)
			(xy 93.913605 -13.393431) (xy 93.868394 -13.454286) (xy 93.81697 -13.50999) (xy 93.759917 -13.559912)
			(xy 93.697881 -13.603487) (xy 93.631564 -13.640222) (xy 93.561718 -13.669699) (xy 93.489135 -13.691585)
			(xy 93.414637 -13.705632) (xy 93.339067 -13.711681) (xy 93.263283 -13.709662) (xy 93.188143 -13.6996)
			(xy 93.114498 -13.681608) (xy 93.043182 -13.65589) (xy 92.975005 -13.622738) (xy 92.910737 -13.582526)
			(xy 92.851108 -13.535711) (xy 92.796792 -13.482823) (xy 92.748406 -13.424461) (xy 92.706498 -13.361286)
			(xy 92.671542 -13.294015) (xy 92.643935 -13.22341) (xy 92.623989 -13.150269) (xy 92.61193 -13.075424)
			(xy 92.607895 -12.99972) (xy 92.03182 -12.99972) (xy 92.031316 -13.037626) (xy 92.023257 -13.113007)
			(xy 92.007232 -13.187105) (xy 91.983422 -13.25908) (xy 91.952096 -13.328116) (xy 91.913609 -13.393431)
			(xy 91.868398 -13.454286) (xy 91.816974 -13.50999) (xy 91.759921 -13.559912) (xy 91.697885 -13.603487)
			(xy 91.631568 -13.640222) (xy 91.561722 -13.669699) (xy 91.489139 -13.691585) (xy 91.414641 -13.705632)
			(xy 91.339071 -13.711681) (xy 91.263287 -13.709662) (xy 91.188147 -13.6996) (xy 91.114502 -13.681608)
			(xy 91.043186 -13.65589) (xy 90.975009 -13.622738) (xy 90.910741 -13.582526) (xy 90.851112 -13.535711)
			(xy 90.796796 -13.482823) (xy 90.74841 -13.424461) (xy 90.706502 -13.361286) (xy 90.671546 -13.294015)
			(xy 90.643939 -13.22341) (xy 90.623993 -13.150269) (xy 90.611934 -13.075424) (xy 90.607899 -12.99972)
			(xy 66.116637 -12.99972) (xy 66.116708 -13.0048) (xy 66.116208 -13.040461) (xy 66.108222 -13.111335)
			(xy 66.092352 -13.18087) (xy 66.068795 -13.24819) (xy 66.03785 -13.312449) (xy 65.999904 -13.37284)
			(xy 65.955435 -13.428602) (xy 65.905002 -13.479035) (xy 65.84924 -13.523504) (xy 65.788849 -13.56145)
			(xy 65.72459 -13.592395) (xy 65.65727 -13.615952) (xy 65.587735 -13.631822) (xy 65.516861 -13.639808)
			(xy 65.445539 -13.639808) (xy 65.374665 -13.631822) (xy 65.30513 -13.615952) (xy 65.23781 -13.592395)
			(xy 65.173551 -13.56145) (xy 65.11316 -13.523504) (xy 65.057398 -13.479035) (xy 65.006965 -13.428602)
			(xy 64.962496 -13.37284) (xy 64.92455 -13.312449) (xy 64.893605 -13.24819) (xy 64.870048 -13.18087)
			(xy 64.854178 -13.111335) (xy 64.846192 -13.040461) (xy 12.115958 -13.040461) (xy 12.120924 -13.048481)
			(xy 12.159135 -13.12522) (xy 12.190103 -13.205157) (xy 12.213563 -13.28761) (xy 12.229315 -13.371877)
			(xy 12.237225 -13.457237) (xy 12.23772 -13.5001) (xy 12.237225 -13.542963) (xy 12.229315 -13.628323)
			(xy 12.213563 -13.71259) (xy 12.190103 -13.795043) (xy 12.159135 -13.87498) (xy 12.120924 -13.951719)
			(xy 12.075795 -14.024605) (xy 12.024134 -14.093016) (xy 11.96638 -14.156368) (xy 11.903028 -14.214122)
			(xy 11.834617 -14.265783) (xy 11.761731 -14.310912) (xy 11.684992 -14.349123) (xy 11.605055 -14.380091)
			(xy 11.522602 -14.403551) (xy 11.438335 -14.419303) (xy 11.352975 -14.427213) (xy 11.267249 -14.427213)
			(xy 11.181889 -14.419303) (xy 11.097622 -14.403551) (xy 11.015169 -14.380091) (xy 10.935232 -14.349123)
			(xy 10.858493 -14.310912) (xy 10.785607 -14.265783) (xy 10.717196 -14.214122) (xy 10.653844 -14.156368)
			(xy 10.59609 -14.093016) (xy 10.544429 -14.024605) (xy 10.4993 -13.951719) (xy 10.461089 -13.87498)
			(xy 10.430121 -13.795043) (xy 10.406661 -13.71259) (xy 10.390909 -13.628323) (xy 10.382999 -13.542963)
			(xy 2.1844 -13.542963) (xy 2.1844 -14.999716) (xy 90.607899 -14.999716) (xy 90.611934 -14.924012)
			(xy 90.623993 -14.849167) (xy 90.643939 -14.776026) (xy 90.671546 -14.705421) (xy 90.706502 -14.63815)
			(xy 90.74841 -14.574975) (xy 90.796796 -14.516613) (xy 90.851112 -14.463725) (xy 90.910741 -14.41691)
			(xy 90.975009 -14.376698) (xy 91.043186 -14.343546) (xy 91.114502 -14.317828) (xy 91.188147 -14.299836)
			(xy 91.263287 -14.289774) (xy 91.339071 -14.287755) (xy 91.414641 -14.293804) (xy 91.489139 -14.307851)
			(xy 91.561722 -14.329737) (xy 91.631568 -14.359214) (xy 91.697885 -14.395949) (xy 91.759921 -14.439524)
			(xy 91.816974 -14.489446) (xy 91.868398 -14.54515) (xy 91.913609 -14.606005) (xy 91.952096 -14.67132)
			(xy 91.983422 -14.740356) (xy 92.007232 -14.812331) (xy 92.023257 -14.886429) (xy 92.031316 -14.96181)
			(xy 92.03182 -14.999716) (xy 92.607895 -14.999716) (xy 92.61193 -14.924012) (xy 92.623989 -14.849167)
			(xy 92.643935 -14.776026) (xy 92.671542 -14.705421) (xy 92.706498 -14.63815) (xy 92.748406 -14.574975)
			(xy 92.796792 -14.516613) (xy 92.851108 -14.463725) (xy 92.910737 -14.41691) (xy 92.975005 -14.376698)
			(xy 93.043182 -14.343546) (xy 93.114498 -14.317828) (xy 93.188143 -14.299836) (xy 93.263283 -14.289774)
			(xy 93.339067 -14.287755) (xy 93.414637 -14.293804) (xy 93.489135 -14.307851) (xy 93.561718 -14.329737)
			(xy 93.631564 -14.359214) (xy 93.697881 -14.395949) (xy 93.759917 -14.439524) (xy 93.81697 -14.489446)
			(xy 93.868394 -14.54515) (xy 93.913605 -14.606005) (xy 93.952092 -14.67132) (xy 93.983418 -14.740356)
			(xy 94.007228 -14.812331) (xy 94.023253 -14.886429) (xy 94.031312 -14.96181) (xy 94.031816 -14.999716)
			(xy 94.031312 -15.037622) (xy 94.023253 -15.113003) (xy 94.007228 -15.187101) (xy 93.983418 -15.259076)
			(xy 93.952092 -15.328112) (xy 93.913605 -15.393427) (xy 93.868394 -15.454282) (xy 93.81697 -15.509986)
			(xy 93.759917 -15.559908) (xy 93.697881 -15.603483) (xy 93.631564 -15.640218) (xy 93.561718 -15.669695)
			(xy 93.489135 -15.691581) (xy 93.414637 -15.705628) (xy 93.339067 -15.711677) (xy 93.263283 -15.709658)
			(xy 93.188143 -15.699596) (xy 93.114498 -15.681604) (xy 93.043182 -15.655886) (xy 92.975005 -15.622734)
			(xy 92.910737 -15.582522) (xy 92.851108 -15.535707) (xy 92.796792 -15.482819) (xy 92.748406 -15.424457)
			(xy 92.706498 -15.361282) (xy 92.671542 -15.294011) (xy 92.643935 -15.223406) (xy 92.623989 -15.150265)
			(xy 92.61193 -15.07542) (xy 92.607895 -14.999716) (xy 92.03182 -14.999716) (xy 92.031316 -15.037622)
			(xy 92.023257 -15.113003) (xy 92.007232 -15.187101) (xy 91.983422 -15.259076) (xy 91.952096 -15.328112)
			(xy 91.913609 -15.393427) (xy 91.868398 -15.454282) (xy 91.816974 -15.509986) (xy 91.759921 -15.559908)
			(xy 91.697885 -15.603483) (xy 91.631568 -15.640218) (xy 91.561722 -15.669695) (xy 91.489139 -15.691581)
			(xy 91.414641 -15.705628) (xy 91.339071 -15.711677) (xy 91.263287 -15.709658) (xy 91.188147 -15.699596)
			(xy 91.114502 -15.681604) (xy 91.043186 -15.655886) (xy 90.975009 -15.622734) (xy 90.910741 -15.582522)
			(xy 90.851112 -15.535707) (xy 90.796796 -15.482819) (xy 90.74841 -15.424457) (xy 90.706502 -15.361282)
			(xy 90.671546 -15.294011) (xy 90.643939 -15.223406) (xy 90.623993 -15.150265) (xy 90.611934 -15.07542)
			(xy 90.607899 -14.999716) (xy 2.1844 -14.999716) (xy 2.1844 -16.542957) (xy 10.382999 -16.542957)
			(xy 10.382999 -16.457231) (xy 10.390909 -16.371871) (xy 10.406661 -16.287604) (xy 10.430121 -16.205151)
			(xy 10.461089 -16.125214) (xy 10.4993 -16.048475) (xy 10.544429 -15.975589) (xy 10.59609 -15.907178)
			(xy 10.653844 -15.843826) (xy 10.717196 -15.786072) (xy 10.785607 -15.734411) (xy 10.858493 -15.689282)
			(xy 10.935232 -15.651071) (xy 11.015169 -15.620103) (xy 11.097622 -15.596643) (xy 11.181889 -15.580891)
			(xy 11.267249 -15.572981) (xy 11.352975 -15.572981) (xy 11.438335 -15.580891) (xy 11.522602 -15.596643)
			(xy 11.605055 -15.620103) (xy 11.684992 -15.651071) (xy 11.761731 -15.689282) (xy 11.834617 -15.734411)
			(xy 11.903028 -15.786072) (xy 11.96638 -15.843826) (xy 12.024134 -15.907178) (xy 12.075795 -15.975589)
			(xy 12.120924 -16.048475) (xy 12.159135 -16.125214) (xy 12.174417 -16.164661) (xy 34.594792 -16.164661)
			(xy 34.594792 -16.093339) (xy 34.602778 -16.022465) (xy 34.618648 -15.95293) (xy 34.642205 -15.88561)
			(xy 34.67315 -15.821351) (xy 34.711096 -15.76096) (xy 34.755565 -15.705198) (xy 34.805998 -15.654765)
			(xy 34.86176 -15.610296) (xy 34.922151 -15.57235) (xy 34.98641 -15.541405) (xy 35.05373 -15.517848)
			(xy 35.123265 -15.501978) (xy 35.194139 -15.493992) (xy 35.265461 -15.493992) (xy 35.336335 -15.501978)
			(xy 35.40587 -15.517848) (xy 35.47319 -15.541405) (xy 35.537449 -15.57235) (xy 35.59784 -15.610296)
			(xy 35.653602 -15.654765) (xy 35.704035 -15.705198) (xy 35.748504 -15.76096) (xy 35.78645 -15.821351)
			(xy 35.817395 -15.88561) (xy 35.840952 -15.95293) (xy 35.856822 -16.022465) (xy 35.864808 -16.093339)
			(xy 35.865308 -16.129) (xy 35.864808 -16.164661) (xy 35.856822 -16.235535) (xy 35.840952 -16.30507)
			(xy 35.817395 -16.37239) (xy 35.78645 -16.436649) (xy 35.748504 -16.49704) (xy 35.704035 -16.552802)
			(xy 35.685776 -16.571061) (xy 39.954192 -16.571061) (xy 39.954192 -16.499739) (xy 39.962178 -16.428865)
			(xy 39.978048 -16.35933) (xy 40.001605 -16.29201) (xy 40.03255 -16.227751) (xy 40.070496 -16.16736)
			(xy 40.114965 -16.111598) (xy 40.165398 -16.061165) (xy 40.22116 -16.016696) (xy 40.281551 -15.97875)
			(xy 40.34581 -15.947805) (xy 40.41313 -15.924248) (xy 40.482665 -15.908378) (xy 40.553539 -15.900392)
			(xy 40.624861 -15.900392) (xy 40.695735 -15.908378) (xy 40.76527 -15.924248) (xy 40.83259 -15.947805)
			(xy 40.896849 -15.97875) (xy 40.95724 -16.016696) (xy 41.013002 -16.061165) (xy 41.063435 -16.111598)
			(xy 41.107904 -16.16736) (xy 41.14585 -16.227751) (xy 41.176795 -16.29201) (xy 41.185561 -16.317061)
			(xy 49.047392 -16.317061) (xy 49.047392 -16.245739) (xy 49.055378 -16.174865) (xy 49.071248 -16.10533)
			(xy 49.094805 -16.03801) (xy 49.12575 -15.973751) (xy 49.163696 -15.91336) (xy 49.208165 -15.857598)
			(xy 49.258598 -15.807165) (xy 49.31436 -15.762696) (xy 49.374751 -15.72475) (xy 49.43901 -15.693805)
			(xy 49.50633 -15.670248) (xy 49.575865 -15.654378) (xy 49.646739 -15.646392) (xy 49.718061 -15.646392)
			(xy 49.788935 -15.654378) (xy 49.85847 -15.670248) (xy 49.92579 -15.693805) (xy 49.990049 -15.72475)
			(xy 50.05044 -15.762696) (xy 50.106202 -15.807165) (xy 50.156635 -15.857598) (xy 50.201104 -15.91336)
			(xy 50.23905 -15.973751) (xy 50.269995 -16.03801) (xy 50.293552 -16.10533) (xy 50.309422 -16.174865)
			(xy 50.317408 -16.245739) (xy 50.317908 -16.2814) (xy 50.317408 -16.317061) (xy 50.309422 -16.387935)
			(xy 50.293552 -16.45747) (xy 50.269995 -16.52479) (xy 50.23905 -16.589049) (xy 50.201104 -16.64944)
			(xy 50.156635 -16.705202) (xy 50.106202 -16.755635) (xy 50.05044 -16.800104) (xy 49.990049 -16.83805)
			(xy 49.92579 -16.868995) (xy 49.85847 -16.892552) (xy 49.788935 -16.908422) (xy 49.718061 -16.916408)
			(xy 49.646739 -16.916408) (xy 49.575865 -16.908422) (xy 49.50633 -16.892552) (xy 49.43901 -16.868995)
			(xy 49.374751 -16.83805) (xy 49.31436 -16.800104) (xy 49.258598 -16.755635) (xy 49.208165 -16.705202)
			(xy 49.163696 -16.64944) (xy 49.12575 -16.589049) (xy 49.094805 -16.52479) (xy 49.071248 -16.45747)
			(xy 49.055378 -16.387935) (xy 49.047392 -16.317061) (xy 41.185561 -16.317061) (xy 41.200352 -16.35933)
			(xy 41.216222 -16.428865) (xy 41.224208 -16.499739) (xy 41.224708 -16.5354) (xy 41.224208 -16.571061)
			(xy 41.216222 -16.641935) (xy 41.200352 -16.71147) (xy 41.176795 -16.77879) (xy 41.14585 -16.843049)
			(xy 41.107904 -16.90344) (xy 41.063435 -16.959202) (xy 41.013002 -17.009635) (xy 40.95724 -17.054104)
			(xy 40.896849 -17.09205) (xy 40.83259 -17.122995) (xy 40.76527 -17.146552) (xy 40.695735 -17.162422)
			(xy 40.624861 -17.170408) (xy 40.553539 -17.170408) (xy 40.482665 -17.162422) (xy 40.41313 -17.146552)
			(xy 40.34581 -17.122995) (xy 40.281551 -17.09205) (xy 40.22116 -17.054104) (xy 40.165398 -17.009635)
			(xy 40.114965 -16.959202) (xy 40.070496 -16.90344) (xy 40.03255 -16.843049) (xy 40.001605 -16.77879)
			(xy 39.978048 -16.71147) (xy 39.962178 -16.641935) (xy 39.954192 -16.571061) (xy 35.685776 -16.571061)
			(xy 35.653602 -16.603235) (xy 35.59784 -16.647704) (xy 35.537449 -16.68565) (xy 35.47319 -16.716595)
			(xy 35.40587 -16.740152) (xy 35.336335 -16.756022) (xy 35.265461 -16.764008) (xy 35.194139 -16.764008)
			(xy 35.123265 -16.756022) (xy 35.05373 -16.740152) (xy 34.98641 -16.716595) (xy 34.922151 -16.68565)
			(xy 34.86176 -16.647704) (xy 34.805998 -16.603235) (xy 34.755565 -16.552802) (xy 34.711096 -16.49704)
			(xy 34.67315 -16.436649) (xy 34.642205 -16.37239) (xy 34.618648 -16.30507) (xy 34.602778 -16.235535)
			(xy 34.594792 -16.164661) (xy 12.174417 -16.164661) (xy 12.190103 -16.205151) (xy 12.213563 -16.287604)
			(xy 12.229315 -16.371871) (xy 12.237225 -16.457231) (xy 12.23772 -16.500094) (xy 12.237225 -16.542957)
			(xy 12.229315 -16.628317) (xy 12.213563 -16.712584) (xy 12.190103 -16.795037) (xy 12.159135 -16.874974)
			(xy 12.120924 -16.951713) (xy 12.075795 -17.024599) (xy 12.024134 -17.09301) (xy 11.96638 -17.156362)
			(xy 11.903028 -17.214116) (xy 11.834617 -17.265777) (xy 11.761731 -17.310906) (xy 11.684992 -17.349117)
			(xy 11.605055 -17.380085) (xy 11.522602 -17.403545) (xy 11.438335 -17.419297) (xy 11.352975 -17.427207)
			(xy 11.267249 -17.427207) (xy 11.181889 -17.419297) (xy 11.097622 -17.403545) (xy 11.015169 -17.380085)
			(xy 10.935232 -17.349117) (xy 10.858493 -17.310906) (xy 10.785607 -17.265777) (xy 10.717196 -17.214116)
			(xy 10.653844 -17.156362) (xy 10.59609 -17.09301) (xy 10.544429 -17.024599) (xy 10.4993 -16.951713)
			(xy 10.461089 -16.874974) (xy 10.430121 -16.795037) (xy 10.406661 -16.712584) (xy 10.390909 -16.628317)
			(xy 10.382999 -16.542957) (xy 2.1844 -16.542957) (xy 2.1844 -19.267424) (xy 2.184943 -19.284049)
			(xy 2.193544 -19.316168) (xy 2.210153 -19.344973) (xy 2.233644 -19.368506) (xy 2.262418 -19.385168)
			(xy 2.294522 -19.393826) (xy 2.311146 -19.394424) (xy 2.355686 -19.395064) (xy 2.444366 -19.403525)
			(xy 2.53189 -19.420118) (xy 2.617514 -19.444701) (xy 2.70051 -19.477065) (xy 2.780172 -19.516936)
			(xy 2.855824 -19.563974) (xy 2.926822 -19.617779) (xy 2.992563 -19.677895) (xy 3.052488 -19.74381)
			(xy 3.106088 -19.814963) (xy 3.152907 -19.890751) (xy 3.192547 -19.970529) (xy 3.22467 -20.053618)
			(xy 3.249005 -20.139313) (xy 3.265344 -20.226884) (xy 3.273549 -20.315589) (xy 3.273549 -20.360132)
			(xy 3.882143 -20.360132) (xy 3.886146 -20.27227) (xy 3.898122 -20.185136) (xy 3.917973 -20.099452)
			(xy 3.945532 -20.015928) (xy 3.980573 -19.935256) (xy 4.022804 -19.858105) (xy 4.071876 -19.785114)
			(xy 4.127383 -19.716888) (xy 4.188863 -19.653992) (xy 4.255808 -19.596947) (xy 4.327663 -19.546226)
			(xy 4.403833 -19.502249) (xy 4.483686 -19.465381) (xy 4.566561 -19.435928) (xy 4.651771 -19.414132)
			(xy 4.73861 -19.400176) (xy 4.826358 -19.394173) (xy 4.914288 -19.396175) (xy 5.001673 -19.406165)
			(xy 5.087786 -19.42406) (xy 5.171916 -19.449711) (xy 5.253364 -19.482906) (xy 5.331457 -19.52337)
			(xy 5.362065 -19.542951) (xy 10.382999 -19.542951) (xy 10.382999 -19.457225) (xy 10.390909 -19.371865)
			(xy 10.406661 -19.287598) (xy 10.430121 -19.205145) (xy 10.461089 -19.125208) (xy 10.4993 -19.048469)
			(xy 10.544429 -18.975583) (xy 10.59609 -18.907172) (xy 10.653844 -18.84382) (xy 10.717196 -18.786066)
			(xy 10.785607 -18.734405) (xy 10.858493 -18.689276) (xy 10.935232 -18.651065) (xy 11.015169 -18.620097)
			(xy 11.097622 -18.596637) (xy 11.181889 -18.580885) (xy 11.267249 -18.572975) (xy 11.352975 -18.572975)
			(xy 11.438335 -18.580885) (xy 11.522602 -18.596637) (xy 11.605055 -18.620097) (xy 11.684992 -18.651065)
			(xy 11.761731 -18.689276) (xy 11.834617 -18.734405) (xy 11.903028 -18.786066) (xy 11.96638 -18.84382)
			(xy 12.024134 -18.907172) (xy 12.075795 -18.975583) (xy 12.120924 -19.048469) (xy 12.159135 -19.125208)
			(xy 12.190103 -19.205145) (xy 12.213563 -19.287598) (xy 12.229315 -19.371865) (xy 12.237225 -19.457225)
			(xy 12.23772 -19.500088) (xy 12.237351 -19.532039) (xy 19.996681 -19.532039) (xy 19.997529 -19.451093)
			(xy 20.006414 -19.370631) (xy 20.023247 -19.29145) (xy 20.047863 -19.214333) (xy 20.080018 -19.140042)
			(xy 20.119394 -19.069313) (xy 20.165601 -19.002846) (xy 20.218182 -18.941297) (xy 20.276617 -18.885276)
			(xy 20.340329 -18.835337) (xy 20.408686 -18.791974) (xy 20.481012 -18.755616) (xy 20.556592 -18.726622)
			(xy 20.634679 -18.70528) (xy 20.7145 -18.6918) (xy 20.754848 -18.688558) (xy 20.771336 -18.686912)
			(xy 20.802703 -18.676276) (xy 20.830275 -18.657924) (xy 20.852194 -18.633092) (xy 20.866981 -18.603455)
			(xy 20.87364 -18.57101) (xy 20.873212 -18.554446) (xy 20.871761 -18.527225) (xy 20.871635 -18.472707)
			(xy 20.872958 -18.44548) (xy 20.873378 -18.428951) (xy 20.866724 -18.396577) (xy 20.851966 -18.367004)
			(xy 20.830099 -18.342221) (xy 20.802594 -18.323896) (xy 20.7713 -18.313263) (xy 20.754848 -18.311622)
			(xy 20.714506 -18.308351) (xy 20.634695 -18.294868) (xy 20.556618 -18.273525) (xy 20.481047 -18.244531)
			(xy 20.40873 -18.208175) (xy 20.340382 -18.164816) (xy 20.276678 -18.114881) (xy 20.21825 -18.058866)
			(xy 20.165674 -17.997325) (xy 20.119472 -17.930865) (xy 20.080099 -17.860145) (xy 20.047946 -17.785864)
			(xy 20.023329 -17.708756) (xy 20.006494 -17.629585) (xy 19.997606 -17.549133) (xy 19.996753 -17.468195)
			(xy 20.003944 -17.387574) (xy 20.019108 -17.308065) (xy 20.042094 -17.230456) (xy 20.072675 -17.155514)
			(xy 20.110549 -17.08398) (xy 20.155341 -17.016561) (xy 20.206608 -16.953926) (xy 20.263844 -16.896692)
			(xy 20.326481 -16.845427) (xy 20.3939 -16.800637) (xy 20.465435 -16.762765) (xy 20.540379 -16.732186)
			(xy 20.617989 -16.709202) (xy 20.697498 -16.694041) (xy 20.77812 -16.686852) (xy 20.859057 -16.687708)
			(xy 20.939509 -16.696598) (xy 21.01868 -16.713436) (xy 21.095787 -16.738054) (xy 21.170067 -16.77021)
			(xy 21.240786 -16.809585) (xy 21.307244 -16.855789) (xy 21.368784 -16.908367) (xy 21.424797 -16.966797)
			(xy 21.47473 -17.030502) (xy 21.518087 -17.098851) (xy 21.554441 -17.17117) (xy 21.583432 -17.246741)
			(xy 21.604773 -17.324819) (xy 21.618253 -17.40463) (xy 21.621496 -17.444974) (xy 21.623168 -17.461457)
			(xy 21.633805 -17.492818) (xy 21.652154 -17.520386) (xy 21.67698 -17.542303) (xy 21.706609 -17.557093)
			(xy 21.739047 -17.56376) (xy 21.755608 -17.563338) (xy 21.782769 -17.561958) (xy 21.837159 -17.561958)
			(xy 21.86432 -17.563338) (xy 21.880887 -17.563732) (xy 21.91334 -17.557097) (xy 21.942986 -17.542324)
			(xy 21.967825 -17.52041) (xy 21.986179 -17.492837) (xy 21.996807 -17.461465) (xy 21.998432 -17.444974)
			(xy 22.001723 -17.404632) (xy 22.015204 -17.324816) (xy 22.036546 -17.246735) (xy 22.065538 -17.171159)
			(xy 22.101894 -17.098838) (xy 22.145254 -17.030485) (xy 22.195189 -16.966777) (xy 22.251206 -16.908345)
			(xy 22.312749 -16.855765) (xy 22.379211 -16.809559) (xy 22.449934 -16.770184) (xy 22.524219 -16.738028)
			(xy 22.60133 -16.713409) (xy 22.680505 -16.696573) (xy 22.760961 -16.687684) (xy 22.841902 -16.68683)
			(xy 22.922528 -16.694021) (xy 23.00204 -16.709186) (xy 23.079653 -16.732173) (xy 23.154599 -16.762756)
			(xy 23.226137 -16.800632) (xy 23.293558 -16.845427) (xy 23.356196 -16.896697) (xy 23.413432 -16.953936)
			(xy 23.464699 -17.016577) (xy 23.50949 -17.084) (xy 23.547362 -17.15554) (xy 23.577941 -17.230487)
			(xy 23.600925 -17.308101) (xy 23.616084 -17.387614) (xy 23.617099 -17.399) (xy 26.785314 -17.399)
			(xy 26.789385 -17.343378) (xy 26.801511 -17.288941) (xy 26.821434 -17.23685) (xy 26.84873 -17.188215)
			(xy 26.882816 -17.144072) (xy 26.922965 -17.105363) (xy 26.968323 -17.072912) (xy 27.017923 -17.047411)
			(xy 27.070707 -17.029404) (xy 27.12555 -17.019274) (xy 27.181284 -17.017237) (xy 27.236721 -17.023337)
			(xy 27.290678 -17.037443) (xy 27.342007 -17.059255) (xy 27.389613 -17.088309) (xy 27.432481 -17.123984)
			(xy 27.469698 -17.165521) (xy 27.500471 -17.212034) (xy 27.524143 -17.262531) (xy 27.540211 -17.315938)
			(xy 27.548331 -17.371114) (xy 27.54884 -17.399) (xy 27.548376 -17.4244) (xy 29.325314 -17.4244) (xy 29.329385 -17.368778)
			(xy 29.341511 -17.314341) (xy 29.361434 -17.26225) (xy 29.38873 -17.213615) (xy 29.422816 -17.169472)
			(xy 29.462965 -17.130763) (xy 29.508323 -17.098312) (xy 29.557923 -17.072811) (xy 29.610707 -17.054804)
			(xy 29.66555 -17.044674) (xy 29.721284 -17.042637) (xy 29.776721 -17.048737) (xy 29.830678 -17.062843)
			(xy 29.882007 -17.084655) (xy 29.929613 -17.113709) (xy 29.972481 -17.149384) (xy 30.009698 -17.190921)
			(xy 30.040471 -17.237434) (xy 30.064143 -17.287931) (xy 30.080211 -17.341338) (xy 30.088331 -17.396514)
			(xy 30.08884 -17.4244) (xy 30.088331 -17.452286) (xy 30.080211 -17.507462) (xy 30.064143 -17.560869)
			(xy 30.040471 -17.611366) (xy 30.009698 -17.657879) (xy 29.972481 -17.699416) (xy 29.929613 -17.735091)
			(xy 29.882007 -17.764145) (xy 29.830678 -17.785957) (xy 29.776721 -17.800063) (xy 29.721284 -17.806163)
			(xy 29.66555 -17.804126) (xy 29.610707 -17.793996) (xy 29.557923 -17.775989) (xy 29.508323 -17.750488)
			(xy 29.462965 -17.718037) (xy 29.422816 -17.679328) (xy 29.38873 -17.635185) (xy 29.361434 -17.58655)
			(xy 29.341511 -17.534459) (xy 29.329385 -17.480022) (xy 29.325314 -17.4244) (xy 27.548376 -17.4244)
			(xy 27.548331 -17.426886) (xy 27.540211 -17.482062) (xy 27.524143 -17.535469) (xy 27.500471 -17.585966)
			(xy 27.469698 -17.632479) (xy 27.432481 -17.674016) (xy 27.389613 -17.709691) (xy 27.342007 -17.738745)
			(xy 27.290678 -17.760557) (xy 27.236721 -17.774663) (xy 27.181284 -17.780763) (xy 27.12555 -17.778726)
			(xy 27.070707 -17.768596) (xy 27.017923 -17.750589) (xy 26.968323 -17.725088) (xy 26.922965 -17.692637)
			(xy 26.882816 -17.653928) (xy 26.84873 -17.609785) (xy 26.821434 -17.56115) (xy 26.801511 -17.509059)
			(xy 26.789385 -17.454622) (xy 26.785314 -17.399) (xy 23.617099 -17.399) (xy 23.623271 -17.46824)
			(xy 23.622414 -17.549181) (xy 23.613521 -17.629637) (xy 23.59668 -17.708811) (xy 23.572057 -17.785921)
			(xy 23.539897 -17.860204) (xy 23.500518 -17.930925) (xy 23.454308 -17.997385) (xy 23.444725 -18.0086)
			(xy 30.595314 -18.0086) (xy 30.599385 -17.952978) (xy 30.611511 -17.898541) (xy 30.631434 -17.84645)
			(xy 30.65873 -17.797815) (xy 30.692816 -17.753672) (xy 30.732965 -17.714963) (xy 30.778323 -17.682512)
			(xy 30.827923 -17.657011) (xy 30.880707 -17.639004) (xy 30.93555 -17.628874) (xy 30.991284 -17.626837)
			(xy 31.046721 -17.632937) (xy 31.100678 -17.647043) (xy 31.152007 -17.668855) (xy 31.18446 -17.688661)
			(xy 71.399392 -17.688661) (xy 71.399392 -17.617339) (xy 71.407378 -17.546465) (xy 71.423248 -17.47693)
			(xy 71.446805 -17.40961) (xy 71.47775 -17.345351) (xy 71.515696 -17.28496) (xy 71.560165 -17.229198)
			(xy 71.610598 -17.178765) (xy 71.66636 -17.134296) (xy 71.726751 -17.09635) (xy 71.79101 -17.065405)
			(xy 71.85833 -17.041848) (xy 71.927865 -17.025978) (xy 71.998739 -17.017992) (xy 72.070061 -17.017992)
			(xy 72.140935 -17.025978) (xy 72.21047 -17.041848) (xy 72.27779 -17.065405) (xy 72.342049 -17.09635)
			(xy 72.40244 -17.134296) (xy 72.458202 -17.178765) (xy 72.508635 -17.229198) (xy 72.553104 -17.28496)
			(xy 72.59105 -17.345351) (xy 72.621995 -17.40961) (xy 72.645552 -17.47693) (xy 72.661422 -17.546465)
			(xy 72.669408 -17.617339) (xy 72.669908 -17.653) (xy 72.669408 -17.688661) (xy 72.661422 -17.759535)
			(xy 72.645552 -17.82907) (xy 72.621995 -17.89639) (xy 72.59105 -17.960649) (xy 72.553104 -18.02104)
			(xy 72.508635 -18.076802) (xy 72.458202 -18.127235) (xy 72.40244 -18.171704) (xy 72.342049 -18.20965)
			(xy 72.27779 -18.240595) (xy 72.21047 -18.264152) (xy 72.140935 -18.280022) (xy 72.070061 -18.288008)
			(xy 71.998739 -18.288008) (xy 71.927865 -18.280022) (xy 71.85833 -18.264152) (xy 71.79101 -18.240595)
			(xy 71.726751 -18.20965) (xy 71.66636 -18.171704) (xy 71.610598 -18.127235) (xy 71.560165 -18.076802)
			(xy 71.515696 -18.02104) (xy 71.47775 -17.960649) (xy 71.446805 -17.89639) (xy 71.423248 -17.82907)
			(xy 71.407378 -17.759535) (xy 71.399392 -17.688661) (xy 31.18446 -17.688661) (xy 31.199613 -17.697909)
			(xy 31.242481 -17.733584) (xy 31.279698 -17.775121) (xy 31.310471 -17.821634) (xy 31.334143 -17.872131)
			(xy 31.350211 -17.925538) (xy 31.358331 -17.980714) (xy 31.35884 -18.0086) (xy 31.358331 -18.036486)
			(xy 31.350211 -18.091662) (xy 31.334143 -18.145069) (xy 31.310471 -18.195566) (xy 31.279698 -18.242079)
			(xy 31.242481 -18.283616) (xy 31.199613 -18.319291) (xy 31.152007 -18.348345) (xy 31.100678 -18.370157)
			(xy 31.046721 -18.384263) (xy 30.991284 -18.390363) (xy 30.93555 -18.388326) (xy 30.880707 -18.378196)
			(xy 30.827923 -18.360189) (xy 30.778323 -18.334688) (xy 30.732965 -18.302237) (xy 30.692816 -18.263528)
			(xy 30.65873 -18.219385) (xy 30.631434 -18.17075) (xy 30.611511 -18.118659) (xy 30.599385 -18.064222)
			(xy 30.595314 -18.0086) (xy 23.444725 -18.0086) (xy 23.401726 -18.058925) (xy 23.34329 -18.114939)
			(xy 23.27958 -18.16487) (xy 23.211225 -18.208227) (xy 23.138901 -18.244579) (xy 23.063324 -18.273567)
			(xy 22.985242 -18.294905) (xy 22.905426 -18.308382) (xy 22.86508 -18.311622) (xy 22.848612 -18.31324)
			(xy 22.817287 -18.323865) (xy 22.789744 -18.342184) (xy 22.767834 -18.366966) (xy 22.753028 -18.396546)
			(xy 22.746321 -18.428937) (xy 22.746716 -18.44548) (xy 22.74824 -18.50009) (xy 22.746716 -18.554446)
			(xy 22.746248 -18.571015) (xy 22.752892 -18.603476) (xy 22.767678 -18.633129) (xy 22.789607 -18.65797)
			(xy 22.817196 -18.67632) (xy 22.848583 -18.68694) (xy 22.86508 -18.688558) (xy 22.905431 -18.691788)
			(xy 22.9209 -18.6944) (xy 28.055314 -18.6944) (xy 28.059385 -18.638778) (xy 28.071511 -18.584341)
			(xy 28.091434 -18.53225) (xy 28.11873 -18.483615) (xy 28.152816 -18.439472) (xy 28.192965 -18.400763)
			(xy 28.238323 -18.368312) (xy 28.287923 -18.342811) (xy 28.340707 -18.324804) (xy 28.39555 -18.314674)
			(xy 28.451284 -18.312637) (xy 28.506721 -18.318737) (xy 28.560678 -18.332843) (xy 28.612007 -18.354655)
			(xy 28.659613 -18.383709) (xy 28.702481 -18.419384) (xy 28.739698 -18.460921) (xy 28.770471 -18.507434)
			(xy 28.791485 -18.552261) (xy 35.966392 -18.552261) (xy 35.966392 -18.480939) (xy 35.974378 -18.410065)
			(xy 35.990248 -18.34053) (xy 36.013805 -18.27321) (xy 36.04475 -18.208951) (xy 36.082696 -18.14856)
			(xy 36.127165 -18.092798) (xy 36.177598 -18.042365) (xy 36.23336 -17.997896) (xy 36.293751 -17.95995)
			(xy 36.35801 -17.929005) (xy 36.42533 -17.905448) (xy 36.494865 -17.889578) (xy 36.565739 -17.881592)
			(xy 36.637061 -17.881592) (xy 36.707935 -17.889578) (xy 36.77747 -17.905448) (xy 36.84479 -17.929005)
			(xy 36.909049 -17.95995) (xy 36.96944 -17.997896) (xy 37.025202 -18.042365) (xy 37.075635 -18.092798)
			(xy 37.120104 -18.14856) (xy 37.15805 -18.208951) (xy 37.188995 -18.27321) (xy 37.212552 -18.34053)
			(xy 37.228422 -18.410065) (xy 37.236408 -18.480939) (xy 37.236908 -18.5166) (xy 37.236408 -18.552261)
			(xy 37.228422 -18.623135) (xy 37.221409 -18.653861) (xy 43.637192 -18.653861) (xy 43.637192 -18.582539)
			(xy 43.645178 -18.511665) (xy 43.661048 -18.44213) (xy 43.684605 -18.37481) (xy 43.71555 -18.310551)
			(xy 43.753496 -18.25016) (xy 43.797965 -18.194398) (xy 43.848398 -18.143965) (xy 43.90416 -18.099496)
			(xy 43.964551 -18.06155) (xy 44.02881 -18.030605) (xy 44.09613 -18.007048) (xy 44.165665 -17.991178)
			(xy 44.236539 -17.983192) (xy 44.307861 -17.983192) (xy 44.378735 -17.991178) (xy 44.44827 -18.007048)
			(xy 44.51559 -18.030605) (xy 44.579849 -18.06155) (xy 44.64024 -18.099496) (xy 44.696002 -18.143965)
			(xy 44.746435 -18.194398) (xy 44.790904 -18.25016) (xy 44.82885 -18.310551) (xy 44.859795 -18.37481)
			(xy 44.883352 -18.44213) (xy 44.896893 -18.501461) (xy 51.866792 -18.501461) (xy 51.866792 -18.430139)
			(xy 51.874778 -18.359265) (xy 51.890648 -18.28973) (xy 51.914205 -18.22241) (xy 51.94515 -18.158151)
			(xy 51.983096 -18.09776) (xy 52.027565 -18.041998) (xy 52.077998 -17.991565) (xy 52.13376 -17.947096)
			(xy 52.194151 -17.90915) (xy 52.25841 -17.878205) (xy 52.32573 -17.854648) (xy 52.395265 -17.838778)
			(xy 52.466139 -17.830792) (xy 52.537461 -17.830792) (xy 52.608335 -17.838778) (xy 52.67787 -17.854648)
			(xy 52.74519 -17.878205) (xy 52.809449 -17.90915) (xy 52.86984 -17.947096) (xy 52.925602 -17.991565)
			(xy 52.976035 -18.041998) (xy 53.020504 -18.09776) (xy 53.05845 -18.158151) (xy 53.089395 -18.22241)
			(xy 53.112952 -18.28973) (xy 53.128822 -18.359265) (xy 53.136808 -18.430139) (xy 53.137308 -18.4658)
			(xy 53.136808 -18.501461) (xy 53.128822 -18.572335) (xy 53.112952 -18.64187) (xy 53.089395 -18.70919)
			(xy 53.05845 -18.773449) (xy 53.020504 -18.83384) (xy 52.976035 -18.889602) (xy 52.957776 -18.907861)
			(xy 63.982592 -18.907861) (xy 63.982592 -18.836539) (xy 63.990578 -18.765665) (xy 64.006448 -18.69613)
			(xy 64.030005 -18.62881) (xy 64.06095 -18.564551) (xy 64.098896 -18.50416) (xy 64.143365 -18.448398)
			(xy 64.193798 -18.397965) (xy 64.24956 -18.353496) (xy 64.309951 -18.31555) (xy 64.37421 -18.284605)
			(xy 64.44153 -18.261048) (xy 64.511065 -18.245178) (xy 64.581939 -18.237192) (xy 64.653261 -18.237192)
			(xy 64.724135 -18.245178) (xy 64.79367 -18.261048) (xy 64.86099 -18.284605) (xy 64.925249 -18.31555)
			(xy 64.98564 -18.353496) (xy 65.041402 -18.397965) (xy 65.091835 -18.448398) (xy 65.136304 -18.50416)
			(xy 65.17425 -18.564551) (xy 65.205195 -18.62881) (xy 65.228752 -18.69613) (xy 65.244622 -18.765665)
			(xy 65.252608 -18.836539) (xy 65.253108 -18.8722) (xy 65.252608 -18.907861) (xy 65.244622 -18.978735)
			(xy 65.228752 -19.04827) (xy 65.205195 -19.11559) (xy 65.17425 -19.179849) (xy 65.136304 -19.24024)
			(xy 65.091835 -19.296002) (xy 65.041402 -19.346435) (xy 64.98564 -19.390904) (xy 64.925249 -19.42885)
			(xy 64.86099 -19.459795) (xy 64.79367 -19.483352) (xy 64.724135 -19.499222) (xy 64.653261 -19.507208)
			(xy 64.581939 -19.507208) (xy 64.511065 -19.499222) (xy 64.44153 -19.483352) (xy 64.37421 -19.459795)
			(xy 64.309951 -19.42885) (xy 64.24956 -19.390904) (xy 64.193798 -19.346435) (xy 64.143365 -19.296002)
			(xy 64.098896 -19.24024) (xy 64.06095 -19.179849) (xy 64.030005 -19.11559) (xy 64.006448 -19.04827)
			(xy 63.990578 -18.978735) (xy 63.982592 -18.907861) (xy 52.957776 -18.907861) (xy 52.925602 -18.940035)
			(xy 52.86984 -18.984504) (xy 52.809449 -19.02245) (xy 52.74519 -19.053395) (xy 52.67787 -19.076952)
			(xy 52.608335 -19.092822) (xy 52.537461 -19.100808) (xy 52.466139 -19.100808) (xy 52.395265 -19.092822)
			(xy 52.32573 -19.076952) (xy 52.25841 -19.053395) (xy 52.194151 -19.02245) (xy 52.13376 -18.984504)
			(xy 52.077998 -18.940035) (xy 52.027565 -18.889602) (xy 51.983096 -18.83384) (xy 51.94515 -18.773449)
			(xy 51.914205 -18.70919) (xy 51.890648 -18.64187) (xy 51.874778 -18.572335) (xy 51.866792 -18.501461)
			(xy 44.896893 -18.501461) (xy 44.899222 -18.511665) (xy 44.907208 -18.582539) (xy 44.907708 -18.6182)
			(xy 44.907208 -18.653861) (xy 44.899222 -18.724735) (xy 44.883352 -18.79427) (xy 44.859795 -18.86159)
			(xy 44.82885 -18.925849) (xy 44.790904 -18.98624) (xy 44.746435 -19.042002) (xy 44.696002 -19.092435)
			(xy 44.64024 -19.136904) (xy 44.579849 -19.17485) (xy 44.51559 -19.205795) (xy 44.44827 -19.229352)
			(xy 44.378735 -19.245222) (xy 44.307861 -19.253208) (xy 44.236539 -19.253208) (xy 44.165665 -19.245222)
			(xy 44.09613 -19.229352) (xy 44.02881 -19.205795) (xy 43.964551 -19.17485) (xy 43.90416 -19.136904)
			(xy 43.848398 -19.092435) (xy 43.797965 -19.042002) (xy 43.753496 -18.98624) (xy 43.71555 -18.925849)
			(xy 43.684605 -18.86159) (xy 43.661048 -18.79427) (xy 43.645178 -18.724735) (xy 43.637192 -18.653861)
			(xy 37.221409 -18.653861) (xy 37.212552 -18.69267) (xy 37.188995 -18.75999) (xy 37.15805 -18.824249)
			(xy 37.120104 -18.88464) (xy 37.075635 -18.940402) (xy 37.025202 -18.990835) (xy 36.96944 -19.035304)
			(xy 36.909049 -19.07325) (xy 36.84479 -19.104195) (xy 36.77747 -19.127752) (xy 36.707935 -19.143622)
			(xy 36.637061 -19.151608) (xy 36.565739 -19.151608) (xy 36.494865 -19.143622) (xy 36.42533 -19.127752)
			(xy 36.35801 -19.104195) (xy 36.293751 -19.07325) (xy 36.23336 -19.035304) (xy 36.177598 -18.990835)
			(xy 36.127165 -18.940402) (xy 36.082696 -18.88464) (xy 36.04475 -18.824249) (xy 36.013805 -18.75999)
			(xy 35.990248 -18.69267) (xy 35.974378 -18.623135) (xy 35.966392 -18.552261) (xy 28.791485 -18.552261)
			(xy 28.794143 -18.557931) (xy 28.810211 -18.611338) (xy 28.818331 -18.666514) (xy 28.81884 -18.6944)
			(xy 28.818331 -18.722286) (xy 28.810211 -18.777462) (xy 28.794143 -18.830869) (xy 28.770471 -18.881366)
			(xy 28.739698 -18.927879) (xy 28.702481 -18.969416) (xy 28.659613 -19.005091) (xy 28.612007 -19.034145)
			(xy 28.560678 -19.055957) (xy 28.506721 -19.070063) (xy 28.451284 -19.076163) (xy 28.39555 -19.074126)
			(xy 28.340707 -19.063996) (xy 28.287923 -19.045989) (xy 28.238323 -19.020488) (xy 28.192965 -18.988037)
			(xy 28.152816 -18.949328) (xy 28.11873 -18.905185) (xy 28.091434 -18.85655) (xy 28.071511 -18.804459)
			(xy 28.059385 -18.750022) (xy 28.055314 -18.6944) (xy 22.9209 -18.6944) (xy 22.985256 -18.705267)
			(xy 23.063347 -18.726608) (xy 23.138932 -18.755601) (xy 23.211262 -18.791959) (xy 23.279623 -18.835323)
			(xy 23.343339 -18.885263) (xy 23.401778 -18.941285) (xy 23.454363 -19.002836) (xy 23.500573 -19.069306)
			(xy 23.539952 -19.140037) (xy 23.57211 -19.214331) (xy 23.596728 -19.291452) (xy 23.613563 -19.370636)
			(xy 23.622449 -19.451102) (xy 23.623298 -19.532052) (xy 23.616101 -19.612686) (xy 23.60093 -19.692206)
			(xy 23.577934 -19.769826) (xy 23.547341 -19.844778) (xy 23.509454 -19.916319) (xy 23.464648 -19.983744)
			(xy 23.413365 -20.046383) (xy 23.356113 -20.103619) (xy 23.293459 -20.154884) (xy 23.226022 -20.199671)
			(xy 23.15447 -20.237538) (xy 23.07951 -20.26811) (xy 23.001883 -20.291084) (xy 22.922359 -20.306233)
			(xy 22.841723 -20.313407) (xy 22.760773 -20.312536) (xy 22.68031 -20.303627) (xy 22.60113 -20.286769)
			(xy 22.524016 -20.262129) (xy 22.449732 -20.22995) (xy 22.379011 -20.190552) (xy 22.312554 -20.144323)
			(xy 22.251019 -20.09172) (xy 22.195013 -20.033265) (xy 22.145091 -19.969536) (xy 22.101746 -19.901163)
			(xy 22.065408 -19.828822) (xy 22.036436 -19.753229) (xy 22.015117 -19.675132) (xy 22.001662 -19.595303)
			(xy 21.998432 -19.554952) (xy 21.996701 -19.538497) (xy 21.986024 -19.507197) (xy 21.967663 -19.479692)
			(xy 21.942851 -19.457828) (xy 21.913253 -19.443074) (xy 21.880858 -19.436422) (xy 21.86432 -19.436842)
			(xy 21.837159 -19.438222) (xy 21.782769 -19.438222) (xy 21.755608 -19.436842) (xy 21.739058 -19.436381)
			(xy 21.706631 -19.442996) (xy 21.677 -19.457738) (xy 21.652164 -19.479613) (xy 21.633798 -19.507145)
			(xy 21.623141 -19.538478) (xy 21.621496 -19.554952) (xy 21.618257 -19.595301) (xy 21.6048 -19.675125)
			(xy 21.58348 -19.753218) (xy 21.554508 -19.828807) (xy 21.51817 -19.901143) (xy 21.474827 -19.969512)
			(xy 21.424906 -20.033238) (xy 21.368901 -20.091689) (xy 21.307367 -20.144288) (xy 21.240913 -20.190514)
			(xy 21.170195 -20.229909) (xy 21.095914 -20.262085) (xy 21.018804 -20.286723) (xy 20.939627 -20.303579)
			(xy 20.859168 -20.312487) (xy 20.778222 -20.313358) (xy 20.69759 -20.306183) (xy 20.618069 -20.291035)
			(xy 20.540447 -20.268061) (xy 20.46549 -20.237491) (xy 20.393941 -20.199626) (xy 20.326508 -20.15484)
			(xy 20.263856 -20.103578) (xy 20.206608 -20.046345) (xy 20.155327 -19.983708) (xy 20.110522 -19.916288)
			(xy 20.072637 -19.844749) (xy 20.042045 -19.769802) (xy 20.01905 -19.692186) (xy 20.003879 -19.612669)
			(xy 19.996681 -19.532039) (xy 12.237351 -19.532039) (xy 12.237225 -19.542951) (xy 12.229315 -19.628311)
			(xy 12.213563 -19.712578) (xy 12.190103 -19.795031) (xy 12.159135 -19.874968) (xy 12.120924 -19.951707)
			(xy 12.075795 -20.024593) (xy 12.024134 -20.093004) (xy 11.96638 -20.156356) (xy 11.903028 -20.21411)
			(xy 11.834617 -20.265771) (xy 11.761731 -20.3109) (xy 11.684992 -20.349111) (xy 11.605055 -20.380079)
			(xy 11.522602 -20.403539) (xy 11.438335 -20.419291) (xy 11.352975 -20.427201) (xy 11.267249 -20.427201)
			(xy 11.181889 -20.419291) (xy 11.097622 -20.403539) (xy 11.015169 -20.380079) (xy 10.935232 -20.349111)
			(xy 10.858493 -20.3109) (xy 10.785607 -20.265771) (xy 10.717196 -20.21411) (xy 10.653844 -20.156356)
			(xy 10.59609 -20.093004) (xy 10.544429 -20.024593) (xy 10.4993 -19.951707) (xy 10.461089 -19.874968)
			(xy 10.430121 -19.795031) (xy 10.406661 -19.712578) (xy 10.390909 -19.628311) (xy 10.382999 -19.542951)
			(xy 5.362065 -19.542951) (xy 5.405546 -19.570768) (xy 5.475018 -19.624707) (xy 5.539297 -19.68474)
			(xy 5.597851 -19.750369) (xy 5.650195 -19.821051) (xy 5.695894 -19.8962) (xy 5.73457 -19.975193)
			(xy 5.765902 -20.057376) (xy 5.789632 -20.142068) (xy 5.805562 -20.228567) (xy 5.81356 -20.316155)
			(xy 5.81406 -20.360132) (xy 5.81356 -20.404109) (xy 5.805562 -20.491697) (xy 5.789632 -20.578196)
			(xy 5.765902 -20.662888) (xy 5.73457 -20.745071) (xy 5.695894 -20.824064) (xy 5.650195 -20.899213)
			(xy 5.597851 -20.969895) (xy 5.539297 -21.035524) (xy 5.475018 -21.095557) (xy 5.405546 -21.149496)
			(xy 5.331457 -21.196894) (xy 5.253364 -21.237358) (xy 5.171916 -21.270553) (xy 5.087786 -21.296204)
			(xy 5.001673 -21.314099) (xy 4.914288 -21.324089) (xy 4.826358 -21.326091) (xy 4.73861 -21.320088)
			(xy 4.651771 -21.306132) (xy 4.566561 -21.284336) (xy 4.483686 -21.254883) (xy 4.403833 -21.218015)
			(xy 4.327663 -21.174038) (xy 4.255808 -21.123317) (xy 4.188863 -21.066272) (xy 4.127383 -21.003376)
			(xy 4.071876 -20.93515) (xy 4.022804 -20.862159) (xy 3.980573 -20.785008) (xy 3.945532 -20.704336)
			(xy 3.917973 -20.620812) (xy 3.898122 -20.535128) (xy 3.886146 -20.447994) (xy 3.882143 -20.360132)
			(xy 3.273549 -20.360132) (xy 3.273549 -20.404671) (xy 3.265344 -20.493376) (xy 3.249005 -20.580948)
			(xy 3.22467 -20.666642) (xy 3.192547 -20.749731) (xy 3.152907 -20.829509) (xy 3.106088 -20.905297)
			(xy 3.052488 -20.97645) (xy 2.992563 -21.042365) (xy 2.926822 -21.102481) (xy 2.855824 -21.156286)
			(xy 2.780172 -21.203324) (xy 2.70051 -21.243195) (xy 2.617514 -21.275559) (xy 2.53189 -21.300142)
			(xy 2.444366 -21.316735) (xy 2.355686 -21.325196) (xy 2.311146 -21.32584) (xy 2.294522 -21.326414)
			(xy 2.262419 -21.335075) (xy 2.233647 -21.351742) (xy 2.210162 -21.375281) (xy 2.193562 -21.404091)
			(xy 2.184975 -21.436214) (xy 2.1844 -21.45284) (xy 2.1844 -21.500084) (xy 19.996152 -21.500084) (xy 20.000196 -21.419054)
			(xy 20.012288 -21.33883) (xy 20.032307 -21.260208) (xy 20.060056 -21.18397) (xy 20.095257 -21.110874)
			(xy 20.137561 -21.041646) (xy 20.186548 -20.976974) (xy 20.241731 -20.917502) (xy 20.302561 -20.863819)
			(xy 20.368434 -20.816459) (xy 20.438695 -20.775894) (xy 20.512646 -20.742526) (xy 20.589552 -20.716687)
			(xy 20.668649 -20.698634) (xy 20.74915 -20.688546) (xy 20.830255 -20.686523) (xy 20.911159 -20.692586)
			(xy 20.991057 -20.706674) (xy 21.069155 -20.728647) (xy 21.144677 -20.758288) (xy 21.216873 -20.7953)
			(xy 21.285025 -20.839317) (xy 21.348455 -20.889902) (xy 21.406534 -20.94655) (xy 21.458684 -21.0087)
			(xy 21.504386 -21.075733) (xy 21.543187 -21.146983) (xy 21.574701 -21.221743) (xy 21.598615 -21.299269)
			(xy 21.61469 -21.378791) (xy 21.622768 -21.459519) (xy 21.623274 -21.500084) (xy 21.996148 -21.500084)
			(xy 22.000192 -21.419054) (xy 22.012284 -21.33883) (xy 22.032303 -21.260208) (xy 22.060052 -21.18397)
			(xy 22.095253 -21.110874) (xy 22.137557 -21.041646) (xy 22.186544 -20.976974) (xy 22.241727 -20.917502)
			(xy 22.302557 -20.863819) (xy 22.36843 -20.816459) (xy 22.438691 -20.775894) (xy 22.512642 -20.742526)
			(xy 22.589548 -20.716687) (xy 22.668645 -20.698634) (xy 22.749146 -20.688546) (xy 22.830251 -20.686523)
			(xy 22.911155 -20.692586) (xy 22.991053 -20.706674) (xy 23.069151 -20.728647) (xy 23.144673 -20.758288)
			(xy 23.216869 -20.7953) (xy 23.285021 -20.839317) (xy 23.316057 -20.864068) (xy 26.785314 -20.864068)
			(xy 26.789385 -20.808446) (xy 26.801511 -20.754009) (xy 26.821434 -20.701918) (xy 26.84873 -20.653283)
			(xy 26.882816 -20.60914) (xy 26.922965 -20.570431) (xy 26.968323 -20.53798) (xy 27.017923 -20.512479)
			(xy 27.070707 -20.494472) (xy 27.12555 -20.484342) (xy 27.181284 -20.482305) (xy 27.236721 -20.488405)
			(xy 27.290678 -20.502511) (xy 27.342007 -20.524323) (xy 27.389613 -20.553377) (xy 27.432481 -20.589052)
			(xy 27.469698 -20.630589) (xy 27.500471 -20.677102) (xy 27.524143 -20.727599) (xy 27.540211 -20.781006)
			(xy 27.548331 -20.836182) (xy 27.54884 -20.864068) (xy 27.548331 -20.891954) (xy 27.544959 -20.914868)
			(xy 28.106114 -20.914868) (xy 28.110185 -20.859246) (xy 28.122311 -20.804809) (xy 28.142234 -20.752718)
			(xy 28.16953 -20.704083) (xy 28.203616 -20.65994) (xy 28.243765 -20.621231) (xy 28.289123 -20.58878)
			(xy 28.338723 -20.563279) (xy 28.391507 -20.545272) (xy 28.44635 -20.535142) (xy 28.502084 -20.533105)
			(xy 28.557521 -20.539205) (xy 28.611478 -20.553311) (xy 28.662807 -20.575123) (xy 28.710413 -20.604177)
			(xy 28.753281 -20.639852) (xy 28.790498 -20.681389) (xy 28.821271 -20.727902) (xy 28.844943 -20.778399)
			(xy 28.861011 -20.831806) (xy 28.869131 -20.886982) (xy 28.86964 -20.914868) (xy 28.869131 -20.942754)
			(xy 28.865759 -20.965668) (xy 29.376114 -20.965668) (xy 29.380185 -20.910046) (xy 29.392311 -20.855609)
			(xy 29.412234 -20.803518) (xy 29.43953 -20.754883) (xy 29.473616 -20.71074) (xy 29.513765 -20.672031)
			(xy 29.559123 -20.63958) (xy 29.608723 -20.614079) (xy 29.661507 -20.596072) (xy 29.71635 -20.585942)
			(xy 29.772084 -20.583905) (xy 29.827521 -20.590005) (xy 29.881478 -20.604111) (xy 29.932807 -20.625923)
			(xy 29.980413 -20.654977) (xy 30.023281 -20.690652) (xy 30.060498 -20.732189) (xy 30.091271 -20.778702)
			(xy 30.114943 -20.829199) (xy 30.131011 -20.882606) (xy 30.13848 -20.933357) (xy 30.79846 -20.933357)
			(xy 30.803541 -20.877812) (xy 30.816655 -20.823599) (xy 30.837521 -20.771872) (xy 30.865696 -20.723734)
			(xy 30.900578 -20.680211) (xy 30.941425 -20.642229) (xy 30.987367 -20.6106) (xy 31.037424 -20.585995)
			(xy 31.090529 -20.56894) (xy 31.145552 -20.559798) (xy 31.201319 -20.558765) (xy 31.229046 -20.561808)
			(xy 31.252129 -20.564202) (xy 31.298459 -20.561641) (xy 31.343555 -20.550712) (xy 31.385918 -20.53178)
			(xy 31.42414 -20.505472) (xy 31.456952 -20.472664) (xy 31.483265 -20.434445) (xy 31.502202 -20.392084)
			(xy 31.513136 -20.34699) (xy 31.515703 -20.30066) (xy 31.513272 -20.277582) (xy 31.510233 -20.249862)
			(xy 31.511274 -20.194108) (xy 31.520421 -20.1391) (xy 31.537478 -20.08601) (xy 31.562082 -20.035968)
			(xy 31.593709 -19.990041) (xy 31.631684 -19.949207) (xy 31.6752 -19.914337) (xy 31.723328 -19.886173)
			(xy 31.775044 -19.865315) (xy 31.829245 -19.852208) (xy 31.884776 -19.847131) (xy 31.940456 -19.850192)
			(xy 31.995096 -19.861327) (xy 32.047533 -19.880296) (xy 32.096651 -19.906698) (xy 32.141401 -19.939968)
			(xy 32.180832 -19.979399) (xy 32.214102 -20.024149) (xy 32.240504 -20.073267) (xy 32.259473 -20.125704)
			(xy 32.270608 -20.180344) (xy 32.273669 -20.236024) (xy 32.268592 -20.291555) (xy 32.255485 -20.345756)
			(xy 32.234627 -20.397472) (xy 32.206463 -20.4456) (xy 32.171593 -20.489116) (xy 32.130759 -20.527091)
			(xy 32.084832 -20.558718) (xy 32.03479 -20.583322) (xy 31.9817 -20.600379) (xy 31.926692 -20.609526)
			(xy 31.870938 -20.610567) (xy 31.843218 -20.607528) (xy 31.820141 -20.605056) (xy 31.773804 -20.607624)
			(xy 31.728703 -20.61856) (xy 31.686335 -20.6375) (xy 31.64811 -20.663817) (xy 31.615297 -20.696634)
			(xy 31.588985 -20.734863) (xy 31.57005 -20.777232) (xy 31.559119 -20.822335) (xy 31.556558 -20.868672)
			(xy 31.558992 -20.891754) (xy 31.562035 -20.919481) (xy 31.561002 -20.975248) (xy 31.55186 -21.030271)
			(xy 31.534805 -21.083376) (xy 31.5102 -21.133433) (xy 31.478571 -21.179375) (xy 31.440589 -21.220222)
			(xy 31.397066 -21.255104) (xy 31.348928 -21.283279) (xy 31.297201 -21.304145) (xy 31.242988 -21.317259)
			(xy 31.187443 -21.32234) (xy 31.13175 -21.31928) (xy 31.077096 -21.308146) (xy 31.024645 -21.289172)
			(xy 30.975515 -21.262765) (xy 30.930753 -21.229487) (xy 30.891313 -21.190047) (xy 30.858035 -21.145285)
			(xy 30.831628 -21.096155) (xy 30.812654 -21.043704) (xy 30.80152 -20.98905) (xy 30.79846 -20.933357)
			(xy 30.13848 -20.933357) (xy 30.139131 -20.937782) (xy 30.13964 -20.965668) (xy 30.139131 -20.993554)
			(xy 30.131011 -21.04873) (xy 30.114943 -21.102137) (xy 30.091271 -21.152634) (xy 30.060498 -21.199147)
			(xy 30.023281 -21.240684) (xy 29.980413 -21.276359) (xy 29.932807 -21.305413) (xy 29.881478 -21.327225)
			(xy 29.827521 -21.341331) (xy 29.772084 -21.347431) (xy 29.71635 -21.345394) (xy 29.661507 -21.335264)
			(xy 29.608723 -21.317257) (xy 29.559123 -21.291756) (xy 29.513765 -21.259305) (xy 29.473616 -21.220596)
			(xy 29.43953 -21.176453) (xy 29.412234 -21.127818) (xy 29.392311 -21.075727) (xy 29.380185 -21.02129)
			(xy 29.376114 -20.965668) (xy 28.865759 -20.965668) (xy 28.861011 -20.99793) (xy 28.844943 -21.051337)
			(xy 28.821271 -21.101834) (xy 28.790498 -21.148347) (xy 28.753281 -21.189884) (xy 28.710413 -21.225559)
			(xy 28.662807 -21.254613) (xy 28.611478 -21.276425) (xy 28.557521 -21.290531) (xy 28.502084 -21.296631)
			(xy 28.44635 -21.294594) (xy 28.391507 -21.284464) (xy 28.338723 -21.266457) (xy 28.289123 -21.240956)
			(xy 28.243765 -21.208505) (xy 28.203616 -21.169796) (xy 28.16953 -21.125653) (xy 28.142234 -21.077018)
			(xy 28.122311 -21.024927) (xy 28.110185 -20.97049) (xy 28.106114 -20.914868) (xy 27.544959 -20.914868)
			(xy 27.540211 -20.94713) (xy 27.524143 -21.000537) (xy 27.500471 -21.051034) (xy 27.469698 -21.097547)
			(xy 27.432481 -21.139084) (xy 27.389613 -21.174759) (xy 27.342007 -21.203813) (xy 27.290678 -21.225625)
			(xy 27.236721 -21.239731) (xy 27.181284 -21.245831) (xy 27.12555 -21.243794) (xy 27.070707 -21.233664)
			(xy 27.017923 -21.215657) (xy 26.968323 -21.190156) (xy 26.922965 -21.157705) (xy 26.882816 -21.118996)
			(xy 26.84873 -21.074853) (xy 26.821434 -21.026218) (xy 26.801511 -20.974127) (xy 26.789385 -20.91969)
			(xy 26.785314 -20.864068) (xy 23.316057 -20.864068) (xy 23.348451 -20.889902) (xy 23.40653 -20.94655)
			(xy 23.45868 -21.0087) (xy 23.504382 -21.075733) (xy 23.543183 -21.146983) (xy 23.574697 -21.221743)
			(xy 23.598611 -21.299269) (xy 23.614686 -21.378791) (xy 23.622764 -21.459519) (xy 23.62327 -21.500084)
			(xy 23.622764 -21.540649) (xy 23.614686 -21.621377) (xy 23.598611 -21.700899) (xy 23.574697 -21.778425)
			(xy 23.543183 -21.853185) (xy 23.504382 -21.924435) (xy 23.45868 -21.991468) (xy 23.40653 -22.053618)
			(xy 23.376548 -22.082861) (xy 40.462192 -22.082861) (xy 40.462192 -22.011539) (xy 40.470178 -21.940665)
			(xy 40.486048 -21.87113) (xy 40.509605 -21.80381) (xy 40.54055 -21.739551) (xy 40.578496 -21.67916)
			(xy 40.622965 -21.623398) (xy 40.673398 -21.572965) (xy 40.72916 -21.528496) (xy 40.789551 -21.49055)
			(xy 40.85381 -21.459605) (xy 40.92113 -21.436048) (xy 40.990665 -21.420178) (xy 41.061539 -21.412192)
			(xy 41.132861 -21.412192) (xy 41.203735 -21.420178) (xy 41.27327 -21.436048) (xy 41.34059 -21.459605)
			(xy 41.404849 -21.49055) (xy 41.46524 -21.528496) (xy 41.491529 -21.549461) (xy 45.440592 -21.549461)
			(xy 45.440592 -21.478139) (xy 45.448578 -21.407265) (xy 45.464448 -21.33773) (xy 45.488005 -21.27041)
			(xy 45.51895 -21.206151) (xy 45.556896 -21.14576) (xy 45.601365 -21.089998) (xy 45.651798 -21.039565)
			(xy 45.70756 -20.995096) (xy 45.767951 -20.95715) (xy 45.83221 -20.926205) (xy 45.89953 -20.902648)
			(xy 45.969065 -20.886778) (xy 46.039939 -20.878792) (xy 46.111261 -20.878792) (xy 46.182135 -20.886778)
			(xy 46.25167 -20.902648) (xy 46.31899 -20.926205) (xy 46.383249 -20.95715) (xy 46.44364 -20.995096)
			(xy 46.499402 -21.039565) (xy 46.549835 -21.089998) (xy 46.594304 -21.14576) (xy 46.63225 -21.206151)
			(xy 46.663195 -21.27041) (xy 46.686752 -21.33773) (xy 46.702622 -21.407265) (xy 46.710608 -21.478139)
			(xy 46.711108 -21.5138) (xy 46.710608 -21.549461) (xy 46.702622 -21.620335) (xy 46.686752 -21.68987)
			(xy 46.663195 -21.75719) (xy 46.63225 -21.821449) (xy 46.594304 -21.88184) (xy 46.549835 -21.937602)
			(xy 46.499402 -21.988035) (xy 46.44364 -22.032504) (xy 46.383249 -22.07045) (xy 46.31899 -22.101395)
			(xy 46.25167 -22.124952) (xy 46.182135 -22.140822) (xy 46.111261 -22.148808) (xy 46.039939 -22.148808)
			(xy 45.969065 -22.140822) (xy 45.89953 -22.124952) (xy 45.83221 -22.101395) (xy 45.767951 -22.07045)
			(xy 45.70756 -22.032504) (xy 45.651798 -21.988035) (xy 45.601365 -21.937602) (xy 45.556896 -21.88184)
			(xy 45.51895 -21.821449) (xy 45.488005 -21.75719) (xy 45.464448 -21.68987) (xy 45.448578 -21.620335)
			(xy 45.440592 -21.549461) (xy 41.491529 -21.549461) (xy 41.521002 -21.572965) (xy 41.571435 -21.623398)
			(xy 41.615904 -21.67916) (xy 41.65385 -21.739551) (xy 41.684795 -21.80381) (xy 41.708352 -21.87113)
			(xy 41.724222 -21.940665) (xy 41.732208 -22.011539) (xy 41.732708 -22.0472) (xy 41.732208 -22.082861)
			(xy 41.724222 -22.153735) (xy 41.708352 -22.22327) (xy 41.684795 -22.29059) (xy 41.65385 -22.354849)
			(xy 41.615904 -22.41524) (xy 41.571435 -22.471002) (xy 41.521002 -22.521435) (xy 41.46524 -22.565904)
			(xy 41.404849 -22.60385) (xy 41.34059 -22.634795) (xy 41.27327 -22.658352) (xy 41.203735 -22.674222)
			(xy 41.132861 -22.682208) (xy 41.061539 -22.682208) (xy 40.990665 -22.674222) (xy 40.92113 -22.658352)
			(xy 40.85381 -22.634795) (xy 40.789551 -22.60385) (xy 40.72916 -22.565904) (xy 40.673398 -22.521435)
			(xy 40.622965 -22.471002) (xy 40.578496 -22.41524) (xy 40.54055 -22.354849) (xy 40.509605 -22.29059)
			(xy 40.486048 -22.22327) (xy 40.470178 -22.153735) (xy 40.462192 -22.082861) (xy 23.376548 -22.082861)
			(xy 23.348451 -22.110266) (xy 23.285021 -22.160851) (xy 23.216869 -22.204868) (xy 23.144673 -22.24188)
			(xy 23.069151 -22.271521) (xy 22.991053 -22.293494) (xy 22.911155 -22.307582) (xy 22.830251 -22.313645)
			(xy 22.749146 -22.311622) (xy 22.668645 -22.301534) (xy 22.589548 -22.283481) (xy 22.512642 -22.257642)
			(xy 22.438691 -22.224274) (xy 22.36843 -22.183709) (xy 22.302557 -22.136349) (xy 22.241727 -22.082666)
			(xy 22.186544 -22.023194) (xy 22.137557 -21.958522) (xy 22.095253 -21.889294) (xy 22.060052 -21.816198)
			(xy 22.032303 -21.73996) (xy 22.012284 -21.661338) (xy 22.000192 -21.581114) (xy 21.996148 -21.500084)
			(xy 21.623274 -21.500084) (xy 21.622768 -21.540649) (xy 21.61469 -21.621377) (xy 21.598615 -21.700899)
			(xy 21.574701 -21.778425) (xy 21.543187 -21.853185) (xy 21.504386 -21.924435) (xy 21.458684 -21.991468)
			(xy 21.406534 -22.053618) (xy 21.348455 -22.110266) (xy 21.285025 -22.160851) (xy 21.216873 -22.204868)
			(xy 21.144677 -22.24188) (xy 21.069155 -22.271521) (xy 20.991057 -22.293494) (xy 20.911159 -22.307582)
			(xy 20.830255 -22.313645) (xy 20.74915 -22.311622) (xy 20.668649 -22.301534) (xy 20.589552 -22.283481)
			(xy 20.512646 -22.257642) (xy 20.438695 -22.224274) (xy 20.368434 -22.183709) (xy 20.302561 -22.136349)
			(xy 20.241731 -22.082666) (xy 20.186548 -22.023194) (xy 20.137561 -21.958522) (xy 20.095257 -21.889294)
			(xy 20.060056 -21.816198) (xy 20.032307 -21.73996) (xy 20.012288 -21.661338) (xy 20.000196 -21.581114)
			(xy 19.996152 -21.500084) (xy 2.1844 -21.500084) (xy 2.1844 -22.264624) (xy 2.184943 -22.281249)
			(xy 2.193544 -22.313368) (xy 2.210153 -22.342173) (xy 2.233644 -22.365706) (xy 2.262418 -22.382368)
			(xy 2.294522 -22.391026) (xy 2.311146 -22.391624) (xy 2.355686 -22.392264) (xy 2.444366 -22.400725)
			(xy 2.53189 -22.417318) (xy 2.617514 -22.441901) (xy 2.70051 -22.474265) (xy 2.780172 -22.514136)
			(xy 2.855824 -22.561174) (xy 2.926822 -22.614979) (xy 2.992563 -22.675095) (xy 3.052488 -22.74101)
			(xy 3.106088 -22.812163) (xy 3.152907 -22.887951) (xy 3.192547 -22.967729) (xy 3.22467 -23.050818)
			(xy 3.249005 -23.136513) (xy 3.265344 -23.224084) (xy 3.273549 -23.312789) (xy 3.273549 -23.357332)
			(xy 3.882143 -23.357332) (xy 3.886146 -23.26947) (xy 3.898122 -23.182336) (xy 3.917973 -23.096652)
			(xy 3.945532 -23.013128) (xy 3.980573 -22.932456) (xy 4.022804 -22.855305) (xy 4.071876 -22.782314)
			(xy 4.127383 -22.714088) (xy 4.188863 -22.651192) (xy 4.255808 -22.594147) (xy 4.327663 -22.543426)
			(xy 4.403833 -22.499449) (xy 4.483686 -22.462581) (xy 4.566561 -22.433128) (xy 4.651771 -22.411332)
			(xy 4.73861 -22.397376) (xy 4.826358 -22.391373) (xy 4.914288 -22.393375) (xy 5.001673 -22.403365)
			(xy 5.087786 -22.42126) (xy 5.171916 -22.446911) (xy 5.253364 -22.480106) (xy 5.331457 -22.52057)
			(xy 5.366432 -22.542945) (xy 10.382999 -22.542945) (xy 10.382999 -22.457219) (xy 10.390909 -22.371859)
			(xy 10.406661 -22.287592) (xy 10.430121 -22.205139) (xy 10.461089 -22.125202) (xy 10.4993 -22.048463)
			(xy 10.544429 -21.975577) (xy 10.59609 -21.907166) (xy 10.653844 -21.843814) (xy 10.717196 -21.78606)
			(xy 10.785607 -21.734399) (xy 10.858493 -21.68927) (xy 10.935232 -21.651059) (xy 11.015169 -21.620091)
			(xy 11.097622 -21.596631) (xy 11.181889 -21.580879) (xy 11.267249 -21.572969) (xy 11.352975 -21.572969)
			(xy 11.438335 -21.580879) (xy 11.522602 -21.596631) (xy 11.605055 -21.620091) (xy 11.684992 -21.651059)
			(xy 11.761731 -21.68927) (xy 11.834617 -21.734399) (xy 11.903028 -21.78606) (xy 11.96638 -21.843814)
			(xy 12.024134 -21.907166) (xy 12.075795 -21.975577) (xy 12.120924 -22.048463) (xy 12.159135 -22.125202)
			(xy 12.190103 -22.205139) (xy 12.213563 -22.287592) (xy 12.229315 -22.371859) (xy 12.237225 -22.457219)
			(xy 12.23772 -22.500082) (xy 12.237225 -22.542945) (xy 12.229315 -22.628305) (xy 12.213563 -22.712572)
			(xy 12.190103 -22.795025) (xy 12.159135 -22.874962) (xy 12.120924 -22.951701) (xy 12.075795 -23.024587)
			(xy 12.024134 -23.092998) (xy 11.96638 -23.15635) (xy 11.903028 -23.214104) (xy 11.834617 -23.265765)
			(xy 11.761731 -23.310894) (xy 11.684992 -23.349105) (xy 11.605055 -23.380073) (xy 11.522602 -23.403533)
			(xy 11.438335 -23.419285) (xy 11.352975 -23.427195) (xy 11.267249 -23.427195) (xy 11.181889 -23.419285)
			(xy 11.097622 -23.403533) (xy 11.015169 -23.380073) (xy 10.935232 -23.349105) (xy 10.858493 -23.310894)
			(xy 10.785607 -23.265765) (xy 10.717196 -23.214104) (xy 10.653844 -23.15635) (xy 10.59609 -23.092998)
			(xy 10.544429 -23.024587) (xy 10.4993 -22.951701) (xy 10.461089 -22.874962) (xy 10.430121 -22.795025)
			(xy 10.406661 -22.712572) (xy 10.390909 -22.628305) (xy 10.382999 -22.542945) (xy 5.366432 -22.542945)
			(xy 5.405546 -22.567968) (xy 5.475018 -22.621907) (xy 5.539297 -22.68194) (xy 5.597851 -22.747569)
			(xy 5.650195 -22.818251) (xy 5.695894 -22.8934) (xy 5.73457 -22.972393) (xy 5.765902 -23.054576)
			(xy 5.789632 -23.139268) (xy 5.805562 -23.225767) (xy 5.81356 -23.313355) (xy 5.81406 -23.357332)
			(xy 5.81356 -23.401309) (xy 5.805562 -23.488897) (xy 5.803502 -23.50008) (xy 19.996152 -23.50008)
			(xy 20.000196 -23.41905) (xy 20.012288 -23.338826) (xy 20.032307 -23.260204) (xy 20.060056 -23.183966)
			(xy 20.095257 -23.11087) (xy 20.137561 -23.041642) (xy 20.186548 -22.97697) (xy 20.241731 -22.917498)
			(xy 20.302561 -22.863815) (xy 20.368434 -22.816455) (xy 20.438695 -22.77589) (xy 20.512646 -22.742522)
			(xy 20.589552 -22.716683) (xy 20.668649 -22.69863) (xy 20.74915 -22.688542) (xy 20.830255 -22.686519)
			(xy 20.911159 -22.692582) (xy 20.991057 -22.70667) (xy 21.069155 -22.728643) (xy 21.144677 -22.758284)
			(xy 21.216873 -22.795296) (xy 21.285025 -22.839313) (xy 21.348455 -22.889898) (xy 21.406534 -22.946546)
			(xy 21.458684 -23.008696) (xy 21.504386 -23.075729) (xy 21.543187 -23.146979) (xy 21.574701 -23.221739)
			(xy 21.598615 -23.299265) (xy 21.61469 -23.378787) (xy 21.622768 -23.459515) (xy 21.623274 -23.50008)
			(xy 21.996148 -23.50008) (xy 22.000192 -23.41905) (xy 22.012284 -23.338826) (xy 22.032303 -23.260204)
			(xy 22.060052 -23.183966) (xy 22.095253 -23.11087) (xy 22.137557 -23.041642) (xy 22.186544 -22.97697)
			(xy 22.241727 -22.917498) (xy 22.302557 -22.863815) (xy 22.36843 -22.816455) (xy 22.438691 -22.77589)
			(xy 22.512642 -22.742522) (xy 22.589548 -22.716683) (xy 22.668645 -22.69863) (xy 22.749146 -22.688542)
			(xy 22.830251 -22.686519) (xy 22.911155 -22.692582) (xy 22.991053 -22.70667) (xy 23.069151 -22.728643)
			(xy 23.144673 -22.758284) (xy 23.216869 -22.795296) (xy 23.285021 -22.839313) (xy 23.348451 -22.889898)
			(xy 23.40653 -22.946546) (xy 23.45868 -23.008696) (xy 23.504382 -23.075729) (xy 23.543183 -23.146979)
			(xy 23.574697 -23.221739) (xy 23.598611 -23.299265) (xy 23.614686 -23.378787) (xy 23.622764 -23.459515)
			(xy 23.623074 -23.484332) (xy 26.792943 -23.484332) (xy 26.796946 -23.39647) (xy 26.808922 -23.309336)
			(xy 26.828773 -23.223652) (xy 26.856332 -23.140128) (xy 26.891373 -23.059456) (xy 26.933604 -22.982305)
			(xy 26.982676 -22.909314) (xy 27.038183 -22.841088) (xy 27.099663 -22.778192) (xy 27.166608 -22.721147)
			(xy 27.238463 -22.670426) (xy 27.314633 -22.626449) (xy 27.394486 -22.589581) (xy 27.477361 -22.560128)
			(xy 27.562571 -22.538332) (xy 27.64941 -22.524376) (xy 27.737158 -22.518373) (xy 27.825088 -22.520375)
			(xy 27.912473 -22.530365) (xy 27.998586 -22.54826) (xy 28.082716 -22.573911) (xy 28.164164 -22.607106)
			(xy 28.242257 -22.64757) (xy 28.316346 -22.694968) (xy 28.385818 -22.748907) (xy 28.450097 -22.80894)
			(xy 28.508651 -22.874569) (xy 28.560995 -22.945251) (xy 28.606694 -23.0204) (xy 28.64537 -23.099393)
			(xy 28.676702 -23.181576) (xy 28.700432 -23.266268) (xy 28.716362 -23.352767) (xy 28.72436 -23.440355)
			(xy 28.72486 -23.484332) (xy 29.332943 -23.484332) (xy 29.336946 -23.39647) (xy 29.348922 -23.309336)
			(xy 29.368773 -23.223652) (xy 29.396332 -23.140128) (xy 29.431373 -23.059456) (xy 29.473604 -22.982305)
			(xy 29.522676 -22.909314) (xy 29.578183 -22.841088) (xy 29.639663 -22.778192) (xy 29.706608 -22.721147)
			(xy 29.778463 -22.670426) (xy 29.854633 -22.626449) (xy 29.934486 -22.589581) (xy 30.017361 -22.560128)
			(xy 30.102571 -22.538332) (xy 30.18941 -22.524376) (xy 30.277158 -22.518373) (xy 30.365088 -22.520375)
			(xy 30.452473 -22.530365) (xy 30.538586 -22.54826) (xy 30.622716 -22.573911) (xy 30.704164 -22.607106)
			(xy 30.782257 -22.64757) (xy 30.856346 -22.694968) (xy 30.925818 -22.748907) (xy 30.990097 -22.80894)
			(xy 31.048651 -22.874569) (xy 31.100995 -22.945251) (xy 31.146694 -23.0204) (xy 31.18537 -23.099393)
			(xy 31.216702 -23.181576) (xy 31.22911 -23.225861) (xy 32.740592 -23.225861) (xy 32.740592 -23.154539)
			(xy 32.748578 -23.083665) (xy 32.764448 -23.01413) (xy 32.788005 -22.94681) (xy 32.81895 -22.882551)
			(xy 32.856896 -22.82216) (xy 32.901365 -22.766398) (xy 32.951798 -22.715965) (xy 33.00756 -22.671496)
			(xy 33.067951 -22.63355) (xy 33.13221 -22.602605) (xy 33.19953 -22.579048) (xy 33.269065 -22.563178)
			(xy 33.339939 -22.555192) (xy 33.411261 -22.555192) (xy 33.482135 -22.563178) (xy 33.55167 -22.579048)
			(xy 33.61899 -22.602605) (xy 33.683249 -22.63355) (xy 33.74364 -22.671496) (xy 33.799402 -22.715965)
			(xy 33.849835 -22.766398) (xy 33.894304 -22.82216) (xy 33.93225 -22.882551) (xy 33.963027 -22.946461)
			(xy 34.874192 -22.946461) (xy 34.874192 -22.875139) (xy 34.882178 -22.804265) (xy 34.898048 -22.73473)
			(xy 34.921605 -22.66741) (xy 34.95255 -22.603151) (xy 34.990496 -22.54276) (xy 35.034965 -22.486998)
			(xy 35.085398 -22.436565) (xy 35.14116 -22.392096) (xy 35.201551 -22.35415) (xy 35.26581 -22.323205)
			(xy 35.33313 -22.299648) (xy 35.402665 -22.283778) (xy 35.473539 -22.275792) (xy 35.544861 -22.275792)
			(xy 35.615735 -22.283778) (xy 35.68527 -22.299648) (xy 35.75259 -22.323205) (xy 35.816849 -22.35415)
			(xy 35.87724 -22.392096) (xy 35.933002 -22.436565) (xy 35.983435 -22.486998) (xy 36.027904 -22.54276)
			(xy 36.06585 -22.603151) (xy 36.096795 -22.66741) (xy 36.120352 -22.73473) (xy 36.136222 -22.804265)
			(xy 36.144208 -22.875139) (xy 36.144708 -22.9108) (xy 36.144208 -22.946461) (xy 36.136222 -23.017335)
			(xy 36.120352 -23.08687) (xy 36.096795 -23.15419) (xy 36.06585 -23.218449) (xy 36.027904 -23.27884)
			(xy 35.983435 -23.334602) (xy 35.933002 -23.385035) (xy 35.87724 -23.429504) (xy 35.816849 -23.46745)
			(xy 35.75259 -23.498395) (xy 35.68527 -23.521952) (xy 35.615735 -23.537822) (xy 35.544861 -23.545808)
			(xy 35.473539 -23.545808) (xy 35.402665 -23.537822) (xy 35.33313 -23.521952) (xy 35.26581 -23.498395)
			(xy 35.201551 -23.46745) (xy 35.14116 -23.429504) (xy 35.085398 -23.385035) (xy 35.034965 -23.334602)
			(xy 34.990496 -23.27884) (xy 34.95255 -23.218449) (xy 34.921605 -23.15419) (xy 34.898048 -23.08687)
			(xy 34.882178 -23.017335) (xy 34.874192 -22.946461) (xy 33.963027 -22.946461) (xy 33.963195 -22.94681)
			(xy 33.986752 -23.01413) (xy 34.002622 -23.083665) (xy 34.010608 -23.154539) (xy 34.011108 -23.1902)
			(xy 34.010608 -23.225861) (xy 34.002622 -23.296735) (xy 33.986752 -23.36627) (xy 33.963195 -23.43359)
			(xy 33.93225 -23.497849) (xy 33.894304 -23.55824) (xy 33.849835 -23.614002) (xy 33.799402 -23.664435)
			(xy 33.74364 -23.708904) (xy 33.683249 -23.74685) (xy 33.61899 -23.777795) (xy 33.55167 -23.801352)
			(xy 33.482135 -23.817222) (xy 33.411261 -23.825208) (xy 33.339939 -23.825208) (xy 33.269065 -23.817222)
			(xy 33.19953 -23.801352) (xy 33.13221 -23.777795) (xy 33.067951 -23.74685) (xy 33.00756 -23.708904)
			(xy 32.951798 -23.664435) (xy 32.901365 -23.614002) (xy 32.856896 -23.55824) (xy 32.81895 -23.497849)
			(xy 32.788005 -23.43359) (xy 32.764448 -23.36627) (xy 32.748578 -23.296735) (xy 32.740592 -23.225861)
			(xy 31.22911 -23.225861) (xy 31.240432 -23.266268) (xy 31.256362 -23.352767) (xy 31.26436 -23.440355)
			(xy 31.26486 -23.484332) (xy 31.26436 -23.528309) (xy 31.256362 -23.615897) (xy 31.240432 -23.702396)
			(xy 31.216702 -23.787088) (xy 31.18537 -23.869271) (xy 31.146694 -23.948264) (xy 31.100995 -24.023413)
			(xy 31.048651 -24.094095) (xy 31.007462 -24.140261) (xy 68.783192 -24.140261) (xy 68.783192 -24.068939)
			(xy 68.791178 -23.998065) (xy 68.807048 -23.92853) (xy 68.830605 -23.86121) (xy 68.86155 -23.796951)
			(xy 68.899496 -23.73656) (xy 68.943965 -23.680798) (xy 68.994398 -23.630365) (xy 69.05016 -23.585896)
			(xy 69.110551 -23.54795) (xy 69.17481 -23.517005) (xy 69.24213 -23.493448) (xy 69.311665 -23.477578)
			(xy 69.382539 -23.469592) (xy 69.453861 -23.469592) (xy 69.524735 -23.477578) (xy 69.59427 -23.493448)
			(xy 69.66159 -23.517005) (xy 69.725849 -23.54795) (xy 69.78624 -23.585896) (xy 69.842002 -23.630365)
			(xy 69.892435 -23.680798) (xy 69.936904 -23.73656) (xy 69.97485 -23.796951) (xy 70.005795 -23.86121)
			(xy 70.029352 -23.92853) (xy 70.045222 -23.998065) (xy 70.053208 -24.068939) (xy 70.053708 -24.1046)
			(xy 70.053208 -24.140261) (xy 70.045222 -24.211135) (xy 70.029352 -24.28067) (xy 70.005795 -24.34799)
			(xy 69.97485 -24.412249) (xy 69.936904 -24.47264) (xy 69.892435 -24.528402) (xy 69.842002 -24.578835)
			(xy 69.78624 -24.623304) (xy 69.725849 -24.66125) (xy 69.66159 -24.692195) (xy 69.59427 -24.715752)
			(xy 69.524735 -24.731622) (xy 69.453861 -24.739608) (xy 69.382539 -24.739608) (xy 69.311665 -24.731622)
			(xy 69.24213 -24.715752) (xy 69.17481 -24.692195) (xy 69.110551 -24.66125) (xy 69.05016 -24.623304)
			(xy 68.994398 -24.578835) (xy 68.943965 -24.528402) (xy 68.899496 -24.47264) (xy 68.86155 -24.412249)
			(xy 68.830605 -24.34799) (xy 68.807048 -24.28067) (xy 68.791178 -24.211135) (xy 68.783192 -24.140261)
			(xy 31.007462 -24.140261) (xy 30.990097 -24.159724) (xy 30.925818 -24.219757) (xy 30.856346 -24.273696)
			(xy 30.782257 -24.321094) (xy 30.704164 -24.361558) (xy 30.622716 -24.394753) (xy 30.538586 -24.420404)
			(xy 30.452473 -24.438299) (xy 30.365088 -24.448289) (xy 30.277158 -24.450291) (xy 30.18941 -24.444288)
			(xy 30.102571 -24.430332) (xy 30.017361 -24.408536) (xy 29.934486 -24.379083) (xy 29.854633 -24.342215)
			(xy 29.778463 -24.298238) (xy 29.706608 -24.247517) (xy 29.639663 -24.190472) (xy 29.578183 -24.127576)
			(xy 29.522676 -24.05935) (xy 29.473604 -23.986359) (xy 29.431373 -23.909208) (xy 29.396332 -23.828536)
			(xy 29.368773 -23.745012) (xy 29.348922 -23.659328) (xy 29.336946 -23.572194) (xy 29.332943 -23.484332)
			(xy 28.72486 -23.484332) (xy 28.72436 -23.528309) (xy 28.716362 -23.615897) (xy 28.700432 -23.702396)
			(xy 28.676702 -23.787088) (xy 28.64537 -23.869271) (xy 28.606694 -23.948264) (xy 28.560995 -24.023413)
			(xy 28.508651 -24.094095) (xy 28.450097 -24.159724) (xy 28.385818 -24.219757) (xy 28.316346 -24.273696)
			(xy 28.242257 -24.321094) (xy 28.164164 -24.361558) (xy 28.082716 -24.394753) (xy 27.998586 -24.420404)
			(xy 27.912473 -24.438299) (xy 27.825088 -24.448289) (xy 27.737158 -24.450291) (xy 27.64941 -24.444288)
			(xy 27.562571 -24.430332) (xy 27.477361 -24.408536) (xy 27.394486 -24.379083) (xy 27.314633 -24.342215)
			(xy 27.238463 -24.298238) (xy 27.166608 -24.247517) (xy 27.099663 -24.190472) (xy 27.038183 -24.127576)
			(xy 26.982676 -24.05935) (xy 26.933604 -23.986359) (xy 26.891373 -23.909208) (xy 26.856332 -23.828536)
			(xy 26.828773 -23.745012) (xy 26.808922 -23.659328) (xy 26.796946 -23.572194) (xy 26.792943 -23.484332)
			(xy 23.623074 -23.484332) (xy 23.62327 -23.50008) (xy 23.622764 -23.540645) (xy 23.614686 -23.621373)
			(xy 23.598611 -23.700895) (xy 23.574697 -23.778421) (xy 23.543183 -23.853181) (xy 23.504382 -23.924431)
			(xy 23.45868 -23.991464) (xy 23.40653 -24.053614) (xy 23.348451 -24.110262) (xy 23.285021 -24.160847)
			(xy 23.216869 -24.204864) (xy 23.144673 -24.241876) (xy 23.069151 -24.271517) (xy 22.991053 -24.29349)
			(xy 22.911155 -24.307578) (xy 22.830251 -24.313641) (xy 22.749146 -24.311618) (xy 22.668645 -24.30153)
			(xy 22.589548 -24.283477) (xy 22.512642 -24.257638) (xy 22.438691 -24.22427) (xy 22.36843 -24.183705)
			(xy 22.302557 -24.136345) (xy 22.241727 -24.082662) (xy 22.186544 -24.02319) (xy 22.137557 -23.958518)
			(xy 22.095253 -23.88929) (xy 22.060052 -23.816194) (xy 22.032303 -23.739956) (xy 22.012284 -23.661334)
			(xy 22.000192 -23.58111) (xy 21.996148 -23.50008) (xy 21.623274 -23.50008) (xy 21.622768 -23.540645)
			(xy 21.61469 -23.621373) (xy 21.598615 -23.700895) (xy 21.574701 -23.778421) (xy 21.543187 -23.853181)
			(xy 21.504386 -23.924431) (xy 21.458684 -23.991464) (xy 21.406534 -24.053614) (xy 21.348455 -24.110262)
			(xy 21.285025 -24.160847) (xy 21.216873 -24.204864) (xy 21.144677 -24.241876) (xy 21.069155 -24.271517)
			(xy 20.991057 -24.29349) (xy 20.911159 -24.307578) (xy 20.830255 -24.313641) (xy 20.74915 -24.311618)
			(xy 20.668649 -24.30153) (xy 20.589552 -24.283477) (xy 20.512646 -24.257638) (xy 20.438695 -24.22427)
			(xy 20.368434 -24.183705) (xy 20.302561 -24.136345) (xy 20.241731 -24.082662) (xy 20.186548 -24.02319)
			(xy 20.137561 -23.958518) (xy 20.095257 -23.88929) (xy 20.060056 -23.816194) (xy 20.032307 -23.739956)
			(xy 20.012288 -23.661334) (xy 20.000196 -23.58111) (xy 19.996152 -23.50008) (xy 5.803502 -23.50008)
			(xy 5.789632 -23.575396) (xy 5.765902 -23.660088) (xy 5.73457 -23.742271) (xy 5.695894 -23.821264)
			(xy 5.650195 -23.896413) (xy 5.597851 -23.967095) (xy 5.539297 -24.032724) (xy 5.475018 -24.092757)
			(xy 5.405546 -24.146696) (xy 5.331457 -24.194094) (xy 5.253364 -24.234558) (xy 5.171916 -24.267753)
			(xy 5.087786 -24.293404) (xy 5.001673 -24.311299) (xy 4.914288 -24.321289) (xy 4.826358 -24.323291)
			(xy 4.73861 -24.317288) (xy 4.651771 -24.303332) (xy 4.566561 -24.281536) (xy 4.483686 -24.252083)
			(xy 4.403833 -24.215215) (xy 4.327663 -24.171238) (xy 4.255808 -24.120517) (xy 4.188863 -24.063472)
			(xy 4.127383 -24.000576) (xy 4.071876 -23.93235) (xy 4.022804 -23.859359) (xy 3.980573 -23.782208)
			(xy 3.945532 -23.701536) (xy 3.917973 -23.618012) (xy 3.898122 -23.532328) (xy 3.886146 -23.445194)
			(xy 3.882143 -23.357332) (xy 3.273549 -23.357332) (xy 3.273549 -23.401871) (xy 3.265344 -23.490576)
			(xy 3.249005 -23.578148) (xy 3.22467 -23.663842) (xy 3.192547 -23.746931) (xy 3.152907 -23.826709)
			(xy 3.106088 -23.902497) (xy 3.052488 -23.97365) (xy 2.992563 -24.039565) (xy 2.926822 -24.099681)
			(xy 2.855824 -24.153486) (xy 2.780172 -24.200524) (xy 2.70051 -24.240395) (xy 2.617514 -24.272759)
			(xy 2.53189 -24.297342) (xy 2.444366 -24.313935) (xy 2.355686 -24.322396) (xy 2.311146 -24.32304)
			(xy 2.294522 -24.323614) (xy 2.262419 -24.332275) (xy 2.233647 -24.348942) (xy 2.210162 -24.372481)
			(xy 2.193562 -24.401291) (xy 2.184975 -24.433414) (xy 2.1844 -24.45004) (xy 2.1844 -25.542939) (xy 10.382999 -25.542939)
			(xy 10.382999 -25.457213) (xy 10.390909 -25.371853) (xy 10.406661 -25.287586) (xy 10.430121 -25.205133)
			(xy 10.461089 -25.125196) (xy 10.4993 -25.048457) (xy 10.544429 -24.975571) (xy 10.59609 -24.90716)
			(xy 10.653844 -24.843808) (xy 10.717196 -24.786054) (xy 10.785607 -24.734393) (xy 10.858493 -24.689264)
			(xy 10.935232 -24.651053) (xy 11.015169 -24.620085) (xy 11.097622 -24.596625) (xy 11.181889 -24.580873)
			(xy 11.267249 -24.572963) (xy 11.352975 -24.572963) (xy 11.438335 -24.580873) (xy 11.522602 -24.596625)
			(xy 11.605055 -24.620085) (xy 11.684992 -24.651053) (xy 11.761731 -24.689264) (xy 11.834617 -24.734393)
			(xy 11.903028 -24.786054) (xy 11.96638 -24.843808) (xy 12.024134 -24.90716) (xy 12.075795 -24.975571)
			(xy 12.120924 -25.048457) (xy 12.159135 -25.125196) (xy 12.190103 -25.205133) (xy 12.213563 -25.287586)
			(xy 12.229315 -25.371853) (xy 12.237225 -25.457213) (xy 12.23772 -25.500076) (xy 12.237225 -25.542939)
			(xy 12.229315 -25.628299) (xy 12.213563 -25.712566) (xy 12.190103 -25.795019) (xy 12.159135 -25.874956)
			(xy 12.120924 -25.951695) (xy 12.075795 -26.024581) (xy 12.024134 -26.092992) (xy 11.96638 -26.156344)
			(xy 11.903028 -26.214098) (xy 11.834617 -26.265759) (xy 11.761731 -26.310888) (xy 11.684992 -26.349099)
			(xy 11.605055 -26.380067) (xy 11.522602 -26.403527) (xy 11.438335 -26.419279) (xy 11.352975 -26.427189)
			(xy 11.267249 -26.427189) (xy 11.181889 -26.419279) (xy 11.097622 -26.403527) (xy 11.015169 -26.380067)
			(xy 10.935232 -26.349099) (xy 10.858493 -26.310888) (xy 10.785607 -26.265759) (xy 10.717196 -26.214098)
			(xy 10.653844 -26.156344) (xy 10.59609 -26.092992) (xy 10.544429 -26.024581) (xy 10.4993 -25.951695)
			(xy 10.461089 -25.874956) (xy 10.430121 -25.795019) (xy 10.406661 -25.712566) (xy 10.390909 -25.628299)
			(xy 10.382999 -25.542939) (xy 2.1844 -25.542939) (xy 2.1844 -27.563318) (xy 2.184894 -27.586309)
			(xy 2.193161 -27.63154) (xy 2.209433 -27.674546) (xy 2.233177 -27.713922) (xy 2.263618 -27.748384)
			(xy 2.299763 -27.776805) (xy 2.340432 -27.798259) (xy 2.384298 -27.812046) (xy 2.429928 -27.817714)
			(xy 2.475834 -27.81508) (xy 2.520516 -27.804229) (xy 2.562517 -27.785515) (xy 2.600465 -27.75955)
			(xy 2.633122 -27.72718) (xy 2.64668 -27.708606) (xy 2.685112 -27.654295) (xy 2.767477 -27.549788)
			(xy 2.855853 -27.450311) (xy 2.949931 -27.35621) (xy 3.049387 -27.267811) (xy 3.153875 -27.185421)
			(xy 3.263032 -27.109325) (xy 3.37648 -27.039788) (xy 3.493826 -26.977051) (xy 3.614661 -26.921332)
			(xy 3.738567 -26.872824) (xy 3.865115 -26.831694) (xy 3.993864 -26.798087) (xy 4.124369 -26.772118)
			(xy 4.256176 -26.753877) (xy 4.388828 -26.743429) (xy 4.521866 -26.740808) (xy 4.654827 -26.746024)
			(xy 4.78725 -26.75906) (xy 4.918676 -26.779869) (xy 5.048649 -26.80838) (xy 5.176718 -26.844494)
			(xy 5.302438 -26.888086) (xy 5.425374 -26.939003) (xy 5.545099 -26.99707) (xy 5.661198 -27.062085)
			(xy 5.773267 -27.133823) (xy 5.880919 -27.212034) (xy 5.983779 -27.296448) (xy 6.08149 -27.386771)
			(xy 6.173715 -27.48269) (xy 6.215855 -27.532031) (xy 19.996675 -27.532031) (xy 19.997523 -27.451084)
			(xy 20.006408 -27.370622) (xy 20.023241 -27.29144) (xy 20.047857 -27.214322) (xy 20.080012 -27.14003)
			(xy 20.119388 -27.069301) (xy 20.165596 -27.002833) (xy 20.218177 -26.941283) (xy 20.276613 -26.885262)
			(xy 20.340325 -26.835322) (xy 20.408682 -26.791959) (xy 20.481009 -26.7556) (xy 20.55659 -26.726606)
			(xy 20.634678 -26.705264) (xy 20.714499 -26.691784) (xy 20.754848 -26.688542) (xy 20.771338 -26.686913)
			(xy 20.802708 -26.676275) (xy 20.830281 -26.65792) (xy 20.8522 -26.633085) (xy 20.866986 -26.603444)
			(xy 20.873642 -26.570995) (xy 20.873212 -26.55443) (xy 20.871759 -26.527209) (xy 20.871634 -26.472691)
			(xy 20.872958 -26.445464) (xy 20.873393 -26.428936) (xy 20.866735 -26.396561) (xy 20.851974 -26.366987)
			(xy 20.830104 -26.342204) (xy 20.802596 -26.32388) (xy 20.771301 -26.313247) (xy 20.754848 -26.311606)
			(xy 20.714505 -26.308352) (xy 20.634695 -26.294869) (xy 20.556618 -26.273526) (xy 20.481047 -26.244533)
			(xy 20.40873 -26.208177) (xy 20.340382 -26.164817) (xy 20.276679 -26.114883) (xy 20.21825 -26.058868)
			(xy 20.165675 -25.997327) (xy 20.119472 -25.930868) (xy 20.080099 -25.860148) (xy 20.047946 -25.785867)
			(xy 20.023329 -25.70876) (xy 20.006494 -25.629589) (xy 19.997605 -25.549137) (xy 19.996752 -25.4682)
			(xy 20.003942 -25.387579) (xy 20.019105 -25.30807) (xy 20.042091 -25.230461) (xy 20.072671 -25.155519)
			(xy 20.110545 -25.083985) (xy 20.155336 -25.016566) (xy 20.206603 -24.95393) (xy 20.263837 -24.896696)
			(xy 20.326474 -24.845431) (xy 20.393893 -24.80064) (xy 20.465427 -24.762767) (xy 20.54037 -24.732188)
			(xy 20.617979 -24.709203) (xy 20.697488 -24.694041) (xy 20.778109 -24.686852) (xy 20.859046 -24.687706)
			(xy 20.939498 -24.696595) (xy 21.018669 -24.713432) (xy 21.095776 -24.738049) (xy 21.170057 -24.770203)
			(xy 21.240776 -24.809577) (xy 21.307235 -24.855781) (xy 21.368775 -24.908357) (xy 21.424789 -24.966786)
			(xy 21.474722 -25.03049) (xy 21.518081 -25.098838) (xy 21.554436 -25.171156) (xy 21.583429 -25.246727)
			(xy 21.604771 -25.324804) (xy 21.618253 -25.404614) (xy 21.621496 -25.444958) (xy 21.623181 -25.46144)
			(xy 21.633814 -25.492801) (xy 21.65216 -25.520368) (xy 21.676984 -25.542286) (xy 21.706611 -25.557077)
			(xy 21.739048 -25.563744) (xy 21.755608 -25.563322) (xy 21.782769 -25.561942) (xy 21.837159 -25.561942)
			(xy 21.86432 -25.563322) (xy 21.880888 -25.563731) (xy 21.913342 -25.557095) (xy 21.942991 -25.54232)
			(xy 21.96783 -25.520403) (xy 21.986183 -25.492826) (xy 21.996809 -25.46145) (xy 21.998432 -25.444958)
			(xy 22.001677 -25.404612) (xy 22.015157 -25.324797) (xy 22.036498 -25.246716) (xy 22.06549 -25.171141)
			(xy 22.101846 -25.098819) (xy 22.145205 -25.030466) (xy 22.19514 -24.966758) (xy 22.251156 -24.908325)
			(xy 22.312699 -24.855745) (xy 22.37916 -24.809539) (xy 22.449882 -24.770162) (xy 22.524166 -24.738005)
			(xy 22.601277 -24.713386) (xy 22.680452 -24.696548) (xy 22.760907 -24.687658) (xy 22.841848 -24.686803)
			(xy 22.922474 -24.693993) (xy 23.001987 -24.709155) (xy 23.0796 -24.732141) (xy 23.154546 -24.762722)
			(xy 23.226084 -24.800597) (xy 23.293506 -24.84539) (xy 23.356146 -24.896659) (xy 23.413383 -24.953896)
			(xy 23.464651 -25.016535) (xy 23.509444 -25.083957) (xy 23.547319 -25.155495) (xy 23.5779 -25.230442)
			(xy 23.600885 -25.308055) (xy 23.616048 -25.387568) (xy 23.623237 -25.468193) (xy 23.622382 -25.549134)
			(xy 23.613492 -25.62959) (xy 23.596654 -25.708765) (xy 23.572034 -25.785875) (xy 23.539877 -25.860159)
			(xy 23.5005 -25.930882) (xy 23.454294 -25.997343) (xy 23.401714 -26.058886) (xy 23.343281 -26.114901)
			(xy 23.279573 -26.164836) (xy 23.21122 -26.208195) (xy 23.138898 -26.24455) (xy 23.063322 -26.273542)
			(xy 22.985241 -26.294884) (xy 22.905426 -26.308364) (xy 22.86508 -26.311606) (xy 22.848615 -26.313241)
			(xy 22.817291 -26.323864) (xy 22.78975 -26.34218) (xy 22.76784 -26.366958) (xy 22.753033 -26.396534)
			(xy 22.75121 -26.405332) (xy 26.792943 -26.405332) (xy 26.796946 -26.31747) (xy 26.808922 -26.230336)
			(xy 26.828773 -26.144652) (xy 26.856332 -26.061128) (xy 26.891373 -25.980456) (xy 26.933604 -25.903305)
			(xy 26.982676 -25.830314) (xy 27.038183 -25.762088) (xy 27.099663 -25.699192) (xy 27.166608 -25.642147)
			(xy 27.238463 -25.591426) (xy 27.314633 -25.547449) (xy 27.394486 -25.510581) (xy 27.477361 -25.481128)
			(xy 27.562571 -25.459332) (xy 27.64941 -25.445376) (xy 27.737158 -25.439373) (xy 27.825088 -25.441375)
			(xy 27.912473 -25.451365) (xy 27.998586 -25.46926) (xy 28.082716 -25.494911) (xy 28.164164 -25.528106)
			(xy 28.242257 -25.56857) (xy 28.316346 -25.615968) (xy 28.385818 -25.669907) (xy 28.450097 -25.72994)
			(xy 28.508651 -25.795569) (xy 28.560995 -25.866251) (xy 28.606694 -25.9414) (xy 28.64537 -26.020393)
			(xy 28.676702 -26.102576) (xy 28.700432 -26.187268) (xy 28.716362 -26.273767) (xy 28.72436 -26.361355)
			(xy 28.72486 -26.405332) (xy 29.332943 -26.405332) (xy 29.336946 -26.31747) (xy 29.348922 -26.230336)
			(xy 29.368773 -26.144652) (xy 29.396332 -26.061128) (xy 29.431373 -25.980456) (xy 29.473604 -25.903305)
			(xy 29.522676 -25.830314) (xy 29.578183 -25.762088) (xy 29.639663 -25.699192) (xy 29.706608 -25.642147)
			(xy 29.778463 -25.591426) (xy 29.854633 -25.547449) (xy 29.934486 -25.510581) (xy 30.017361 -25.481128)
			(xy 30.102571 -25.459332) (xy 30.18941 -25.445376) (xy 30.277158 -25.439373) (xy 30.365088 -25.441375)
			(xy 30.452473 -25.451365) (xy 30.538586 -25.46926) (xy 30.622716 -25.494911) (xy 30.704164 -25.528106)
			(xy 30.782257 -25.56857) (xy 30.856346 -25.615968) (xy 30.925818 -25.669907) (xy 30.990097 -25.72994)
			(xy 31.022146 -25.765861) (xy 32.181792 -25.765861) (xy 32.181792 -25.694539) (xy 32.189778 -25.623665)
			(xy 32.205648 -25.55413) (xy 32.229205 -25.48681) (xy 32.26015 -25.422551) (xy 32.298096 -25.36216)
			(xy 32.342565 -25.306398) (xy 32.392998 -25.255965) (xy 32.44876 -25.211496) (xy 32.509151 -25.17355)
			(xy 32.57341 -25.142605) (xy 32.64073 -25.119048) (xy 32.710265 -25.103178) (xy 32.781139 -25.095192)
			(xy 32.852461 -25.095192) (xy 32.923335 -25.103178) (xy 32.99287 -25.119048) (xy 33.06019 -25.142605)
			(xy 33.124449 -25.17355) (xy 33.18484 -25.211496) (xy 33.240602 -25.255965) (xy 33.291035 -25.306398)
			(xy 33.335504 -25.36216) (xy 33.37345 -25.422551) (xy 33.404395 -25.48681) (xy 33.427952 -25.55413)
			(xy 33.443822 -25.623665) (xy 33.451808 -25.694539) (xy 33.452308 -25.7302) (xy 33.451808 -25.765861)
			(xy 33.443822 -25.836735) (xy 33.427952 -25.90627) (xy 33.404395 -25.97359) (xy 33.37345 -26.037849)
			(xy 33.368793 -26.045261) (xy 39.547792 -26.045261) (xy 39.547792 -25.973939) (xy 39.555778 -25.903065)
			(xy 39.571648 -25.83353) (xy 39.595205 -25.76621) (xy 39.62615 -25.701951) (xy 39.664096 -25.64156)
			(xy 39.708565 -25.585798) (xy 39.758998 -25.535365) (xy 39.81476 -25.490896) (xy 39.875151 -25.45295)
			(xy 39.93941 -25.422005) (xy 40.00673 -25.398448) (xy 40.076265 -25.382578) (xy 40.147139 -25.374592)
			(xy 40.218461 -25.374592) (xy 40.289335 -25.382578) (xy 40.35887 -25.398448) (xy 40.42619 -25.422005)
			(xy 40.490449 -25.45295) (xy 40.55084 -25.490896) (xy 40.606602 -25.535365) (xy 40.633898 -25.562661)
			(xy 54.330592 -25.562661) (xy 54.330592 -25.491339) (xy 54.338578 -25.420465) (xy 54.354448 -25.35093)
			(xy 54.378005 -25.28361) (xy 54.40895 -25.219351) (xy 54.446896 -25.15896) (xy 54.491365 -25.103198)
			(xy 54.541798 -25.052765) (xy 54.59756 -25.008296) (xy 54.657951 -24.97035) (xy 54.72221 -24.939405)
			(xy 54.78953 -24.915848) (xy 54.859065 -24.899978) (xy 54.929939 -24.891992) (xy 55.001261 -24.891992)
			(xy 55.072135 -24.899978) (xy 55.14167 -24.915848) (xy 55.20899 -24.939405) (xy 55.273249 -24.97035)
			(xy 55.33364 -25.008296) (xy 55.389402 -25.052765) (xy 55.439835 -25.103198) (xy 55.484304 -25.15896)
			(xy 55.52225 -25.219351) (xy 55.553195 -25.28361) (xy 55.576752 -25.35093) (xy 55.592622 -25.420465)
			(xy 55.597196 -25.461061) (xy 63.271392 -25.461061) (xy 63.271392 -25.389739) (xy 63.279378 -25.318865)
			(xy 63.295248 -25.24933) (xy 63.318805 -25.18201) (xy 63.34975 -25.117751) (xy 63.387696 -25.05736)
			(xy 63.432165 -25.001598) (xy 63.482598 -24.951165) (xy 63.53836 -24.906696) (xy 63.598751 -24.86875)
			(xy 63.66301 -24.837805) (xy 63.73033 -24.814248) (xy 63.799865 -24.798378) (xy 63.870739 -24.790392)
			(xy 63.942061 -24.790392) (xy 64.012935 -24.798378) (xy 64.08247 -24.814248) (xy 64.14979 -24.837805)
			(xy 64.214049 -24.86875) (xy 64.27444 -24.906696) (xy 64.330202 -24.951165) (xy 64.380635 -25.001598)
			(xy 64.425104 -25.05736) (xy 64.46305 -25.117751) (xy 64.493995 -25.18201) (xy 64.517552 -25.24933)
			(xy 64.533422 -25.318865) (xy 64.541408 -25.389739) (xy 64.541908 -25.4254) (xy 64.541408 -25.461061)
			(xy 64.533422 -25.531935) (xy 64.517552 -25.60147) (xy 64.49558 -25.664261) (xy 70.942192 -25.664261)
			(xy 70.942192 -25.592939) (xy 70.950178 -25.522065) (xy 70.966048 -25.45253) (xy 70.989605 -25.38521)
			(xy 71.02055 -25.320951) (xy 71.058496 -25.26056) (xy 71.102965 -25.204798) (xy 71.153398 -25.154365)
			(xy 71.20916 -25.109896) (xy 71.269551 -25.07195) (xy 71.33381 -25.041005) (xy 71.40113 -25.017448)
			(xy 71.470665 -25.001578) (xy 71.541539 -24.993592) (xy 71.612861 -24.993592) (xy 71.683735 -25.001578)
			(xy 71.75327 -25.017448) (xy 71.82059 -25.041005) (xy 71.884849 -25.07195) (xy 71.94524 -25.109896)
			(xy 72.001002 -25.154365) (xy 72.051435 -25.204798) (xy 72.095904 -25.26056) (xy 72.13385 -25.320951)
			(xy 72.164795 -25.38521) (xy 72.188352 -25.45253) (xy 72.204222 -25.522065) (xy 72.212208 -25.592939)
			(xy 72.212708 -25.6286) (xy 72.212208 -25.664261) (xy 72.206484 -25.715061) (xy 77.546192 -25.715061)
			(xy 77.546192 -25.643739) (xy 77.554178 -25.572865) (xy 77.570048 -25.50333) (xy 77.593605 -25.43601)
			(xy 77.62455 -25.371751) (xy 77.662496 -25.31136) (xy 77.706965 -25.255598) (xy 77.757398 -25.205165)
			(xy 77.81316 -25.160696) (xy 77.873551 -25.12275) (xy 77.93781 -25.091805) (xy 78.00513 -25.068248)
			(xy 78.074665 -25.052378) (xy 78.145539 -25.044392) (xy 78.216861 -25.044392) (xy 78.287735 -25.052378)
			(xy 78.35727 -25.068248) (xy 78.42459 -25.091805) (xy 78.488849 -25.12275) (xy 78.54924 -25.160696)
			(xy 78.605002 -25.205165) (xy 78.655435 -25.255598) (xy 78.699904 -25.31136) (xy 78.73785 -25.371751)
			(xy 78.768795 -25.43601) (xy 78.792352 -25.50333) (xy 78.808222 -25.572865) (xy 78.816208 -25.643739)
			(xy 78.816708 -25.6794) (xy 78.816208 -25.715061) (xy 78.808222 -25.785935) (xy 78.792352 -25.85547)
			(xy 78.768795 -25.92279) (xy 78.73785 -25.987049) (xy 78.699904 -26.04744) (xy 78.655435 -26.103202)
			(xy 78.605002 -26.153635) (xy 78.54924 -26.198104) (xy 78.488849 -26.23605) (xy 78.42459 -26.266995)
			(xy 78.35727 -26.290552) (xy 78.287735 -26.306422) (xy 78.216861 -26.314408) (xy 78.145539 -26.314408)
			(xy 78.074665 -26.306422) (xy 78.00513 -26.290552) (xy 77.93781 -26.266995) (xy 77.873551 -26.23605)
			(xy 77.81316 -26.198104) (xy 77.757398 -26.153635) (xy 77.706965 -26.103202) (xy 77.662496 -26.04744)
			(xy 77.62455 -25.987049) (xy 77.593605 -25.92279) (xy 77.570048 -25.85547) (xy 77.554178 -25.785935)
			(xy 77.546192 -25.715061) (xy 72.206484 -25.715061) (xy 72.204222 -25.735135) (xy 72.188352 -25.80467)
			(xy 72.164795 -25.87199) (xy 72.13385 -25.936249) (xy 72.095904 -25.99664) (xy 72.051435 -26.052402)
			(xy 72.001002 -26.102835) (xy 71.94524 -26.147304) (xy 71.884849 -26.18525) (xy 71.82059 -26.216195)
			(xy 71.75327 -26.239752) (xy 71.683735 -26.255622) (xy 71.612861 -26.263608) (xy 71.541539 -26.263608)
			(xy 71.470665 -26.255622) (xy 71.40113 -26.239752) (xy 71.33381 -26.216195) (xy 71.269551 -26.18525)
			(xy 71.20916 -26.147304) (xy 71.153398 -26.102835) (xy 71.102965 -26.052402) (xy 71.058496 -25.99664)
			(xy 71.02055 -25.936249) (xy 70.989605 -25.87199) (xy 70.966048 -25.80467) (xy 70.950178 -25.735135)
			(xy 70.942192 -25.664261) (xy 64.49558 -25.664261) (xy 64.493995 -25.66879) (xy 64.46305 -25.733049)
			(xy 64.425104 -25.79344) (xy 64.380635 -25.849202) (xy 64.330202 -25.899635) (xy 64.27444 -25.944104)
			(xy 64.214049 -25.98205) (xy 64.14979 -26.012995) (xy 64.08247 -26.036552) (xy 64.012935 -26.052422)
			(xy 63.942061 -26.060408) (xy 63.870739 -26.060408) (xy 63.799865 -26.052422) (xy 63.73033 -26.036552)
			(xy 63.66301 -26.012995) (xy 63.598751 -25.98205) (xy 63.53836 -25.944104) (xy 63.482598 -25.899635)
			(xy 63.432165 -25.849202) (xy 63.387696 -25.79344) (xy 63.34975 -25.733049) (xy 63.318805 -25.66879)
			(xy 63.295248 -25.60147) (xy 63.279378 -25.531935) (xy 63.271392 -25.461061) (xy 55.597196 -25.461061)
			(xy 55.600608 -25.491339) (xy 55.601108 -25.527) (xy 55.600608 -25.562661) (xy 55.592622 -25.633535)
			(xy 55.576752 -25.70307) (xy 55.553195 -25.77039) (xy 55.52225 -25.834649) (xy 55.484304 -25.89504)
			(xy 55.439835 -25.950802) (xy 55.389402 -26.001235) (xy 55.33364 -26.045704) (xy 55.273249 -26.08365)
			(xy 55.20899 -26.114595) (xy 55.14167 -26.138152) (xy 55.072135 -26.154022) (xy 55.001261 -26.162008)
			(xy 54.929939 -26.162008) (xy 54.859065 -26.154022) (xy 54.78953 -26.138152) (xy 54.72221 -26.114595)
			(xy 54.657951 -26.08365) (xy 54.59756 -26.045704) (xy 54.541798 -26.001235) (xy 54.491365 -25.950802)
			(xy 54.446896 -25.89504) (xy 54.40895 -25.834649) (xy 54.378005 -25.77039) (xy 54.354448 -25.70307)
			(xy 54.338578 -25.633535) (xy 54.330592 -25.562661) (xy 40.633898 -25.562661) (xy 40.657035 -25.585798)
			(xy 40.701504 -25.64156) (xy 40.73945 -25.701951) (xy 40.770395 -25.76621) (xy 40.793952 -25.83353)
			(xy 40.809822 -25.903065) (xy 40.817808 -25.973939) (xy 40.818308 -26.0096) (xy 40.817808 -26.045261)
			(xy 40.809822 -26.116135) (xy 40.793952 -26.18567) (xy 40.770395 -26.25299) (xy 40.73945 -26.317249)
			(xy 40.701504 -26.37764) (xy 40.657035 -26.433402) (xy 40.606602 -26.483835) (xy 40.55084 -26.528304)
			(xy 40.490449 -26.56625) (xy 40.42619 -26.597195) (xy 40.35887 -26.620752) (xy 40.289335 -26.636622)
			(xy 40.218461 -26.644608) (xy 40.147139 -26.644608) (xy 40.076265 -26.636622) (xy 40.00673 -26.620752)
			(xy 39.93941 -26.597195) (xy 39.875151 -26.56625) (xy 39.81476 -26.528304) (xy 39.758998 -26.483835)
			(xy 39.708565 -26.433402) (xy 39.664096 -26.37764) (xy 39.62615 -26.317249) (xy 39.595205 -26.25299)
			(xy 39.571648 -26.18567) (xy 39.555778 -26.116135) (xy 39.547792 -26.045261) (xy 33.368793 -26.045261)
			(xy 33.335504 -26.09824) (xy 33.291035 -26.154002) (xy 33.240602 -26.204435) (xy 33.18484 -26.248904)
			(xy 33.124449 -26.28685) (xy 33.06019 -26.317795) (xy 32.99287 -26.341352) (xy 32.923335 -26.357222)
			(xy 32.852461 -26.365208) (xy 32.781139 -26.365208) (xy 32.710265 -26.357222) (xy 32.64073 -26.341352)
			(xy 32.57341 -26.317795) (xy 32.509151 -26.28685) (xy 32.44876 -26.248904) (xy 32.392998 -26.204435)
			(xy 32.342565 -26.154002) (xy 32.298096 -26.09824) (xy 32.26015 -26.037849) (xy 32.229205 -25.97359)
			(xy 32.205648 -25.90627) (xy 32.189778 -25.836735) (xy 32.181792 -25.765861) (xy 31.022146 -25.765861)
			(xy 31.048651 -25.795569) (xy 31.100995 -25.866251) (xy 31.146694 -25.9414) (xy 31.18537 -26.020393)
			(xy 31.216702 -26.102576) (xy 31.240432 -26.187268) (xy 31.256362 -26.273767) (xy 31.26436 -26.361355)
			(xy 31.26486 -26.405332) (xy 31.26436 -26.449309) (xy 31.256362 -26.536897) (xy 31.240432 -26.623396)
			(xy 31.216702 -26.708088) (xy 31.18537 -26.790271) (xy 31.146694 -26.869264) (xy 31.100995 -26.944413)
			(xy 31.048651 -27.015095) (xy 30.990097 -27.080724) (xy 30.925818 -27.140757) (xy 30.856346 -27.194696)
			(xy 30.782257 -27.242094) (xy 30.704164 -27.282558) (xy 30.622716 -27.315753) (xy 30.538586 -27.341404)
			(xy 30.452473 -27.359299) (xy 30.365088 -27.369289) (xy 30.277158 -27.371291) (xy 30.18941 -27.365288)
			(xy 30.102571 -27.351332) (xy 30.017361 -27.329536) (xy 29.934486 -27.300083) (xy 29.854633 -27.263215)
			(xy 29.778463 -27.219238) (xy 29.706608 -27.168517) (xy 29.639663 -27.111472) (xy 29.578183 -27.048576)
			(xy 29.522676 -26.98035) (xy 29.473604 -26.907359) (xy 29.431373 -26.830208) (xy 29.396332 -26.749536)
			(xy 29.368773 -26.666012) (xy 29.348922 -26.580328) (xy 29.336946 -26.493194) (xy 29.332943 -26.405332)
			(xy 28.72486 -26.405332) (xy 28.72436 -26.449309) (xy 28.716362 -26.536897) (xy 28.700432 -26.623396)
			(xy 28.676702 -26.708088) (xy 28.64537 -26.790271) (xy 28.606694 -26.869264) (xy 28.560995 -26.944413)
			(xy 28.508651 -27.015095) (xy 28.450097 -27.080724) (xy 28.385818 -27.140757) (xy 28.316346 -27.194696)
			(xy 28.242257 -27.242094) (xy 28.164164 -27.282558) (xy 28.082716 -27.315753) (xy 27.998586 -27.341404)
			(xy 27.912473 -27.359299) (xy 27.825088 -27.369289) (xy 27.737158 -27.371291) (xy 27.64941 -27.365288)
			(xy 27.562571 -27.351332) (xy 27.477361 -27.329536) (xy 27.394486 -27.300083) (xy 27.314633 -27.263215)
			(xy 27.238463 -27.219238) (xy 27.166608 -27.168517) (xy 27.099663 -27.111472) (xy 27.038183 -27.048576)
			(xy 26.982676 -26.98035) (xy 26.933604 -26.907359) (xy 26.891373 -26.830208) (xy 26.856332 -26.749536)
			(xy 26.828773 -26.666012) (xy 26.808922 -26.580328) (xy 26.796946 -26.493194) (xy 26.792943 -26.405332)
			(xy 22.75121 -26.405332) (xy 22.746323 -26.428922) (xy 22.746716 -26.445464) (xy 22.74824 -26.500074)
			(xy 22.747727 -26.545195) (xy 22.739125 -26.635025) (xy 22.72193 -26.723613) (xy 22.709632 -26.767028)
			(xy 22.458172 -26.767028) (xy 22.399498 -26.80081) (xy 22.38248 -26.830528) (xy 22.364155 -26.861233)
			(xy 22.321887 -26.91891) (xy 22.273644 -26.971692) (xy 22.21999 -27.018963) (xy 22.161551 -27.060171)
			(xy 22.130512 -27.077924) (xy 22.115946 -27.086618) (xy 22.091669 -27.110292) (xy 22.07446 -27.13951)
			(xy 22.065525 -27.172222) (xy 22.06498 -27.189176) (xy 22.06498 -27.403044) (xy 22.027257 -27.413294)
			(xy 21.95052 -27.428226) (xy 21.872805 -27.436711) (xy 21.794654 -27.438692) (xy 21.755608 -27.436826)
			(xy 21.739059 -27.43638) (xy 21.706633 -27.442994) (xy 21.677004 -27.457734) (xy 21.652169 -27.479605)
			(xy 21.633802 -27.507134) (xy 21.623143 -27.538463) (xy 21.621496 -27.554936) (xy 21.618264 -27.595286)
			(xy 21.604807 -27.675111) (xy 21.583488 -27.753204) (xy 21.554516 -27.828794) (xy 21.518178 -27.901132)
			(xy 21.474834 -27.969502) (xy 21.424913 -28.033228) (xy 21.368909 -28.09168) (xy 21.307375 -28.144279)
			(xy 21.24092 -28.190506) (xy 21.170202 -28.229903) (xy 21.09592 -28.262079) (xy 21.018809 -28.286718)
			(xy 20.939632 -28.303575) (xy 20.859172 -28.312483) (xy 20.778226 -28.313354) (xy 20.697593 -28.30618)
			(xy 20.618071 -28.291031) (xy 20.540448 -28.268058) (xy 20.465491 -28.237488) (xy 20.393941 -28.199623)
			(xy 20.326506 -28.154837) (xy 20.263855 -28.103574) (xy 20.206605 -28.046341) (xy 20.155324 -27.983704)
			(xy 20.110519 -27.916283) (xy 20.072632 -27.844744) (xy 20.04204 -27.769796) (xy 20.019045 -27.692179)
			(xy 20.003873 -27.612662) (xy 19.996675 -27.532031) (xy 6.215855 -27.532031) (xy 6.260132 -27.583873)
			(xy 6.340442 -27.689967) (xy 6.414366 -27.800607) (xy 6.481649 -27.915406) (xy 6.542055 -28.033968)
			(xy 6.595377 -28.15588) (xy 6.641428 -28.280721) (xy 6.68005 -28.408056) (xy 6.711108 -28.537444)
			(xy 6.712088 -28.542933) (xy 10.382999 -28.542933) (xy 10.382999 -28.457207) (xy 10.390909 -28.371847)
			(xy 10.406661 -28.28758) (xy 10.430121 -28.205127) (xy 10.461089 -28.12519) (xy 10.4993 -28.048451)
			(xy 10.544429 -27.975565) (xy 10.59609 -27.907154) (xy 10.653844 -27.843802) (xy 10.717196 -27.786048)
			(xy 10.785607 -27.734387) (xy 10.858493 -27.689258) (xy 10.935232 -27.651047) (xy 11.015169 -27.620079)
			(xy 11.097622 -27.596619) (xy 11.181889 -27.580867) (xy 11.267249 -27.572957) (xy 11.352975 -27.572957)
			(xy 11.438335 -27.580867) (xy 11.522602 -27.596619) (xy 11.605055 -27.620079) (xy 11.684992 -27.651047)
			(xy 11.761731 -27.689258) (xy 11.834617 -27.734387) (xy 11.903028 -27.786048) (xy 11.96638 -27.843802)
			(xy 12.024134 -27.907154) (xy 12.075795 -27.975565) (xy 12.120924 -28.048451) (xy 12.159135 -28.12519)
			(xy 12.190103 -28.205127) (xy 12.213563 -28.28758) (xy 12.229315 -28.371847) (xy 12.237225 -28.457207)
			(xy 12.23772 -28.50007) (xy 12.237225 -28.542933) (xy 12.229315 -28.628293) (xy 12.213563 -28.71256)
			(xy 12.190103 -28.795013) (xy 12.159135 -28.87495) (xy 12.120924 -28.951689) (xy 12.075795 -29.024575)
			(xy 12.024134 -29.092986) (xy 11.96638 -29.156338) (xy 11.903028 -29.214092) (xy 11.834617 -29.265753)
			(xy 11.761731 -29.310882) (xy 11.684992 -29.349093) (xy 11.605055 -29.380061) (xy 11.522602 -29.403521)
			(xy 11.438335 -29.419273) (xy 11.352975 -29.427183) (xy 11.267249 -29.427183) (xy 11.181889 -29.419273)
			(xy 11.097622 -29.403521) (xy 11.015169 -29.380061) (xy 10.935232 -29.349093) (xy 10.858493 -29.310882)
			(xy 10.785607 -29.265753) (xy 10.717196 -29.214092) (xy 10.653844 -29.156338) (xy 10.59609 -29.092986)
			(xy 10.544429 -29.024575) (xy 10.4993 -28.951689) (xy 10.461089 -28.87495) (xy 10.430121 -28.795013)
			(xy 10.406661 -28.71256) (xy 10.390909 -28.628293) (xy 10.382999 -28.542933) (xy 6.712088 -28.542933)
			(xy 6.734494 -28.668436) (xy 6.750127 -28.800577) (xy 6.757954 -28.93341) (xy 6.758432 -28.999942)
			(xy 6.758432 -31.542927) (xy 10.382999 -31.542927) (xy 10.382999 -31.457201) (xy 10.390909 -31.371841)
			(xy 10.406661 -31.287574) (xy 10.430121 -31.205121) (xy 10.461089 -31.125184) (xy 10.4993 -31.048445)
			(xy 10.544429 -30.975559) (xy 10.59609 -30.907148) (xy 10.653844 -30.843796) (xy 10.717196 -30.786042)
			(xy 10.785607 -30.734381) (xy 10.858493 -30.689252) (xy 10.935232 -30.651041) (xy 11.015169 -30.620073)
			(xy 11.097622 -30.596613) (xy 11.181889 -30.580861) (xy 11.267249 -30.572951) (xy 11.352975 -30.572951)
			(xy 11.438335 -30.580861) (xy 11.522602 -30.596613) (xy 11.605055 -30.620073) (xy 11.684992 -30.651041)
			(xy 11.761731 -30.689252) (xy 11.834617 -30.734381) (xy 11.903028 -30.786042) (xy 11.96638 -30.843796)
			(xy 12.024134 -30.907148) (xy 12.075795 -30.975559) (xy 12.120924 -31.048445) (xy 12.159135 -31.125184)
			(xy 12.190103 -31.205121) (xy 12.213563 -31.287574) (xy 12.229315 -31.371841) (xy 12.237225 -31.457201)
			(xy 12.23772 -31.500064) (xy 12.237225 -31.542927) (xy 12.229315 -31.628287) (xy 12.213563 -31.712554)
			(xy 12.190103 -31.795007) (xy 12.159135 -31.874944) (xy 12.120924 -31.951683) (xy 12.075795 -32.024569)
			(xy 12.024134 -32.09298) (xy 11.96638 -32.156332) (xy 11.903028 -32.214086) (xy 11.834617 -32.265747)
			(xy 11.761731 -32.310876) (xy 11.684992 -32.349087) (xy 11.605055 -32.380055) (xy 11.522602 -32.403515)
			(xy 11.438335 -32.419267) (xy 11.352975 -32.427177) (xy 11.267249 -32.427177) (xy 11.181889 -32.419267)
			(xy 11.097622 -32.403515) (xy 11.015169 -32.380055) (xy 10.935232 -32.349087) (xy 10.858493 -32.310876)
			(xy 10.785607 -32.265747) (xy 10.717196 -32.214086) (xy 10.653844 -32.156332) (xy 10.59609 -32.09298)
			(xy 10.544429 -32.024569) (xy 10.4993 -31.951683) (xy 10.461089 -31.874944) (xy 10.430121 -31.795007)
			(xy 10.406661 -31.712554) (xy 10.390909 -31.628287) (xy 10.382999 -31.542927) (xy 6.758432 -31.542927)
			(xy 6.758432 -32.095186) (xy 6.75898 -32.128489) (xy 6.76797 -32.194487) (xy 6.785799 -32.258663)
			(xy 6.812141 -32.319839) (xy 6.846512 -32.376893) (xy 6.888281 -32.428776) (xy 6.912102 -32.452056)
			(xy 6.972768 -32.510183) (xy 7.089118 -32.631417) (xy 7.199532 -32.758081) (xy 7.303756 -32.889887)
			(xy 7.40155 -33.02653) (xy 7.492691 -33.167698) (xy 7.57697 -33.313067) (xy 7.654194 -33.462304)
			(xy 7.724184 -33.615067) (xy 7.786782 -33.771005) (xy 7.841843 -33.929761) (xy 7.889241 -34.09097)
			(xy 7.928868 -34.254264) (xy 7.960632 -34.419268) (xy 7.978346 -34.542921) (xy 10.382999 -34.542921)
			(xy 10.382999 -34.457195) (xy 10.390909 -34.371835) (xy 10.406661 -34.287568) (xy 10.430121 -34.205115)
			(xy 10.461089 -34.125178) (xy 10.4993 -34.048439) (xy 10.544429 -33.975553) (xy 10.59609 -33.907142)
			(xy 10.653844 -33.84379) (xy 10.717196 -33.786036) (xy 10.785607 -33.734375) (xy 10.858493 -33.689246)
			(xy 10.935232 -33.651035) (xy 11.015169 -33.620067) (xy 11.097622 -33.596607) (xy 11.181889 -33.580855)
			(xy 11.267249 -33.572945) (xy 11.352975 -33.572945) (xy 11.438335 -33.580855) (xy 11.522602 -33.596607)
			(xy 11.605055 -33.620067) (xy 11.684992 -33.651035) (xy 11.761731 -33.689246) (xy 11.834617 -33.734375)
			(xy 11.903028 -33.786036) (xy 11.96638 -33.84379) (xy 12.024134 -33.907142) (xy 12.075795 -33.975553)
			(xy 12.120924 -34.048439) (xy 12.159135 -34.125178) (xy 12.190103 -34.205115) (xy 12.213563 -34.287568)
			(xy 12.229315 -34.371835) (xy 12.237225 -34.457195) (xy 12.23772 -34.500058) (xy 12.237225 -34.542921)
			(xy 12.229315 -34.628281) (xy 12.213563 -34.712548) (xy 12.190103 -34.795001) (xy 12.159135 -34.874938)
			(xy 12.120924 -34.951677) (xy 12.075795 -35.024563) (xy 12.024134 -35.092974) (xy 11.96638 -35.156326)
			(xy 11.903028 -35.21408) (xy 11.834617 -35.265741) (xy 11.761731 -35.31087) (xy 11.684992 -35.349081)
			(xy 11.605055 -35.380049) (xy 11.522602 -35.403509) (xy 11.438335 -35.419261) (xy 11.352975 -35.427171)
			(xy 11.267249 -35.427171) (xy 11.181889 -35.419261) (xy 11.097622 -35.403509) (xy 11.015169 -35.380049)
			(xy 10.935232 -35.349081) (xy 10.858493 -35.31087) (xy 10.785607 -35.265741) (xy 10.717196 -35.21408)
			(xy 10.653844 -35.156326) (xy 10.59609 -35.092974) (xy 10.544429 -35.024563) (xy 10.4993 -34.951677)
			(xy 10.461089 -34.874938) (xy 10.430121 -34.795001) (xy 10.406661 -34.712548) (xy 10.390909 -34.628281)
			(xy 10.382999 -34.542921) (xy 7.978346 -34.542921) (xy 7.984461 -34.585603) (xy 8.000301 -34.752888)
			(xy 8.008114 -34.920739) (xy 8.007882 -35.088772) (xy 7.999608 -35.256601) (xy 7.983308 -35.423842)
			(xy 7.959022 -35.590111) (xy 7.926804 -35.755026) (xy 7.886728 -35.918211) (xy 7.838886 -36.079289)
			(xy 7.783389 -36.237893) (xy 7.720362 -36.393658) (xy 7.649952 -36.546228) (xy 7.572318 -36.695252)
			(xy 7.487639 -36.840389) (xy 7.39611 -36.981305) (xy 7.29794 -37.117679) (xy 7.193354 -37.249197)
			(xy 7.082593 -37.375557) (xy 6.965909 -37.496471) (xy 6.962106 -37.500052) (xy 9.403595 -37.500052)
			(xy 9.407599 -37.412167) (xy 9.419579 -37.32501) (xy 9.439434 -37.239303) (xy 9.467001 -37.155758)
			(xy 9.502051 -37.075065) (xy 9.544293 -36.997893) (xy 9.593378 -36.924883) (xy 9.648899 -36.856639)
			(xy 9.710396 -36.793726) (xy 9.777358 -36.736666) (xy 9.849232 -36.685932) (xy 9.925422 -36.641944)
			(xy 10.005296 -36.605066) (xy 10.088193 -36.575605) (xy 10.173425 -36.553803) (xy 10.260287 -36.539843)
			(xy 10.348058 -36.533839) (xy 10.436012 -36.535842) (xy 10.523419 -36.545834) (xy 10.609555 -36.563734)
			(xy 10.693707 -36.589392) (xy 10.775177 -36.622596) (xy 10.85329 -36.66307) (xy 10.927398 -36.710481)
			(xy 10.963694 -36.738661) (xy 23.469592 -36.738661) (xy 23.469592 -36.667339) (xy 23.477578 -36.596465)
			(xy 23.493448 -36.52693) (xy 23.517005 -36.45961) (xy 23.54795 -36.395351) (xy 23.585896 -36.33496)
			(xy 23.630365 -36.279198) (xy 23.680798 -36.228765) (xy 23.73656 -36.184296) (xy 23.796951 -36.14635)
			(xy 23.86121 -36.115405) (xy 23.92853 -36.091848) (xy 23.998065 -36.075978) (xy 24.068939 -36.067992)
			(xy 24.140261 -36.067992) (xy 24.211135 -36.075978) (xy 24.221138 -36.078261) (xy 25.272992 -36.078261)
			(xy 25.272992 -36.006939) (xy 25.280978 -35.936065) (xy 25.296848 -35.86653) (xy 25.320405 -35.79921)
			(xy 25.35135 -35.734951) (xy 25.389296 -35.67456) (xy 25.433765 -35.618798) (xy 25.484198 -35.568365)
			(xy 25.53996 -35.523896) (xy 25.600351 -35.48595) (xy 25.66461 -35.455005) (xy 25.73193 -35.431448)
			(xy 25.801465 -35.415578) (xy 25.872339 -35.407592) (xy 25.943661 -35.407592) (xy 26.014535 -35.415578)
			(xy 26.08407 -35.431448) (xy 26.15139 -35.455005) (xy 26.215649 -35.48595) (xy 26.27604 -35.523896)
			(xy 26.331802 -35.568365) (xy 26.382235 -35.618798) (xy 26.426704 -35.67456) (xy 26.46465 -35.734951)
			(xy 26.495595 -35.79921) (xy 26.519152 -35.86653) (xy 26.535022 -35.936065) (xy 26.543008 -36.006939)
			(xy 26.543508 -36.0426) (xy 26.543008 -36.078261) (xy 26.535022 -36.149135) (xy 26.519152 -36.21867)
			(xy 26.495595 -36.28599) (xy 26.475961 -36.326761) (xy 26.948648 -36.326761) (xy 26.955006 -36.255132)
			(xy 26.969409 -36.184679) (xy 26.991672 -36.116302) (xy 27.02151 -36.050874) (xy 27.058543 -35.989233)
			(xy 27.102296 -35.932165) (xy 27.152212 -35.880401) (xy 27.207651 -35.834602) (xy 27.267905 -35.795352)
			(xy 27.332204 -35.763155) (xy 27.399727 -35.738421) (xy 27.46961 -35.721466) (xy 27.54096 -35.712508)
			(xy 27.612865 -35.71166) (xy 27.684407 -35.718933) (xy 27.75467 -35.734236) (xy 27.822757 -35.757371)
			(xy 27.887798 -35.788043) (xy 27.948961 -35.825861) (xy 28.005464 -35.870341) (xy 28.056586 -35.920914)
			(xy 28.101673 -35.976934) (xy 28.140149 -36.037685) (xy 28.171522 -36.102391) (xy 28.195391 -36.170224)
			(xy 28.203906 -36.20516) (xy 28.209345 -36.227009) (xy 28.227009 -36.268425) (xy 28.251691 -36.306082)
			(xy 28.282619 -36.338803) (xy 28.318827 -36.365566) (xy 28.359182 -36.385534) (xy 28.402423 -36.398083)
			(xy 28.447198 -36.402821) (xy 28.492108 -36.399599) (xy 28.535748 -36.388517) (xy 28.576754 -36.369924)
			(xy 28.595574 -36.35756) (xy 28.625502 -36.337625) (xy 28.688957 -36.303794) (xy 28.755825 -36.277341)
			(xy 28.825252 -36.258605) (xy 28.896349 -36.247826) (xy 28.968209 -36.24514) (xy 29.039913 -36.250582)
			(xy 29.110545 -36.264083) (xy 29.179201 -36.285469) (xy 29.245005 -36.314469) (xy 29.307115 -36.35071)
			(xy 29.364737 -36.393731) (xy 29.380409 -36.408461) (xy 29.819592 -36.408461) (xy 29.819592 -36.337139)
			(xy 29.827578 -36.266265) (xy 29.843448 -36.19673) (xy 29.867005 -36.12941) (xy 29.89795 -36.065151)
			(xy 29.935896 -36.00476) (xy 29.980365 -35.948998) (xy 30.030798 -35.898565) (xy 30.08656 -35.854096)
			(xy 30.146951 -35.81615) (xy 30.21121 -35.785205) (xy 30.27853 -35.761648) (xy 30.348065 -35.745778)
			(xy 30.418939 -35.737792) (xy 30.490261 -35.737792) (xy 30.561135 -35.745778) (xy 30.63067 -35.761648)
			(xy 30.69799 -35.785205) (xy 30.762249 -35.81615) (xy 30.82264 -35.854096) (xy 30.878402 -35.898565)
			(xy 30.928835 -35.948998) (xy 30.973304 -36.00476) (xy 31.01125 -36.065151) (xy 31.042195 -36.12941)
			(xy 31.065752 -36.19673) (xy 31.067699 -36.205261) (xy 32.181792 -36.205261) (xy 32.181792 -36.133939)
			(xy 32.189778 -36.063065) (xy 32.205648 -35.99353) (xy 32.229205 -35.92621) (xy 32.26015 -35.861951)
			(xy 32.298096 -35.80156) (xy 32.342565 -35.745798) (xy 32.392998 -35.695365) (xy 32.44876 -35.650896)
			(xy 32.509151 -35.61295) (xy 32.57341 -35.582005) (xy 32.64073 -35.558448) (xy 32.710265 -35.542578)
			(xy 32.781139 -35.534592) (xy 32.852461 -35.534592) (xy 32.923335 -35.542578) (xy 32.99287 -35.558448)
			(xy 33.06019 -35.582005) (xy 33.088547 -35.595661) (xy 75.641192 -35.595661) (xy 75.641192 -35.524339)
			(xy 75.649178 -35.453465) (xy 75.665048 -35.38393) (xy 75.688605 -35.31661) (xy 75.71955 -35.252351)
			(xy 75.757496 -35.19196) (xy 75.801965 -35.136198) (xy 75.852398 -35.085765) (xy 75.90816 -35.041296)
			(xy 75.968551 -35.00335) (xy 76.03281 -34.972405) (xy 76.10013 -34.948848) (xy 76.169665 -34.932978)
			(xy 76.240539 -34.924992) (xy 76.311861 -34.924992) (xy 76.382735 -34.932978) (xy 76.45227 -34.948848)
			(xy 76.51959 -34.972405) (xy 76.583849 -35.00335) (xy 76.64424 -35.041296) (xy 76.700002 -35.085765)
			(xy 76.750435 -35.136198) (xy 76.794904 -35.19196) (xy 76.83285 -35.252351) (xy 76.863795 -35.31661)
			(xy 76.887352 -35.38393) (xy 76.903222 -35.453465) (xy 76.911208 -35.524339) (xy 76.911708 -35.56)
			(xy 76.911208 -35.595661) (xy 76.903222 -35.666535) (xy 76.887352 -35.73607) (xy 76.863795 -35.80339)
			(xy 76.83285 -35.867649) (xy 76.794904 -35.92804) (xy 76.750435 -35.983802) (xy 76.700002 -36.034235)
			(xy 76.64424 -36.078704) (xy 76.583849 -36.11665) (xy 76.51959 -36.147595) (xy 76.45227 -36.171152)
			(xy 76.382735 -36.187022) (xy 76.311861 -36.195008) (xy 76.240539 -36.195008) (xy 76.169665 -36.187022)
			(xy 76.10013 -36.171152) (xy 76.03281 -36.147595) (xy 75.968551 -36.11665) (xy 75.90816 -36.078704)
			(xy 75.852398 -36.034235) (xy 75.801965 -35.983802) (xy 75.757496 -35.92804) (xy 75.71955 -35.867649)
			(xy 75.688605 -35.80339) (xy 75.665048 -35.73607) (xy 75.649178 -35.666535) (xy 75.641192 -35.595661)
			(xy 33.088547 -35.595661) (xy 33.124449 -35.61295) (xy 33.18484 -35.650896) (xy 33.240602 -35.695365)
			(xy 33.291035 -35.745798) (xy 33.335504 -35.80156) (xy 33.37345 -35.861951) (xy 33.404395 -35.92621)
			(xy 33.427952 -35.99353) (xy 33.443822 -36.063065) (xy 33.451808 -36.133939) (xy 33.452308 -36.1696)
			(xy 33.451808 -36.205261) (xy 33.443822 -36.276135) (xy 33.427952 -36.34567) (xy 33.404395 -36.41299)
			(xy 33.37345 -36.477249) (xy 33.335504 -36.53764) (xy 33.291035 -36.593402) (xy 33.240602 -36.643835)
			(xy 33.18484 -36.688304) (xy 33.124449 -36.72625) (xy 33.06019 -36.757195) (xy 32.99287 -36.780752)
			(xy 32.923335 -36.796622) (xy 32.852461 -36.804608) (xy 32.781139 -36.804608) (xy 32.710265 -36.796622)
			(xy 32.64073 -36.780752) (xy 32.57341 -36.757195) (xy 32.509151 -36.72625) (xy 32.44876 -36.688304)
			(xy 32.392998 -36.643835) (xy 32.342565 -36.593402) (xy 32.298096 -36.53764) (xy 32.26015 -36.477249)
			(xy 32.229205 -36.41299) (xy 32.205648 -36.34567) (xy 32.189778 -36.276135) (xy 32.181792 -36.205261)
			(xy 31.067699 -36.205261) (xy 31.081622 -36.266265) (xy 31.089608 -36.337139) (xy 31.090108 -36.3728)
			(xy 31.089608 -36.408461) (xy 31.081622 -36.479335) (xy 31.065752 -36.54887) (xy 31.042195 -36.61619)
			(xy 31.01125 -36.680449) (xy 30.973304 -36.74084) (xy 30.928835 -36.796602) (xy 30.878402 -36.847035)
			(xy 30.82264 -36.891504) (xy 30.782921 -36.916461) (xy 67.360792 -36.916461) (xy 67.360792 -36.845139)
			(xy 67.368778 -36.774265) (xy 67.384648 -36.70473) (xy 67.408205 -36.63741) (xy 67.43915 -36.573151)
			(xy 67.477096 -36.51276) (xy 67.521565 -36.456998) (xy 67.571998 -36.406565) (xy 67.62776 -36.362096)
			(xy 67.688151 -36.32415) (xy 67.75241 -36.293205) (xy 67.81973 -36.269648) (xy 67.889265 -36.253778)
			(xy 67.960139 -36.245792) (xy 68.031461 -36.245792) (xy 68.102335 -36.253778) (xy 68.17187 -36.269648)
			(xy 68.23919 -36.293205) (xy 68.303449 -36.32415) (xy 68.36384 -36.362096) (xy 68.419602 -36.406565)
			(xy 68.470035 -36.456998) (xy 68.514504 -36.51276) (xy 68.55245 -36.573151) (xy 68.583395 -36.63741)
			(xy 68.606952 -36.70473) (xy 68.622822 -36.774265) (xy 68.630808 -36.845139) (xy 68.631308 -36.8808)
			(xy 68.630808 -36.916461) (xy 68.622822 -36.987335) (xy 68.606952 -37.05687) (xy 68.583395 -37.12419)
			(xy 68.55245 -37.188449) (xy 68.514504 -37.24884) (xy 68.470035 -37.304602) (xy 68.419602 -37.355035)
			(xy 68.36384 -37.399504) (xy 68.303449 -37.43745) (xy 68.23919 -37.468395) (xy 68.17187 -37.491952)
			(xy 68.102335 -37.507822) (xy 68.031461 -37.515808) (xy 67.960139 -37.515808) (xy 67.889265 -37.507822)
			(xy 67.81973 -37.491952) (xy 67.75241 -37.468395) (xy 67.688151 -37.43745) (xy 67.62776 -37.399504)
			(xy 67.571998 -37.355035) (xy 67.521565 -37.304602) (xy 67.477096 -37.24884) (xy 67.43915 -37.188449)
			(xy 67.408205 -37.12419) (xy 67.384648 -37.05687) (xy 67.368778 -36.987335) (xy 67.360792 -36.916461)
			(xy 30.782921 -36.916461) (xy 30.762249 -36.92945) (xy 30.69799 -36.960395) (xy 30.63067 -36.983952)
			(xy 30.561135 -36.999822) (xy 30.490261 -37.007808) (xy 30.418939 -37.007808) (xy 30.348065 -36.999822)
			(xy 30.27853 -36.983952) (xy 30.21121 -36.960395) (xy 30.146951 -36.92945) (xy 30.08656 -36.891504)
			(xy 30.030798 -36.847035) (xy 29.980365 -36.796602) (xy 29.935896 -36.74084) (xy 29.89795 -36.680449)
			(xy 29.867005 -36.61619) (xy 29.843448 -36.54887) (xy 29.827578 -36.479335) (xy 29.819592 -36.408461)
			(xy 29.380409 -36.408461) (xy 29.417135 -36.44298) (xy 29.46364 -36.497829) (xy 29.503656 -36.557577)
			(xy 29.536673 -36.621459) (xy 29.562269 -36.68866) (xy 29.580115 -36.758321) (xy 29.589985 -36.82955)
			(xy 29.591752 -36.901439) (xy 29.585394 -36.973068) (xy 29.570991 -37.043521) (xy 29.548728 -37.111898)
			(xy 29.51889 -37.177326) (xy 29.481857 -37.238967) (xy 29.438104 -37.296035) (xy 29.388188 -37.347799)
			(xy 29.332749 -37.393598) (xy 29.272495 -37.432848) (xy 29.208196 -37.465045) (xy 29.140673 -37.489779)
			(xy 29.07079 -37.506734) (xy 28.99944 -37.515692) (xy 28.927535 -37.51654) (xy 28.855993 -37.509267)
			(xy 28.78573 -37.493964) (xy 28.717643 -37.470829) (xy 28.652602 -37.440157) (xy 28.591439 -37.402339)
			(xy 28.534936 -37.357859) (xy 28.483814 -37.307286) (xy 28.438727 -37.251266) (xy 28.400251 -37.190515)
			(xy 28.368878 -37.125809) (xy 28.345009 -37.057976) (xy 28.336494 -37.02304) (xy 28.331055 -37.001191)
			(xy 28.313391 -36.959775) (xy 28.288709 -36.922118) (xy 28.257781 -36.889397) (xy 28.221573 -36.862634)
			(xy 28.181218 -36.842666) (xy 28.137977 -36.830117) (xy 28.093202 -36.825379) (xy 28.048292 -36.828601)
			(xy 28.004652 -36.839683) (xy 27.963646 -36.858276) (xy 27.944826 -36.87064) (xy 27.914898 -36.890575)
			(xy 27.851443 -36.924406) (xy 27.784575 -36.950859) (xy 27.715148 -36.969595) (xy 27.644051 -36.980374)
			(xy 27.572191 -36.98306) (xy 27.500487 -36.977618) (xy 27.429855 -36.964117) (xy 27.361199 -36.942731)
			(xy 27.295395 -36.913731) (xy 27.233285 -36.87749) (xy 27.175663 -36.834469) (xy 27.123265 -36.78522)
			(xy 27.07676 -36.730371) (xy 27.036744 -36.670623) (xy 27.003727 -36.606741) (xy 26.978131 -36.53954)
			(xy 26.960285 -36.469879) (xy 26.950415 -36.39865) (xy 26.948648 -36.326761) (xy 26.475961 -36.326761)
			(xy 26.46465 -36.350249) (xy 26.426704 -36.41064) (xy 26.382235 -36.466402) (xy 26.331802 -36.516835)
			(xy 26.27604 -36.561304) (xy 26.215649 -36.59925) (xy 26.15139 -36.630195) (xy 26.08407 -36.653752)
			(xy 26.014535 -36.669622) (xy 25.943661 -36.677608) (xy 25.872339 -36.677608) (xy 25.801465 -36.669622)
			(xy 25.73193 -36.653752) (xy 25.66461 -36.630195) (xy 25.600351 -36.59925) (xy 25.53996 -36.561304)
			(xy 25.484198 -36.516835) (xy 25.433765 -36.466402) (xy 25.389296 -36.41064) (xy 25.35135 -36.350249)
			(xy 25.320405 -36.28599) (xy 25.296848 -36.21867) (xy 25.280978 -36.149135) (xy 25.272992 -36.078261)
			(xy 24.221138 -36.078261) (xy 24.28067 -36.091848) (xy 24.34799 -36.115405) (xy 24.412249 -36.14635)
			(xy 24.47264 -36.184296) (xy 24.528402 -36.228765) (xy 24.578835 -36.279198) (xy 24.623304 -36.33496)
			(xy 24.66125 -36.395351) (xy 24.692195 -36.45961) (xy 24.715752 -36.52693) (xy 24.731622 -36.596465)
			(xy 24.739608 -36.667339) (xy 24.740108 -36.703) (xy 24.739608 -36.738661) (xy 24.731622 -36.809535)
			(xy 24.715752 -36.87907) (xy 24.692195 -36.94639) (xy 24.66125 -37.010649) (xy 24.623304 -37.07104)
			(xy 24.578835 -37.126802) (xy 24.528402 -37.177235) (xy 24.47264 -37.221704) (xy 24.412249 -37.25965)
			(xy 24.34799 -37.290595) (xy 24.28067 -37.314152) (xy 24.211135 -37.330022) (xy 24.140261 -37.338008)
			(xy 24.068939 -37.338008) (xy 23.998065 -37.330022) (xy 23.92853 -37.314152) (xy 23.86121 -37.290595)
			(xy 23.796951 -37.25965) (xy 23.73656 -37.221704) (xy 23.680798 -37.177235) (xy 23.630365 -37.126802)
			(xy 23.585896 -37.07104) (xy 23.54795 -37.010649) (xy 23.517005 -36.94639) (xy 23.493448 -36.87907)
			(xy 23.477578 -36.809535) (xy 23.469592 -36.738661) (xy 10.963694 -36.738661) (xy 10.996889 -36.764434)
			(xy 11.061185 -36.824482) (xy 11.119754 -36.890129) (xy 11.172111 -36.960829) (xy 11.217823 -37.035998)
			(xy 11.256509 -37.115012) (xy 11.28785 -37.197217) (xy 11.311585 -37.281931) (xy 11.327519 -37.368452)
			(xy 11.335519 -37.456064) (xy 11.33602 -37.500052) (xy 11.335519 -37.54404) (xy 11.327519 -37.631652)
			(xy 11.311585 -37.718173) (xy 11.28785 -37.802887) (xy 11.256509 -37.885092) (xy 11.217823 -37.964106)
			(xy 11.172111 -38.039275) (xy 11.119754 -38.109975) (xy 11.061576 -38.175184) (xy 21.970541 -38.175184)
			(xy 21.971759 -38.10453) (xy 21.980808 -38.034448) (xy 21.997577 -37.965802) (xy 22.021858 -37.899441)
			(xy 22.053352 -37.836184) (xy 22.091671 -37.776811) (xy 22.136339 -37.722056) (xy 22.186807 -37.672595)
			(xy 22.242451 -37.629038) (xy 22.302584 -37.591925) (xy 22.366464 -37.561712) (xy 22.433301 -37.538772)
			(xy 22.50227 -37.52339) (xy 22.57252 -37.515755) (xy 22.643184 -37.515961) (xy 22.713389 -37.524006)
			(xy 22.782267 -37.53979) (xy 22.848969 -37.563119) (xy 22.912671 -37.593704) (xy 22.972587 -37.631168)
			(xy 23.027976 -37.675049) (xy 23.078154 -37.724803) (xy 23.122503 -37.779818) (xy 23.138229 -37.8045)
			(xy 24.510237 -37.8045) (xy 24.516013 -37.733674) (xy 24.529654 -37.663935) (xy 24.55099 -37.596154)
			(xy 24.579755 -37.531175) (xy 24.61559 -37.469812) (xy 24.658046 -37.412829) (xy 24.706595 -37.360938)
			(xy 24.76063 -37.314788) (xy 24.819475 -37.274953) (xy 24.882398 -37.241933) (xy 24.948611 -37.216138)
			(xy 25.017289 -37.197891) (xy 25.087574 -37.18742) (xy 25.158589 -37.184855) (xy 25.229446 -37.190228)
			(xy 25.299261 -37.203473) (xy 25.367163 -37.224424) (xy 25.432303 -37.25282) (xy 25.49387 -37.288305)
			(xy 25.551093 -37.330437) (xy 25.603258 -37.37869) (xy 25.649715 -37.432462) (xy 25.689883 -37.491081)
			(xy 25.723261 -37.553815) (xy 25.736804 -37.586666) (xy 25.745214 -37.606826) (xy 25.767981 -37.644104)
			(xy 25.796787 -37.676939) (xy 25.830783 -37.704366) (xy 25.868968 -37.725575) (xy 25.910217 -37.739943)
			(xy 25.953316 -37.747046) (xy 25.996995 -37.746675) (xy 26.039966 -37.73884) (xy 26.080966 -37.723774)
			(xy 26.118785 -37.701918) (xy 26.135838 -37.688266) (xy 26.163402 -37.665842) (xy 26.222697 -37.626679)
			(xy 26.28599 -37.594375) (xy 26.352493 -37.569334) (xy 26.421373 -37.551869) (xy 26.491773 -37.542197)
			(xy 26.562811 -37.540439) (xy 26.633603 -37.546617) (xy 26.703263 -37.560654) (xy 26.770923 -37.582375)
			(xy 26.835737 -37.611509) (xy 26.896896 -37.647692) (xy 26.953636 -37.690471) (xy 27.00525 -37.739314)
			(xy 27.051093 -37.79361) (xy 27.090593 -37.852681) (xy 27.123255 -37.91579) (xy 27.148674 -37.982149)
			(xy 27.16653 -38.050929) (xy 27.176602 -38.121273) (xy 27.178763 -38.1923) (xy 27.172987 -38.263126)
			(xy 27.159346 -38.332865) (xy 27.13801 -38.400646) (xy 27.109245 -38.465625) (xy 27.07341 -38.526988)
			(xy 27.030954 -38.583971) (xy 27.022637 -38.592861) (xy 27.762192 -38.592861) (xy 27.762192 -38.521539)
			(xy 27.770178 -38.450665) (xy 27.786048 -38.38113) (xy 27.809605 -38.31381) (xy 27.84055 -38.249551)
			(xy 27.878496 -38.18916) (xy 27.922965 -38.133398) (xy 27.973398 -38.082965) (xy 28.02916 -38.038496)
			(xy 28.089551 -38.00055) (xy 28.15381 -37.969605) (xy 28.22113 -37.946048) (xy 28.290665 -37.930178)
			(xy 28.361539 -37.922192) (xy 28.432861 -37.922192) (xy 28.503735 -37.930178) (xy 28.57327 -37.946048)
			(xy 28.64059 -37.969605) (xy 28.704849 -38.00055) (xy 28.76524 -38.038496) (xy 28.821002 -38.082965)
			(xy 28.871435 -38.133398) (xy 28.915904 -38.18916) (xy 28.95385 -38.249551) (xy 28.984795 -38.31381)
			(xy 29.008352 -38.38113) (xy 29.024222 -38.450665) (xy 29.032208 -38.521539) (xy 29.032708 -38.5572)
			(xy 29.032208 -38.592861) (xy 29.024222 -38.663735) (xy 29.008352 -38.73327) (xy 28.984795 -38.80059)
			(xy 28.95385 -38.864849) (xy 28.915904 -38.92524) (xy 28.871435 -38.981002) (xy 28.821002 -39.031435)
			(xy 28.76524 -39.075904) (xy 28.704849 -39.11385) (xy 28.64059 -39.144795) (xy 28.57327 -39.168352)
			(xy 28.503735 -39.184222) (xy 28.432861 -39.192208) (xy 28.361539 -39.192208) (xy 28.290665 -39.184222)
			(xy 28.22113 -39.168352) (xy 28.15381 -39.144795) (xy 28.089551 -39.11385) (xy 28.02916 -39.075904)
			(xy 27.973398 -39.031435) (xy 27.922965 -38.981002) (xy 27.878496 -38.92524) (xy 27.84055 -38.864849)
			(xy 27.809605 -38.80059) (xy 27.786048 -38.73327) (xy 27.770178 -38.663735) (xy 27.762192 -38.592861)
			(xy 27.022637 -38.592861) (xy 26.982405 -38.635862) (xy 26.92837 -38.682012) (xy 26.869525 -38.721847)
			(xy 26.806602 -38.754867) (xy 26.740389 -38.780662) (xy 26.671711 -38.798909) (xy 26.601426 -38.80938)
			(xy 26.530411 -38.811945) (xy 26.459554 -38.806572) (xy 26.389739 -38.793327) (xy 26.321837 -38.772376)
			(xy 26.256697 -38.74398) (xy 26.19513 -38.708495) (xy 26.137907 -38.666363) (xy 26.085742 -38.61811)
			(xy 26.039285 -38.564338) (xy 25.999117 -38.505719) (xy 25.965739 -38.442985) (xy 25.952196 -38.410134)
			(xy 25.943786 -38.389974) (xy 25.921019 -38.352696) (xy 25.892213 -38.319861) (xy 25.858217 -38.292434)
			(xy 25.820032 -38.271225) (xy 25.778783 -38.256857) (xy 25.735684 -38.249754) (xy 25.692005 -38.250125)
			(xy 25.649034 -38.25796) (xy 25.608034 -38.273026) (xy 25.570215 -38.294882) (xy 25.553162 -38.308534)
			(xy 25.525598 -38.330958) (xy 25.466303 -38.370121) (xy 25.40301 -38.402425) (xy 25.336507 -38.427466)
			(xy 25.267627 -38.444931) (xy 25.197227 -38.454603) (xy 25.126189 -38.456361) (xy 25.055397 -38.450183)
			(xy 24.985737 -38.436146) (xy 24.918077 -38.414425) (xy 24.853263 -38.385291) (xy 24.792104 -38.349108)
			(xy 24.735364 -38.306329) (xy 24.68375 -38.257486) (xy 24.637907 -38.20319) (xy 24.598407 -38.144119)
			(xy 24.565745 -38.08101) (xy 24.540326 -38.014651) (xy 24.52247 -37.945871) (xy 24.512398 -37.875527)
			(xy 24.510237 -37.8045) (xy 23.138229 -37.8045) (xy 23.160474 -37.839413) (xy 23.191598 -37.902854)
			(xy 23.215492 -37.969355) (xy 23.23186 -38.038098) (xy 23.2405 -38.108231) (xy 23.241306 -38.178891)
			(xy 23.234267 -38.249203) (xy 23.219471 -38.318301) (xy 23.208742 -38.351968) (xy 23.202016 -38.373751)
			(xy 23.19553 -38.41887) (xy 23.197192 -38.464424) (xy 23.206949 -38.50895) (xy 23.22449 -38.551024)
			(xy 23.249251 -38.589296) (xy 23.280439 -38.62254) (xy 23.317054 -38.64969) (xy 23.357924 -38.669877)
			(xy 23.401739 -38.682453) (xy 23.447093 -38.687016) (xy 23.469854 -38.685724) (xy 23.505868 -38.683357)
			(xy 23.578003 -38.685805) (xy 23.649395 -38.69641) (xy 23.719127 -38.715035) (xy 23.786299 -38.741441)
			(xy 23.850047 -38.775288) (xy 23.90955 -38.816139) (xy 23.964041 -38.863469) (xy 24.012819 -38.916669)
			(xy 24.055255 -38.975052) (xy 24.090803 -39.037867) (xy 24.119005 -39.104305) (xy 24.139498 -39.173511)
			(xy 24.146256 -39.208964) (xy 24.15074 -39.23148) (xy 24.166744 -39.274508) (xy 24.190214 -39.313962)
			(xy 24.220387 -39.34856) (xy 24.256283 -39.377177) (xy 24.296734 -39.398883) (xy 24.340426 -39.412972)
			(xy 24.385937 -39.418986) (xy 24.431789 -39.41673) (xy 24.47649 -39.406276) (xy 24.518587 -39.387965)
			(xy 24.537924 -39.375588) (xy 24.567615 -39.356235) (xy 24.630499 -39.323539) (xy 24.69663 -39.298042)
			(xy 24.765188 -39.280063) (xy 24.83532 -39.269823) (xy 24.906157 -39.26745) (xy 24.976818 -39.272973)
			(xy 25.046425 -39.286324) (xy 25.114115 -39.307338) (xy 25.179046 -39.335752) (xy 25.240412 -39.371214)
			(xy 25.297452 -39.413285) (xy 25.349456 -39.46144) (xy 25.39578 -39.515083) (xy 25.435847 -39.573548)
			(xy 25.46916 -39.636107) (xy 25.495306 -39.701984) (xy 25.513959 -39.770362) (xy 25.524889 -39.84039)
			(xy 25.527959 -39.9112) (xy 25.523131 -39.981911) (xy 25.517074 -40.015261) (xy 26.009592 -40.015261)
			(xy 26.009592 -39.943939) (xy 26.017578 -39.873065) (xy 26.033448 -39.80353) (xy 26.057005 -39.73621)
			(xy 26.08795 -39.671951) (xy 26.125896 -39.61156) (xy 26.170365 -39.555798) (xy 26.220798 -39.505365)
			(xy 26.27656 -39.460896) (xy 26.336951 -39.42295) (xy 26.40121 -39.392005) (xy 26.46853 -39.368448)
			(xy 26.538065 -39.352578) (xy 26.608939 -39.344592) (xy 26.680261 -39.344592) (xy 26.751135 -39.352578)
			(xy 26.82067 -39.368448) (xy 26.88799 -39.392005) (xy 26.952249 -39.42295) (xy 27.01264 -39.460896)
			(xy 27.068402 -39.505365) (xy 27.118835 -39.555798) (xy 27.163304 -39.61156) (xy 27.20125 -39.671951)
			(xy 27.232195 -39.73621) (xy 27.255752 -39.80353) (xy 27.271622 -39.873065) (xy 27.279608 -39.943939)
			(xy 27.280108 -39.9796) (xy 27.279608 -40.015261) (xy 27.271622 -40.086135) (xy 27.255752 -40.15567)
			(xy 27.232195 -40.22299) (xy 27.20125 -40.287249) (xy 27.163304 -40.34764) (xy 27.118835 -40.403402)
			(xy 27.117792 -40.404445) (xy 27.533417 -40.404445) (xy 27.541006 -40.333693) (xy 27.556452 -40.264231)
			(xy 27.579561 -40.19693) (xy 27.610043 -40.132631) (xy 27.647517 -40.07214) (xy 27.691513 -40.016214)
			(xy 27.741482 -39.965552) (xy 27.796797 -39.920789) (xy 27.856766 -39.882486) (xy 27.920639 -39.851121)
			(xy 27.987616 -39.827087) (xy 28.056858 -39.810686) (xy 28.127499 -39.802123) (xy 28.198654 -39.801504)
			(xy 28.269433 -39.808837) (xy 28.33895 -39.824031) (xy 28.406335 -39.846896) (xy 28.470744 -39.877145)
			(xy 28.53137 -39.914399) (xy 28.587456 -39.958193) (xy 28.638298 -40.007978) (xy 28.683261 -40.06313)
			(xy 28.721781 -40.122961) (xy 28.753377 -40.186719) (xy 28.777653 -40.253609) (xy 28.794305 -40.322791)
			(xy 28.803124 -40.3934) (xy 28.804001 -40.464553) (xy 28.796924 -40.535358) (xy 28.781982 -40.60493)
			(xy 28.759361 -40.672397) (xy 28.729346 -40.736915) (xy 28.692311 -40.797676) (xy 28.648721 -40.853919)
			(xy 28.624276 -40.879776) (xy 28.609401 -40.895856) (xy 28.584722 -40.932037) (xy 28.566613 -40.971915)
			(xy 28.55561 -41.014308) (xy 28.55204 -41.057959) (xy 28.556008 -41.101576) (xy 28.567396 -41.143866)
			(xy 28.585867 -41.183578) (xy 28.601571 -41.206156) (xy 29.362322 -41.206156) (xy 29.36264 -41.134978)
			(xy 29.37091 -41.064282) (xy 29.387028 -40.994953) (xy 29.410794 -40.92786) (xy 29.441908 -40.863842)
			(xy 29.479982 -40.803703) (xy 29.524538 -40.748196) (xy 29.575018 -40.698015) (xy 29.63079 -40.65379)
			(xy 29.691155 -40.616075) (xy 29.755356 -40.585342) (xy 29.82259 -40.561977) (xy 29.857192 -40.55364)
			(xy 29.879233 -40.548128) (xy 29.921062 -40.530408) (xy 29.959077 -40.505539) (xy 29.992069 -40.474311)
			(xy 30.018988 -40.437719) (xy 30.038978 -40.396926) (xy 30.051403 -40.353231) (xy 30.055867 -40.308024)
			(xy 30.052228 -40.262742) (xy 30.040603 -40.218828) (xy 30.031436 -40.19804) (xy 30.01719 -40.166419)
			(xy 29.994802 -40.100773) (xy 29.9797 -40.03308) (xy 29.972061 -39.964145) (xy 29.971977 -39.894787)
			(xy 29.979449 -39.825833) (xy 29.994389 -39.758104) (xy 30.016618 -39.692405) (xy 30.045871 -39.629519)
			(xy 30.06344 -39.599616) (xy 30.075212 -39.579141) (xy 30.091829 -39.534938) (xy 30.09999 -39.488426)
			(xy 30.099415 -39.441207) (xy 30.090124 -39.394907) (xy 30.072436 -39.351122) (xy 30.046961 -39.31136)
			(xy 30.014576 -39.276991) (xy 29.976398 -39.249199) (xy 29.93374 -39.228942) (xy 29.91104 -39.222426)
			(xy 29.877019 -39.212992) (xy 29.811182 -39.187486) (xy 29.748578 -39.15484) (xy 29.689978 -39.115456)
			(xy 29.636105 -39.069819) (xy 29.587622 -39.018492) (xy 29.545128 -38.962108) (xy 29.509144 -38.90136)
			(xy 29.480116 -38.836999) (xy 29.458401 -38.769816) (xy 29.444266 -38.700641) (xy 29.437886 -38.630325)
			(xy 29.439339 -38.559735) (xy 29.448608 -38.489741) (xy 29.465578 -38.421206) (xy 29.490039 -38.354974)
			(xy 29.521692 -38.291862) (xy 29.560144 -38.232647) (xy 29.604924 -38.178059) (xy 29.655478 -38.128771)
			(xy 29.711184 -38.08539) (xy 29.771354 -38.048451) (xy 29.835249 -38.018409) (xy 29.90208 -37.995635)
			(xy 29.971023 -37.980408) (xy 30.041229 -37.972917) (xy 30.111833 -37.973254) (xy 30.181965 -37.981415)
			(xy 30.25076 -37.997299) (xy 30.283086 -38.008661) (xy 31.521392 -38.008661) (xy 31.521392 -37.937339)
			(xy 31.529378 -37.866465) (xy 31.545248 -37.79693) (xy 31.568805 -37.72961) (xy 31.59975 -37.665351)
			(xy 31.637696 -37.60496) (xy 31.682165 -37.549198) (xy 31.732598 -37.498765) (xy 31.78836 -37.454296)
			(xy 31.848751 -37.41635) (xy 31.91301 -37.385405) (xy 31.98033 -37.361848) (xy 32.049865 -37.345978)
			(xy 32.120739 -37.337992) (xy 32.192061 -37.337992) (xy 32.262935 -37.345978) (xy 32.33247 -37.361848)
			(xy 32.39979 -37.385405) (xy 32.464049 -37.41635) (xy 32.52444 -37.454296) (xy 32.580202 -37.498765)
			(xy 32.630635 -37.549198) (xy 32.675104 -37.60496) (xy 32.71305 -37.665351) (xy 32.743995 -37.72961)
			(xy 32.767552 -37.79693) (xy 32.783422 -37.866465) (xy 32.791408 -37.937339) (xy 32.791908 -37.973)
			(xy 32.791408 -38.008661) (xy 32.783422 -38.079535) (xy 32.767552 -38.14907) (xy 32.743995 -38.21639)
			(xy 32.71305 -38.280649) (xy 32.675104 -38.34104) (xy 32.630635 -38.396802) (xy 32.580202 -38.447235)
			(xy 32.52444 -38.491704) (xy 32.464049 -38.52965) (xy 32.39979 -38.560595) (xy 32.33247 -38.584152)
			(xy 32.262935 -38.600022) (xy 32.192061 -38.608008) (xy 32.120739 -38.608008) (xy 32.049865 -38.600022)
			(xy 31.98033 -38.584152) (xy 31.91301 -38.560595) (xy 31.848751 -38.52965) (xy 31.78836 -38.491704)
			(xy 31.732598 -38.447235) (xy 31.682165 -38.396802) (xy 31.637696 -38.34104) (xy 31.59975 -38.280649)
			(xy 31.568805 -38.21639) (xy 31.545248 -38.14907) (xy 31.529378 -38.079535) (xy 31.521392 -38.008661)
			(xy 30.283086 -38.008661) (xy 30.31737 -38.020711) (xy 30.380975 -38.051361) (xy 30.44079 -38.088873)
			(xy 30.496079 -38.132784) (xy 30.546161 -38.182552) (xy 30.590417 -38.237565) (xy 30.628302 -38.297145)
			(xy 30.659351 -38.360556) (xy 30.683179 -38.427019) (xy 30.699494 -38.495713) (xy 30.708093 -38.565792)
			(xy 30.708873 -38.636392) (xy 30.701822 -38.706644) (xy 30.687027 -38.775681) (xy 30.664671 -38.842653)
			(xy 30.63503 -38.906735) (xy 30.61716 -38.937184) (xy 30.605388 -38.957659) (xy 30.588771 -39.001862)
			(xy 30.58061 -39.048374) (xy 30.581185 -39.095593) (xy 30.590476 -39.141893) (xy 30.608164 -39.185678)
			(xy 30.633639 -39.22544) (xy 30.666024 -39.259809) (xy 30.704202 -39.287601) (xy 30.74686 -39.307858)
			(xy 30.76956 -39.314374) (xy 30.803508 -39.323808) (xy 30.86921 -39.349267) (xy 30.931693 -39.381837)
			(xy 30.99019 -39.421119) (xy 31.043983 -39.466631) (xy 31.092411 -39.517813) (xy 31.134881 -39.574039)
			(xy 31.170872 -39.634616) (xy 31.19994 -39.698804) (xy 31.221731 -39.765812) (xy 31.235975 -39.83482)
			(xy 31.242499 -39.90498) (xy 31.241223 -39.975431) (xy 31.232161 -40.045308) (xy 31.215426 -40.113755)
			(xy 31.191223 -40.17993) (xy 31.159848 -40.243022) (xy 31.121686 -40.302256) (xy 31.077207 -40.356906)
			(xy 31.026956 -40.4063) (xy 30.97155 -40.449833) (xy 30.911668 -40.48697) (xy 30.848046 -40.517255)
			(xy 30.830707 -40.523261) (xy 63.423792 -40.523261) (xy 63.423792 -40.451939) (xy 63.431778 -40.381065)
			(xy 63.447648 -40.31153) (xy 63.471205 -40.24421) (xy 63.50215 -40.179951) (xy 63.540096 -40.11956)
			(xy 63.584565 -40.063798) (xy 63.634998 -40.013365) (xy 63.69076 -39.968896) (xy 63.751151 -39.93095)
			(xy 63.81541 -39.900005) (xy 63.88273 -39.876448) (xy 63.952265 -39.860578) (xy 64.023139 -39.852592)
			(xy 64.094461 -39.852592) (xy 64.165335 -39.860578) (xy 64.23487 -39.876448) (xy 64.30219 -39.900005)
			(xy 64.366449 -39.93095) (xy 64.42684 -39.968896) (xy 64.482602 -40.013365) (xy 64.533035 -40.063798)
			(xy 64.577504 -40.11956) (xy 64.61545 -40.179951) (xy 64.646395 -40.24421) (xy 64.669952 -40.31153)
			(xy 64.685822 -40.381065) (xy 64.693808 -40.451939) (xy 64.694308 -40.4876) (xy 64.693808 -40.523261)
			(xy 64.685822 -40.594135) (xy 64.678809 -40.624861) (xy 70.484992 -40.624861) (xy 70.484992 -40.553539)
			(xy 70.492978 -40.482665) (xy 70.508848 -40.41313) (xy 70.532405 -40.34581) (xy 70.56335 -40.281551)
			(xy 70.601296 -40.22116) (xy 70.645765 -40.165398) (xy 70.696198 -40.114965) (xy 70.75196 -40.070496)
			(xy 70.812351 -40.03255) (xy 70.87661 -40.001605) (xy 70.94393 -39.978048) (xy 71.013465 -39.962178)
			(xy 71.084339 -39.954192) (xy 71.155661 -39.954192) (xy 71.226535 -39.962178) (xy 71.29607 -39.978048)
			(xy 71.36339 -40.001605) (xy 71.427649 -40.03255) (xy 71.48804 -40.070496) (xy 71.543802 -40.114965)
			(xy 71.594235 -40.165398) (xy 71.638704 -40.22116) (xy 71.67665 -40.281551) (xy 71.707595 -40.34581)
			(xy 71.731152 -40.41313) (xy 71.747022 -40.482665) (xy 71.755008 -40.553539) (xy 71.755508 -40.5892)
			(xy 71.755008 -40.624861) (xy 71.747022 -40.695735) (xy 71.731152 -40.76527) (xy 71.707595 -40.83259)
			(xy 71.67665 -40.896849) (xy 71.638704 -40.95724) (xy 71.594235 -41.013002) (xy 71.543802 -41.063435)
			(xy 71.48804 -41.107904) (xy 71.427649 -41.14585) (xy 71.36339 -41.176795) (xy 71.29607 -41.200352)
			(xy 71.226535 -41.216222) (xy 71.155661 -41.224208) (xy 71.084339 -41.224208) (xy 71.013465 -41.216222)
			(xy 70.94393 -41.200352) (xy 70.87661 -41.176795) (xy 70.812351 -41.14585) (xy 70.75196 -41.107904)
			(xy 70.696198 -41.063435) (xy 70.645765 -41.013002) (xy 70.601296 -40.95724) (xy 70.56335 -40.896849)
			(xy 70.532405 -40.83259) (xy 70.508848 -40.76527) (xy 70.492978 -40.695735) (xy 70.484992 -40.624861)
			(xy 64.678809 -40.624861) (xy 64.669952 -40.66367) (xy 64.646395 -40.73099) (xy 64.61545 -40.795249)
			(xy 64.577504 -40.85564) (xy 64.533035 -40.911402) (xy 64.482602 -40.961835) (xy 64.42684 -41.006304)
			(xy 64.366449 -41.04425) (xy 64.30219 -41.075195) (xy 64.23487 -41.098752) (xy 64.165335 -41.114622)
			(xy 64.094461 -41.122608) (xy 64.023139 -41.122608) (xy 63.952265 -41.114622) (xy 63.88273 -41.098752)
			(xy 63.81541 -41.075195) (xy 63.751151 -41.04425) (xy 63.69076 -41.006304) (xy 63.634998 -40.961835)
			(xy 63.584565 -40.911402) (xy 63.540096 -40.85564) (xy 63.50215 -40.795249) (xy 63.471205 -40.73099)
			(xy 63.447648 -40.66367) (xy 63.431778 -40.594135) (xy 63.423792 -40.523261) (xy 30.830707 -40.523261)
			(xy 30.781465 -40.540318) (xy 30.747208 -40.54856) (xy 30.725167 -40.554072) (xy 30.683338 -40.571792)
			(xy 30.645323 -40.596661) (xy 30.612331 -40.627889) (xy 30.585412 -40.664481) (xy 30.565422 -40.705274)
			(xy 30.552997 -40.748969) (xy 30.548533 -40.794176) (xy 30.552172 -40.839458) (xy 30.563797 -40.883372)
			(xy 30.572964 -40.90416) (xy 30.587592 -40.936608) (xy 30.610357 -41.004047) (xy 30.625443 -41.073608)
			(xy 30.632661 -41.144419) (xy 30.631921 -41.215593) (xy 30.623231 -41.286239) (xy 30.606701 -41.355471)
			(xy 30.582537 -41.422422) (xy 30.551042 -41.486253) (xy 30.512612 -41.546165) (xy 30.467727 -41.601407)
			(xy 30.416949 -41.651287) (xy 30.360916 -41.695179) (xy 30.300328 -41.732535) (xy 30.235945 -41.762886)
			(xy 30.168574 -41.785851) (xy 30.099058 -41.801144) (xy 30.028268 -41.808573) (xy 29.957092 -41.808043)
			(xy 29.886421 -41.799563) (xy 29.81714 -41.783239) (xy 29.750118 -41.759274) (xy 29.686193 -41.72797)
			(xy 29.626167 -41.689717) (xy 29.570793 -41.644996) (xy 29.520762 -41.594367) (xy 29.476703 -41.538464)
			(xy 29.439168 -41.477988) (xy 29.408626 -41.413696) (xy 29.38546 -41.346393) (xy 29.369961 -41.276923)
			(xy 29.362322 -41.206156) (xy 28.601571 -41.206156) (xy 28.610875 -41.219533) (xy 28.641677 -41.250668)
			(xy 28.677363 -41.27606) (xy 28.69692 -41.285922) (xy 28.72879 -41.301748) (xy 28.789145 -41.339441)
			(xy 28.844912 -41.38364) (xy 28.895392 -41.433791) (xy 28.939954 -41.489268) (xy 28.97804 -41.549376)
			(xy 29.009173 -41.613362) (xy 29.032964 -41.680425) (xy 29.049114 -41.749726) (xy 29.057422 -41.820398)
			(xy 29.057783 -41.891555) (xy 29.050194 -41.962307) (xy 29.034748 -42.031769) (xy 29.011639 -42.09907)
			(xy 28.981157 -42.163369) (xy 28.943683 -42.22386) (xy 28.899687 -42.279786) (xy 28.849718 -42.330448)
			(xy 28.794403 -42.375211) (xy 28.734434 -42.413514) (xy 28.670561 -42.444879) (xy 28.603584 -42.468913)
			(xy 28.534342 -42.485314) (xy 28.463701 -42.493877) (xy 28.392546 -42.494496) (xy 28.321767 -42.487163)
			(xy 28.25225 -42.471969) (xy 28.184865 -42.449104) (xy 28.120456 -42.418855) (xy 28.05983 -42.381601)
			(xy 28.003744 -42.337807) (xy 27.952902 -42.288022) (xy 27.907939 -42.23287) (xy 27.869419 -42.173039)
			(xy 27.837823 -42.109281) (xy 27.813547 -42.042391) (xy 27.796895 -41.973209) (xy 27.788076 -41.9026)
			(xy 27.787199 -41.831447) (xy 27.794276 -41.760642) (xy 27.809218 -41.69107) (xy 27.831839 -41.623603)
			(xy 27.861854 -41.559085) (xy 27.898889 -41.498324) (xy 27.942479 -41.442081) (xy 27.966924 -41.416224)
			(xy 27.981799 -41.400144) (xy 28.006478 -41.363963) (xy 28.024587 -41.324085) (xy 28.03559 -41.281692)
			(xy 28.03916 -41.238041) (xy 28.035192 -41.194424) (xy 28.023804 -41.152134) (xy 28.005333 -41.112422)
			(xy 27.980325 -41.076467) (xy 27.949523 -41.045332) (xy 27.913837 -41.01994) (xy 27.89428 -41.010078)
			(xy 27.86241 -40.994252) (xy 27.802055 -40.956559) (xy 27.746288 -40.91236) (xy 27.695808 -40.862209)
			(xy 27.651246 -40.806732) (xy 27.61316 -40.746624) (xy 27.582027 -40.682638) (xy 27.558236 -40.615575)
			(xy 27.542086 -40.546274) (xy 27.533778 -40.475602) (xy 27.533417 -40.404445) (xy 27.117792 -40.404445)
			(xy 27.068402 -40.453835) (xy 27.01264 -40.498304) (xy 26.952249 -40.53625) (xy 26.88799 -40.567195)
			(xy 26.82067 -40.590752) (xy 26.751135 -40.606622) (xy 26.680261 -40.614608) (xy 26.608939 -40.614608)
			(xy 26.538065 -40.606622) (xy 26.46853 -40.590752) (xy 26.40121 -40.567195) (xy 26.336951 -40.53625)
			(xy 26.27656 -40.498304) (xy 26.220798 -40.453835) (xy 26.170365 -40.403402) (xy 26.125896 -40.34764)
			(xy 26.08795 -40.287249) (xy 26.057005 -40.22299) (xy 26.033448 -40.15567) (xy 26.017578 -40.086135)
			(xy 26.009592 -40.015261) (xy 25.517074 -40.015261) (xy 25.510465 -40.051647) (xy 25.490119 -40.11954)
			(xy 25.462345 -40.184748) (xy 25.427488 -40.24646) (xy 25.385981 -40.303911) (xy 25.338339 -40.356387)
			(xy 25.285155 -40.403236) (xy 25.227088 -40.443876) (xy 25.164859 -40.477803) (xy 25.099242 -40.504596)
			(xy 25.031051 -40.523921) (xy 24.961134 -40.535539) (xy 24.890358 -40.539306) (xy 24.819602 -40.535174)
			(xy 24.749746 -40.523195) (xy 24.681656 -40.503518) (xy 24.616178 -40.476387) (xy 24.554126 -40.442139)
			(xy 24.496269 -40.401199) (xy 24.443327 -40.354076) (xy 24.395957 -40.301355) (xy 24.354747 -40.24369)
			(xy 24.320209 -40.181799) (xy 24.292772 -40.116448) (xy 24.272777 -40.048451) (xy 24.266144 -40.013636)
			(xy 24.26166 -39.99112) (xy 24.245656 -39.948092) (xy 24.222186 -39.908638) (xy 24.192013 -39.87404)
			(xy 24.156117 -39.845423) (xy 24.115666 -39.823717) (xy 24.071974 -39.809628) (xy 24.026463 -39.803614)
			(xy 23.980611 -39.80587) (xy 23.93591 -39.816324) (xy 23.893813 -39.834635) (xy 23.874476 -39.847012)
			(xy 23.8444 -39.866586) (xy 23.780673 -39.899585) (xy 23.713635 -39.925194) (xy 23.644138 -39.94309)
			(xy 23.573069 -39.953042) (xy 23.50133 -39.954926) (xy 23.429836 -39.948717) (xy 23.359496 -39.934493)
			(xy 23.291206 -39.912437) (xy 23.225835 -39.882829) (xy 23.164216 -39.846045) (xy 23.107133 -39.802554)
			(xy 23.055311 -39.75291) (xy 23.009412 -39.697744) (xy 22.97002 -39.637759) (xy 22.937635 -39.573719)
			(xy 22.91267 -39.506438) (xy 22.895443 -39.436773) (xy 22.886173 -39.36561) (xy 22.884978 -39.293857)
			(xy 22.891873 -39.222426) (xy 22.906771 -39.152226) (xy 22.917658 -39.118032) (xy 22.924384 -39.096249)
			(xy 22.93087 -39.05113) (xy 22.929208 -39.005576) (xy 22.919451 -38.96105) (xy 22.90191 -38.918976)
			(xy 22.877149 -38.880704) (xy 22.845961 -38.84746) (xy 22.809346 -38.82031) (xy 22.768476 -38.800123)
			(xy 22.724661 -38.787547) (xy 22.679307 -38.782984) (xy 22.656546 -38.784276) (xy 22.621283 -38.786543)
			(xy 22.550654 -38.784314) (xy 22.480708 -38.774262) (xy 22.41231 -38.756512) (xy 22.346303 -38.731283)
			(xy 22.283503 -38.698886) (xy 22.224685 -38.659722) (xy 22.170575 -38.614274) (xy 22.121842 -38.563103)
			(xy 22.079087 -38.506841) (xy 22.042838 -38.446183) (xy 22.013542 -38.381877) (xy 21.991562 -38.314719)
			(xy 21.977169 -38.245536) (xy 21.970541 -38.175184) (xy 11.061576 -38.175184) (xy 11.061185 -38.175622)
			(xy 10.996889 -38.23567) (xy 10.927398 -38.289623) (xy 10.85329 -38.337034) (xy 10.775177 -38.377508)
			(xy 10.693707 -38.410712) (xy 10.609555 -38.43637) (xy 10.523419 -38.45427) (xy 10.436012 -38.464262)
			(xy 10.348058 -38.466265) (xy 10.260287 -38.460261) (xy 10.173425 -38.446301) (xy 10.088193 -38.424499)
			(xy 10.005296 -38.395038) (xy 9.925422 -38.35816) (xy 9.849232 -38.314172) (xy 9.777358 -38.263438)
			(xy 9.710396 -38.206378) (xy 9.648899 -38.143465) (xy 9.593378 -38.075221) (xy 9.544293 -38.002211)
			(xy 9.502051 -37.925039) (xy 9.467001 -37.844346) (xy 9.439434 -37.760801) (xy 9.419579 -37.675094)
			(xy 9.407599 -37.587937) (xy 9.403595 -37.500052) (xy 6.962106 -37.500052) (xy 6.843571 -37.61166)
			(xy 6.715859 -37.720861) (xy 6.583066 -37.823822) (xy 6.445496 -37.920309) (xy 6.303465 -38.0101)
			(xy 6.157299 -38.092988) (xy 6.007332 -38.168785) (xy 5.853909 -38.237316) (xy 5.697381 -38.298423)
			(xy 5.538107 -38.351968) (xy 5.376453 -38.397826) (xy 5.212788 -38.435894) (xy 5.047489 -38.466083)
			(xy 4.880935 -38.488324) (xy 4.713506 -38.502567) (xy 4.545588 -38.508779) (xy 4.377565 -38.506946)
			(xy 4.209822 -38.497071) (xy 4.12623 -38.48862) (xy 4.103953 -38.4867) (xy 4.059351 -38.489777) (xy 4.015976 -38.500614)
			(xy 3.975167 -38.518876) (xy 3.938185 -38.543998) (xy 3.90617 -38.575205) (xy 3.880112 -38.611535)
			(xy 3.860815 -38.651864) (xy 3.848874 -38.694948) (xy 3.844659 -38.739458) (xy 3.848299 -38.784017)
			(xy 3.859682 -38.827252) (xy 3.878457 -38.867827) (xy 3.904044 -38.90449) (xy 3.919474 -38.920674)
			(xy 4.277461 -39.278661) (xy 20.650192 -39.278661) (xy 20.650192 -39.207339) (xy 20.658178 -39.136465)
			(xy 20.674048 -39.06693) (xy 20.697605 -38.99961) (xy 20.72855 -38.935351) (xy 20.766496 -38.87496)
			(xy 20.810965 -38.819198) (xy 20.861398 -38.768765) (xy 20.91716 -38.724296) (xy 20.977551 -38.68635)
			(xy 21.04181 -38.655405) (xy 21.10913 -38.631848) (xy 21.178665 -38.615978) (xy 21.249539 -38.607992)
			(xy 21.320861 -38.607992) (xy 21.391735 -38.615978) (xy 21.46127 -38.631848) (xy 21.52859 -38.655405)
			(xy 21.592849 -38.68635) (xy 21.65324 -38.724296) (xy 21.709002 -38.768765) (xy 21.759435 -38.819198)
			(xy 21.803904 -38.87496) (xy 21.84185 -38.935351) (xy 21.872795 -38.99961) (xy 21.896352 -39.06693)
			(xy 21.912222 -39.136465) (xy 21.920208 -39.207339) (xy 21.920708 -39.243) (xy 21.920208 -39.278661)
			(xy 21.912222 -39.349535) (xy 21.896352 -39.41907) (xy 21.872795 -39.48639) (xy 21.84185 -39.550649)
			(xy 21.803904 -39.61104) (xy 21.759435 -39.666802) (xy 21.709002 -39.717235) (xy 21.65324 -39.761704)
			(xy 21.592849 -39.79965) (xy 21.52859 -39.830595) (xy 21.46127 -39.854152) (xy 21.391735 -39.870022)
			(xy 21.320861 -39.878008) (xy 21.249539 -39.878008) (xy 21.178665 -39.870022) (xy 21.10913 -39.854152)
			(xy 21.04181 -39.830595) (xy 20.977551 -39.79965) (xy 20.91716 -39.761704) (xy 20.861398 -39.717235)
			(xy 20.810965 -39.666802) (xy 20.766496 -39.61104) (xy 20.72855 -39.550649) (xy 20.697605 -39.48639)
			(xy 20.674048 -39.41907) (xy 20.658178 -39.349535) (xy 20.650192 -39.278661) (xy 4.277461 -39.278661)
			(xy 6.258661 -41.259861) (xy 12.547592 -41.259861) (xy 12.547592 -41.188539) (xy 12.555578 -41.117665)
			(xy 12.571448 -41.04813) (xy 12.595005 -40.98081) (xy 12.62595 -40.916551) (xy 12.663896 -40.85616)
			(xy 12.708365 -40.800398) (xy 12.758798 -40.749965) (xy 12.81456 -40.705496) (xy 12.874951 -40.66755)
			(xy 12.93921 -40.636605) (xy 13.00653 -40.613048) (xy 13.076065 -40.597178) (xy 13.146939 -40.589192)
			(xy 13.218261 -40.589192) (xy 13.289135 -40.597178) (xy 13.35867 -40.613048) (xy 13.42599 -40.636605)
			(xy 13.490249 -40.66755) (xy 13.55064 -40.705496) (xy 13.606402 -40.749965) (xy 13.656835 -40.800398)
			(xy 13.701304 -40.85616) (xy 13.73925 -40.916551) (xy 13.770195 -40.98081) (xy 13.793752 -41.04813)
			(xy 13.809622 -41.117665) (xy 13.817608 -41.188539) (xy 13.818108 -41.2242) (xy 13.817608 -41.259861)
			(xy 13.809622 -41.330735) (xy 13.793752 -41.40027) (xy 13.770195 -41.46759) (xy 13.73925 -41.531849)
			(xy 13.701304 -41.59224) (xy 13.656835 -41.648002) (xy 13.606402 -41.698435) (xy 13.55064 -41.742904)
			(xy 13.490249 -41.78085) (xy 13.42599 -41.811795) (xy 13.35867 -41.835352) (xy 13.289135 -41.851222)
			(xy 13.218261 -41.859208) (xy 13.146939 -41.859208) (xy 13.076065 -41.851222) (xy 13.00653 -41.835352)
			(xy 12.93921 -41.811795) (xy 12.874951 -41.78085) (xy 12.81456 -41.742904) (xy 12.758798 -41.698435)
			(xy 12.708365 -41.648002) (xy 12.663896 -41.59224) (xy 12.62595 -41.531849) (xy 12.595005 -41.46759)
			(xy 12.571448 -41.40027) (xy 12.555578 -41.330735) (xy 12.547592 -41.259861) (xy 6.258661 -41.259861)
			(xy 6.5278 -41.529) (xy 12.0142 -41.529) (xy 12.991592 -42.506392) (xy 13.004155 -42.518189) (xy 13.034113 -42.535191)
			(xy 13.06753 -42.543555) (xy 13.101966 -42.542669) (xy 13.118592 -42.538142) (xy 13.156184 -42.526712)
			(xy 13.170916 -42.517314) (xy 13.199226 -42.499732) (xy 13.258837 -42.469933) (xy 13.321242 -42.446541)
			(xy 13.385753 -42.429812) (xy 13.451661 -42.419931) (xy 13.518242 -42.417007) (xy 13.584762 -42.421071)
			(xy 13.617702 -42.426128) (xy 13.640013 -42.429366) (xy 13.68509 -42.428841) (xy 13.729367 -42.420372)
			(xy 13.771455 -42.404225) (xy 13.810034 -42.380906) (xy 13.843895 -42.351146) (xy 13.871974 -42.315879)
			(xy 13.893391 -42.276212) (xy 13.907474 -42.233389) (xy 13.913781 -42.188753) (xy 13.912114 -42.143704)
			(xy 13.90777 -42.121582) (xy 13.900595 -42.086324) (xy 13.893306 -42.014738) (xy 13.894149 -41.942788)
			(xy 13.903112 -41.871393) (xy 13.92008 -41.801466) (xy 13.944837 -41.733904) (xy 13.977065 -41.669569)
			(xy 14.016352 -41.609286) (xy 14.062197 -41.553825) (xy 14.114011 -41.503897) (xy 14.171132 -41.460139)
			(xy 14.23283 -41.423112) (xy 14.298314 -41.393289) (xy 14.366748 -41.371053) (xy 14.437255 -41.356687)
			(xy 14.508933 -41.350376) (xy 14.580865 -41.3522) (xy 14.652131 -41.362136) (xy 14.721819 -41.380056)
			(xy 14.789038 -41.405732) (xy 14.852927 -41.438835) (xy 14.912669 -41.478941) (xy 14.967499 -41.525538)
			(xy 15.016716 -41.578028) (xy 15.059691 -41.635741) (xy 15.095873 -41.697938) (xy 15.124799 -41.763823)
			(xy 15.1461 -41.832553) (xy 15.159503 -41.90325) (xy 15.164742 -41.973741) (xy 16.00096 -41.973741)
			(xy 16.003132 -41.918141) (xy 16.013356 -41.863446) (xy 16.031415 -41.810816) (xy 16.056926 -41.761367)
			(xy 16.089348 -41.716146) (xy 16.127993 -41.676114) (xy 16.172043 -41.642118) (xy 16.196056 -41.62806)
			(xy 16.21499 -41.616876) (xy 16.249058 -41.58908) (xy 16.277832 -41.555832) (xy 16.300451 -41.518127)
			(xy 16.316239 -41.47709) (xy 16.324726 -41.433947) (xy 16.325657 -41.389987) (xy 16.319005 -41.346524)
			(xy 16.304968 -41.304855) (xy 16.283966 -41.266226) (xy 16.256626 -41.23179) (xy 16.240506 -41.216834)
			(xy 16.214089 -41.192783) (xy 16.166322 -41.139654) (xy 16.124815 -41.081503) (xy 16.09009 -41.019064)
			(xy 16.062586 -40.953125) (xy 16.04265 -40.884517) (xy 16.030533 -40.814107) (xy 16.026389 -40.742782)
			(xy 16.030268 -40.671443) (xy 16.042123 -40.600988) (xy 16.061804 -40.532307) (xy 16.089063 -40.466266)
			(xy 16.123555 -40.403699) (xy 16.164846 -40.345394) (xy 16.212414 -40.292087) (xy 16.265661 -40.24445)
			(xy 16.323913 -40.203085) (xy 16.386437 -40.168513) (xy 16.452443 -40.141171) (xy 16.521099 -40.121403)
			(xy 16.591538 -40.109458) (xy 16.662873 -40.105488) (xy 16.734203 -40.109542) (xy 16.804629 -40.121569)
			(xy 16.873261 -40.141418) (xy 16.901347 -40.153091) (xy 19.379521 -40.153091) (xy 19.38111 -40.082378)
			(xy 19.39054 -40.012278) (xy 19.407696 -39.943659) (xy 19.432366 -39.877369) (xy 19.464243 -39.814228)
			(xy 19.502934 -39.755017) (xy 19.54796 -39.700468) (xy 19.598764 -39.651256) (xy 19.654719 -39.60799)
			(xy 19.715132 -39.571204) (xy 19.779256 -39.541353) (xy 19.846298 -39.518807) (xy 19.915429 -39.503845)
			(xy 19.985793 -39.496651) (xy 20.056521 -39.497315) (xy 20.126739 -39.505827) (xy 20.195576 -39.522084)
			(xy 20.262184 -39.545884) (xy 20.325736 -39.576932) (xy 20.385448 -39.614845) (xy 20.440581 -39.659154)
			(xy 20.490454 -39.70931) (xy 20.534449 -39.764694) (xy 20.572022 -39.82462) (xy 20.602709 -39.888348)
			(xy 20.62613 -39.955089) (xy 20.641996 -40.024018) (xy 20.65011 -40.094283) (xy 20.650372 -40.165014)
			(xy 20.642778 -40.235336) (xy 20.627424 -40.304381) (xy 20.616418 -40.337994) (xy 20.60962 -40.35923)
			(xy 20.603837 -40.396261) (xy 21.716992 -40.396261) (xy 21.716992 -40.324939) (xy 21.724978 -40.254065)
			(xy 21.740848 -40.18453) (xy 21.764405 -40.11721) (xy 21.79535 -40.052951) (xy 21.833296 -39.99256)
			(xy 21.877765 -39.936798) (xy 21.928198 -39.886365) (xy 21.98396 -39.841896) (xy 22.044351 -39.80395)
			(xy 22.10861 -39.773005) (xy 22.17593 -39.749448) (xy 22.245465 -39.733578) (xy 22.316339 -39.725592)
			(xy 22.387661 -39.725592) (xy 22.458535 -39.733578) (xy 22.52807 -39.749448) (xy 22.59539 -39.773005)
			(xy 22.659649 -39.80395) (xy 22.72004 -39.841896) (xy 22.775802 -39.886365) (xy 22.826235 -39.936798)
			(xy 22.870704 -39.99256) (xy 22.90865 -40.052951) (xy 22.939595 -40.11721) (xy 22.963152 -40.18453)
			(xy 22.979022 -40.254065) (xy 22.987008 -40.324939) (xy 22.987508 -40.3606) (xy 22.987008 -40.396261)
			(xy 22.979022 -40.467135) (xy 22.963152 -40.53667) (xy 22.939595 -40.60399) (xy 22.90865 -40.668249)
			(xy 22.870704 -40.72864) (xy 22.826235 -40.784402) (xy 22.775802 -40.834835) (xy 22.72004 -40.879304)
			(xy 22.659649 -40.91725) (xy 22.59539 -40.948195) (xy 22.52807 -40.971752) (xy 22.458535 -40.987622)
			(xy 22.387661 -40.995608) (xy 22.316339 -40.995608) (xy 22.245465 -40.987622) (xy 22.17593 -40.971752)
			(xy 22.10861 -40.948195) (xy 22.044351 -40.91725) (xy 21.98396 -40.879304) (xy 21.928198 -40.834835)
			(xy 21.877765 -40.784402) (xy 21.833296 -40.72864) (xy 21.79535 -40.668249) (xy 21.764405 -40.60399)
			(xy 21.740848 -40.53667) (xy 21.724978 -40.467135) (xy 21.716992 -40.396261) (xy 20.603837 -40.396261)
			(xy 20.60274 -40.403282) (xy 20.603649 -40.447858) (xy 20.612319 -40.491593) (xy 20.628484 -40.533145)
			(xy 20.651649 -40.57124) (xy 20.681104 -40.604711) (xy 20.715945 -40.632531) (xy 20.755105 -40.653847)
			(xy 20.797383 -40.668007) (xy 20.819364 -40.67175) (xy 20.854285 -40.67736) (xy 20.922674 -40.695413)
			(xy 20.988635 -40.720947) (xy 21.051353 -40.753648) (xy 21.110053 -40.79311) (xy 21.164008 -40.838846)
			(xy 21.212551 -40.89029) (xy 21.255082 -40.946806) (xy 21.291074 -41.007695) (xy 21.320083 -41.072204)
			(xy 21.34175 -41.139535) (xy 21.355807 -41.208856) (xy 21.362079 -41.279309) (xy 21.36049 -41.350022)
			(xy 21.352117 -41.412261) (xy 23.215592 -41.412261) (xy 23.215592 -41.340939) (xy 23.223578 -41.270065)
			(xy 23.239448 -41.20053) (xy 23.263005 -41.13321) (xy 23.29395 -41.068951) (xy 23.331896 -41.00856)
			(xy 23.376365 -40.952798) (xy 23.426798 -40.902365) (xy 23.48256 -40.857896) (xy 23.542951 -40.81995)
			(xy 23.60721 -40.789005) (xy 23.67453 -40.765448) (xy 23.744065 -40.749578) (xy 23.814939 -40.741592)
			(xy 23.886261 -40.741592) (xy 23.957135 -40.749578) (xy 24.02667 -40.765448) (xy 24.09399 -40.789005)
			(xy 24.158249 -40.81995) (xy 24.21864 -40.857896) (xy 24.274402 -40.902365) (xy 24.324835 -40.952798)
			(xy 24.369304 -41.00856) (xy 24.40725 -41.068951) (xy 24.438195 -41.13321) (xy 24.461752 -41.20053)
			(xy 24.477622 -41.270065) (xy 24.485608 -41.340939) (xy 24.486108 -41.3766) (xy 24.485608 -41.412261)
			(xy 24.477622 -41.483135) (xy 24.464812 -41.539261) (xy 24.942792 -41.539261) (xy 24.942792 -41.467939)
			(xy 24.950778 -41.397065) (xy 24.966648 -41.32753) (xy 24.990205 -41.26021) (xy 25.02115 -41.195951)
			(xy 25.059096 -41.13556) (xy 25.103565 -41.079798) (xy 25.153998 -41.029365) (xy 25.20976 -40.984896)
			(xy 25.270151 -40.94695) (xy 25.33441 -40.916005) (xy 25.40173 -40.892448) (xy 25.471265 -40.876578)
			(xy 25.542139 -40.868592) (xy 25.613461 -40.868592) (xy 25.684335 -40.876578) (xy 25.75387 -40.892448)
			(xy 25.82119 -40.916005) (xy 25.885449 -40.94695) (xy 25.94584 -40.984896) (xy 26.001602 -41.029365)
			(xy 26.052035 -41.079798) (xy 26.096504 -41.13556) (xy 26.13445 -41.195951) (xy 26.165395 -41.26021)
			(xy 26.188952 -41.32753) (xy 26.204822 -41.397065) (xy 26.212808 -41.467939) (xy 26.213308 -41.5036)
			(xy 26.212808 -41.539261) (xy 26.204822 -41.610135) (xy 26.188952 -41.67967) (xy 26.165395 -41.74699)
			(xy 26.13445 -41.811249) (xy 26.096504 -41.87164) (xy 26.052035 -41.927402) (xy 26.001602 -41.977835)
			(xy 25.94584 -42.022304) (xy 25.885449 -42.06025) (xy 25.82119 -42.091195) (xy 25.75387 -42.114752)
			(xy 25.684335 -42.130622) (xy 25.613461 -42.138608) (xy 25.542139 -42.138608) (xy 25.471265 -42.130622)
			(xy 25.40173 -42.114752) (xy 25.33441 -42.091195) (xy 25.270151 -42.06025) (xy 25.20976 -42.022304)
			(xy 25.153998 -41.977835) (xy 25.103565 -41.927402) (xy 25.059096 -41.87164) (xy 25.02115 -41.811249)
			(xy 24.990205 -41.74699) (xy 24.966648 -41.67967) (xy 24.950778 -41.610135) (xy 24.942792 -41.539261)
			(xy 24.464812 -41.539261) (xy 24.461752 -41.55267) (xy 24.438195 -41.61999) (xy 24.40725 -41.684249)
			(xy 24.369304 -41.74464) (xy 24.324835 -41.800402) (xy 24.274402 -41.850835) (xy 24.21864 -41.895304)
			(xy 24.158249 -41.93325) (xy 24.09399 -41.964195) (xy 24.02667 -41.987752) (xy 23.957135 -42.003622)
			(xy 23.886261 -42.011608) (xy 23.814939 -42.011608) (xy 23.744065 -42.003622) (xy 23.67453 -41.987752)
			(xy 23.60721 -41.964195) (xy 23.542951 -41.93325) (xy 23.48256 -41.895304) (xy 23.426798 -41.850835)
			(xy 23.376365 -41.800402) (xy 23.331896 -41.74464) (xy 23.29395 -41.684249) (xy 23.263005 -41.61999)
			(xy 23.239448 -41.55267) (xy 23.223578 -41.483135) (xy 23.215592 -41.412261) (xy 21.352117 -41.412261)
			(xy 21.35106 -41.420122) (xy 21.333904 -41.488741) (xy 21.309234 -41.555031) (xy 21.277357 -41.618172)
			(xy 21.238666 -41.677383) (xy 21.19364 -41.731932) (xy 21.142836 -41.781144) (xy 21.086881 -41.82441)
			(xy 21.026468 -41.861196) (xy 20.962344 -41.891047) (xy 20.895302 -41.913593) (xy 20.826171 -41.928555)
			(xy 20.755807 -41.935749) (xy 20.685079 -41.935085) (xy 20.614861 -41.926573) (xy 20.546024 -41.910316)
			(xy 20.479416 -41.886516) (xy 20.415864 -41.855468) (xy 20.356152 -41.817555) (xy 20.301019 -41.773246)
			(xy 20.251146 -41.72309) (xy 20.207151 -41.667706) (xy 20.169578 -41.60778) (xy 20.138891 -41.544052)
			(xy 20.11547 -41.477311) (xy 20.099604 -41.408382) (xy 20.09149 -41.338117) (xy 20.091228 -41.267386)
			(xy 20.098822 -41.197064) (xy 20.114176 -41.128019) (xy 20.125182 -41.094406) (xy 20.13198 -41.07317)
			(xy 20.13886 -41.029118) (xy 20.137951 -40.984542) (xy 20.129281 -40.940807) (xy 20.113116 -40.899255)
			(xy 20.089951 -40.86116) (xy 20.060496 -40.827689) (xy 20.025655 -40.799869) (xy 19.986495 -40.778553)
			(xy 19.944217 -40.764393) (xy 19.922236 -40.76065) (xy 19.887315 -40.75504) (xy 19.818926 -40.736987)
			(xy 19.752965 -40.711453) (xy 19.690247 -40.678752) (xy 19.631547 -40.63929) (xy 19.577592 -40.593554)
			(xy 19.529049 -40.54211) (xy 19.486518 -40.485594) (xy 19.450526 -40.424705) (xy 19.421517 -40.360196)
			(xy 19.39985 -40.292865) (xy 19.385793 -40.223544) (xy 19.379521 -40.153091) (xy 16.901347 -40.153091)
			(xy 16.939235 -40.168838) (xy 17.001718 -40.203483) (xy 17.059922 -40.244916) (xy 17.113113 -40.292615)
			(xy 17.160619 -40.345978) (xy 17.201841 -40.404331) (xy 17.23626 -40.466939) (xy 17.263441 -40.533012)
			(xy 17.283041 -40.601716) (xy 17.294814 -40.672184) (xy 17.29861 -40.743529) (xy 17.294381 -40.814849)
			(xy 17.282182 -40.885245) (xy 17.262165 -40.953828) (xy 17.234584 -41.019735) (xy 17.199786 -41.082133)
			(xy 17.15821 -41.140235) (xy 17.110382 -41.193309) (xy 17.092601 -41.209061) (xy 17.957792 -41.209061)
			(xy 17.957792 -41.137739) (xy 17.965778 -41.066865) (xy 17.981648 -40.99733) (xy 18.005205 -40.93001)
			(xy 18.03615 -40.865751) (xy 18.074096 -40.80536) (xy 18.118565 -40.749598) (xy 18.168998 -40.699165)
			(xy 18.22476 -40.654696) (xy 18.285151 -40.61675) (xy 18.34941 -40.585805) (xy 18.41673 -40.562248)
			(xy 18.486265 -40.546378) (xy 18.557139 -40.538392) (xy 18.628461 -40.538392) (xy 18.699335 -40.546378)
			(xy 18.76887 -40.562248) (xy 18.83619 -40.585805) (xy 18.900449 -40.61675) (xy 18.96084 -40.654696)
			(xy 19.016602 -40.699165) (xy 19.067035 -40.749598) (xy 19.111504 -40.80536) (xy 19.14945 -40.865751)
			(xy 19.180395 -40.93001) (xy 19.203952 -40.99733) (xy 19.219822 -41.066865) (xy 19.227808 -41.137739)
			(xy 19.228308 -41.1734) (xy 19.227808 -41.209061) (xy 19.219822 -41.279935) (xy 19.203952 -41.34947)
			(xy 19.180395 -41.41679) (xy 19.14945 -41.481049) (xy 19.111504 -41.54144) (xy 19.067035 -41.597202)
			(xy 19.016602 -41.647635) (xy 18.96084 -41.692104) (xy 18.900449 -41.73005) (xy 18.83619 -41.760995)
			(xy 18.76887 -41.784552) (xy 18.699335 -41.800422) (xy 18.628461 -41.808408) (xy 18.557139 -41.808408)
			(xy 18.486265 -41.800422) (xy 18.41673 -41.784552) (xy 18.34941 -41.760995) (xy 18.285151 -41.73005)
			(xy 18.22476 -41.692104) (xy 18.168998 -41.647635) (xy 18.118565 -41.597202) (xy 18.074096 -41.54144)
			(xy 18.03615 -41.481049) (xy 18.005205 -41.41679) (xy 17.981648 -41.34947) (xy 17.965778 -41.279935)
			(xy 17.957792 -41.209061) (xy 17.092601 -41.209061) (xy 17.056903 -41.240685) (xy 16.998449 -41.281764)
			(xy 16.935757 -41.31603) (xy 16.869618 -41.343049) (xy 16.835374 -41.353232) (xy 16.814339 -41.359639)
			(xy 16.774716 -41.378697) (xy 16.738966 -41.404293) (xy 16.708156 -41.435661) (xy 16.683206 -41.471864)
			(xy 16.664862 -41.511823) (xy 16.653671 -41.554344) (xy 16.649968 -41.598156) (xy 16.653862 -41.641951)
			(xy 16.665239 -41.684422) (xy 16.683757 -41.7243) (xy 16.695928 -41.742614) (xy 16.711423 -41.765727)
			(xy 16.736272 -41.815512) (xy 16.753628 -41.868378) (xy 16.763123 -41.923204) (xy 16.764554 -41.978828)
			(xy 16.757892 -42.03407) (xy 16.743278 -42.087759) (xy 16.721022 -42.138756) (xy 16.691595 -42.185981)
			(xy 16.655622 -42.228431) (xy 16.613866 -42.265206) (xy 16.567211 -42.295528) (xy 16.516647 -42.318753)
			(xy 16.463247 -42.334388) (xy 16.408142 -42.342102) (xy 16.352501 -42.341731) (xy 16.297503 -42.333284)
			(xy 16.244316 -42.316938) (xy 16.194066 -42.293042) (xy 16.147819 -42.262102) (xy 16.106557 -42.224773)
			(xy 16.071152 -42.181848) (xy 16.042357 -42.134235) (xy 16.020783 -42.082946) (xy 16.006885 -42.029067)
			(xy 16.00096 -41.973741) (xy 15.164742 -41.973741) (xy 15.164836 -41.975007) (xy 15.162031 -42.046908)
			(xy 15.151124 -42.118032) (xy 15.132254 -42.187469) (xy 15.105664 -42.254331) (xy 15.071693 -42.317763)
			(xy 15.030776 -42.376952) (xy 14.983436 -42.431142) (xy 14.930279 -42.479638) (xy 14.871985 -42.521822)
			(xy 14.8093 -42.557152) (xy 14.743027 -42.585177) (xy 14.674012 -42.605538) (xy 14.60314 -42.617975)
			(xy 14.531316 -42.622329) (xy 14.45946 -42.618544) (xy 14.423898 -42.613072) (xy 14.401587 -42.609834)
			(xy 14.35651 -42.610359) (xy 14.312233 -42.618828) (xy 14.270145 -42.634975) (xy 14.231566 -42.658294)
			(xy 14.197705 -42.688054) (xy 14.169626 -42.723321) (xy 14.148209 -42.762988) (xy 14.134126 -42.805811)
			(xy 14.127819 -42.850447) (xy 14.129486 -42.895496) (xy 14.13383 -42.917618) (xy 14.141149 -42.953623)
			(xy 14.148424 -43.026737) (xy 14.147212 -43.100202) (xy 14.137529 -43.173036) (xy 14.119504 -43.244266)
			(xy 14.09338 -43.31294) (xy 14.059504 -43.378139) (xy 14.039342 -43.408854) (xy 14.030033 -43.42372)
			(xy 14.019133 -43.457046) (xy 14.017685 -43.492079) (xy 14.025797 -43.52619) (xy 14.04286 -43.556821)
			(xy 14.054836 -43.569636) (xy 14.351 -43.8658) (xy 15.035784 -43.8658) (xy 15.058138 -43.865331)
			(xy 15.102156 -43.857511) (xy 15.144127 -43.842109) (xy 15.182755 -43.819601) (xy 15.216849 -43.790681)
			(xy 15.245356 -43.756241) (xy 15.267398 -43.717345) (xy 15.282293 -43.675191) (xy 15.289582 -43.631082)
			(xy 15.289041 -43.586378) (xy 15.280685 -43.542458) (xy 15.264774 -43.500678) (xy 15.253716 -43.481244)
			(xy 15.23598 -43.450713) (xy 15.206622 -43.386494) (xy 15.184565 -43.319416) (xy 15.170079 -43.250306)
			(xy 15.163345 -43.180017) (xy 15.164444 -43.109414) (xy 15.173364 -43.039368) (xy 15.189993 -42.970743)
			(xy 15.214128 -42.904384) (xy 15.245471 -42.84111) (xy 15.283635 -42.781701) (xy 15.32815 -42.726888)
			(xy 15.378467 -42.677348) (xy 15.433965 -42.633692) (xy 15.493962 -42.596458) (xy 15.557716 -42.566104)
			(xy 15.624442 -42.543005) (xy 15.693318 -42.527445) (xy 15.763494 -42.519618) (xy 15.834106 -42.519618)
			(xy 15.904282 -42.527445) (xy 15.973158 -42.543005) (xy 16.039884 -42.566104) (xy 16.103638 -42.596458)
			(xy 16.163635 -42.633692) (xy 16.219133 -42.677348) (xy 16.26945 -42.726888) (xy 16.313965 -42.781701)
			(xy 16.352129 -42.84111) (xy 16.383472 -42.904384) (xy 16.407607 -42.970743) (xy 16.424236 -43.039368)
			(xy 16.433156 -43.109414) (xy 16.434255 -43.180017) (xy 16.427521 -43.250306) (xy 16.413035 -43.319416)
			(xy 16.390978 -43.386494) (xy 16.36162 -43.450713) (xy 16.343884 -43.481244) (xy 16.332798 -43.500664)
			(xy 16.316884 -43.542449) (xy 16.308528 -43.586375) (xy 16.307986 -43.631084) (xy 16.315276 -43.675199)
			(xy 16.330173 -43.717358) (xy 16.352217 -43.756259) (xy 16.380728 -43.790703) (xy 16.414826 -43.819627)
			(xy 16.453459 -43.842138) (xy 16.495436 -43.857542) (xy 16.539459 -43.865363) (xy 16.561816 -43.8658)
			(xy 17.103852 -43.8658) (xy 17.125849 -43.865329) (xy 17.169185 -43.857746) (xy 17.210568 -43.842815)
			(xy 17.248763 -43.820983) (xy 17.282629 -43.792902) (xy 17.311155 -43.759409) (xy 17.333488 -43.721505)
			(xy 17.348963 -43.680322) (xy 17.357116 -43.63709) (xy 17.357705 -43.5931) (xy 17.350712 -43.549665)
			(xy 17.336345 -43.508082) (xy 17.326102 -43.48861) (xy 17.309188 -43.45717) (xy 17.281729 -43.391266)
			(xy 17.26183 -43.322699) (xy 17.249741 -43.252335) (xy 17.245615 -43.181059) (xy 17.249504 -43.109769)
			(xy 17.261358 -43.039365) (xy 17.281029 -42.970732) (xy 17.308269 -42.904738) (xy 17.342734 -42.842212)
			(xy 17.383989 -42.783942) (xy 17.431516 -42.730665) (xy 17.484715 -42.683049) (xy 17.542915 -42.641697)
			(xy 17.605384 -42.607128) (xy 17.671333 -42.579778) (xy 17.739932 -42.559993) (xy 17.810317 -42.548022)
			(xy 17.8816 -42.544014) (xy 17.952883 -42.548022) (xy 18.023268 -42.559993) (xy 18.091867 -42.579778)
			(xy 18.157816 -42.607128) (xy 18.220285 -42.641697) (xy 18.278485 -42.683049) (xy 18.331684 -42.730665)
			(xy 18.379211 -42.783942) (xy 18.420466 -42.842212) (xy 18.454931 -42.904738) (xy 18.482171 -42.970732)
			(xy 18.501842 -43.039365) (xy 18.513696 -43.109769) (xy 18.517585 -43.181059) (xy 18.513459 -43.252335)
			(xy 18.50137 -43.322699) (xy 18.481471 -43.391266) (xy 18.454012 -43.45717) (xy 18.437098 -43.48861)
			(xy 18.426835 -43.508078) (xy 18.41244 -43.549662) (xy 18.405424 -43.593104) (xy 18.405998 -43.637106)
			(xy 18.414144 -43.68035) (xy 18.429618 -43.721545) (xy 18.451959 -43.759457) (xy 18.480497 -43.792954)
			(xy 18.514379 -43.821033) (xy 18.552592 -43.842855) (xy 18.593994 -43.857767) (xy 18.637345 -43.865323)
			(xy 18.659348 -43.8658) (xy 19.099784 -43.8658) (xy 19.122138 -43.865331) (xy 19.166156 -43.857511)
			(xy 19.208127 -43.842109) (xy 19.246755 -43.819601) (xy 19.280849 -43.790681) (xy 19.309356 -43.756241)
			(xy 19.331398 -43.717345) (xy 19.346293 -43.675191) (xy 19.353582 -43.631082) (xy 19.353041 -43.586378)
			(xy 19.344685 -43.542458) (xy 19.328774 -43.500678) (xy 19.317716 -43.481244) (xy 19.299713 -43.450245)
			(xy 19.270019 -43.384998) (xy 19.247856 -43.316822) (xy 19.233506 -43.246586) (xy 19.227151 -43.175181)
			(xy 19.228873 -43.103514) (xy 19.23865 -43.032497) (xy 19.256356 -42.963031) (xy 19.281768 -42.895999)
			(xy 19.314562 -42.832252) (xy 19.354322 -42.772601) (xy 19.400542 -42.717804) (xy 19.452636 -42.668557)
			(xy 19.509941 -42.625484) (xy 19.571729 -42.589135) (xy 19.637216 -42.55997) (xy 19.705568 -42.538361)
			(xy 19.775919 -42.524581) (xy 19.847373 -42.518805) (xy 19.919023 -42.521108) (xy 19.989959 -42.53146)
			(xy 20.059279 -42.549729) (xy 20.126103 -42.575684) (xy 20.189582 -42.608993) (xy 20.248908 -42.649236)
			(xy 20.303329 -42.695899) (xy 20.328128 -42.721784) (xy 20.343352 -42.737425) (xy 20.378148 -42.763768)
			(xy 20.416932 -42.783783) (xy 20.458564 -42.796882) (xy 20.501821 -42.80268) (xy 20.545432 -42.801007)
			(xy 20.588118 -42.791912) (xy 20.628624 -42.775662) (xy 20.66576 -42.752735) (xy 20.698436 -42.723803)
			(xy 20.71243 -42.707052) (xy 20.735431 -42.679084) (xy 20.786771 -42.628013) (xy 20.843582 -42.583108)
			(xy 20.905129 -42.54495) (xy 20.970614 -42.514035) (xy 21.039188 -42.490763) (xy 21.109963 -42.475435)
			(xy 21.182021 -42.468251) (xy 21.254429 -42.469303) (xy 21.326249 -42.478577) (xy 21.396548 -42.495954)
			(xy 21.464418 -42.521209) (xy 21.528977 -42.554013) (xy 21.589389 -42.593942) (xy 21.644872 -42.640479)
			(xy 21.694706 -42.69302) (xy 21.738246 -42.750885) (xy 21.774927 -42.813323) (xy 21.804274 -42.879525)
			(xy 21.825907 -42.948634) (xy 21.839545 -43.019754) (xy 21.845012 -43.091963) (xy 21.842236 -43.164325)
			(xy 21.831254 -43.235903) (xy 21.812207 -43.305769) (xy 21.785344 -43.373018) (xy 21.751012 -43.436778)
			(xy 21.730716 -43.466766) (xy 21.717953 -43.485995) (xy 21.698873 -43.528014) (xy 21.687694 -43.572787)
			(xy 21.684784 -43.618843) (xy 21.690238 -43.664667) (xy 21.703877 -43.708754) (xy 21.725252 -43.749652)
			(xy 21.753661 -43.786019) (xy 21.78817 -43.816658) (xy 21.827644 -43.840562) (xy 21.870785 -43.856946)
			(xy 21.916176 -43.86527) (xy 21.93925 -43.8658) (xy 22.21865 -43.8658) (xy 22.240648 -43.865337)
			(xy 22.283987 -43.857768) (xy 22.325375 -43.842848) (xy 22.363574 -43.821023) (xy 22.397444 -43.792944)
			(xy 22.425972 -43.759452) (xy 22.448305 -43.721547) (xy 22.463775 -43.680361) (xy 22.471922 -43.637127)
			(xy 22.4725 -43.593136) (xy 22.465492 -43.549702) (xy 22.451109 -43.508125) (xy 22.42978 -43.469646)
			(xy 22.416262 -43.452288) (xy 22.394557 -43.424662) (xy 22.356713 -43.365465) (xy 22.325631 -43.302455)
			(xy 22.30169 -43.2364) (xy 22.285182 -43.168107) (xy 22.276309 -43.09841) (xy 22.275178 -43.02816)
			(xy 22.281805 -42.958213) (xy 22.296107 -42.889425) (xy 22.317911 -42.822634) (xy 22.346949 -42.758656)
			(xy 22.382869 -42.698273) (xy 22.425231 -42.64222) (xy 22.449028 -42.616374) (xy 22.463792 -42.600083)
			(xy 22.48805 -42.563419) (xy 22.505639 -42.523128) (xy 22.516034 -42.480412) (xy 22.518925 -42.436545)
			(xy 22.514226 -42.392835) (xy 22.502077 -42.350584) (xy 22.48284 -42.311054) (xy 22.457089 -42.275423)
			(xy 22.441662 -42.259758) (xy 22.422106 -42.24005) (xy 22.388327 -42.195989) (xy 22.361291 -42.147497)
			(xy 22.341569 -42.095599) (xy 22.329578 -42.04139) (xy 22.32557 -41.986015) (xy 22.329631 -41.930645)
			(xy 22.341675 -41.876447) (xy 22.361447 -41.824568) (xy 22.38853 -41.776102) (xy 22.422351 -41.732074)
			(xy 22.462198 -41.693413) (xy 22.507226 -41.660935) (xy 22.556487 -41.635327) (xy 22.60894 -41.61713)
			(xy 22.663476 -41.606727) (xy 22.718944 -41.604339) (xy 22.774172 -41.610015) (xy 22.827994 -41.623637)
			(xy 22.879274 -41.644916) (xy 22.926928 -41.673403) (xy 22.96995 -41.708496) (xy 23.007431 -41.749455)
			(xy 23.038579 -41.795413) (xy 23.062737 -41.845401) (xy 23.079395 -41.898362) (xy 23.0882 -41.953179)
			(xy 23.088967 -42.008693) (xy 23.08168 -42.063732) (xy 23.066492 -42.117134) (xy 23.05558 -42.142664)
			(xy 23.046957 -42.162909) (xy 23.03604 -42.205532) (xy 23.032632 -42.249399) (xy 23.036833 -42.293197)
			(xy 23.048518 -42.335616) (xy 23.067339 -42.375387) (xy 23.092731 -42.41132) (xy 23.123935 -42.44234)
			(xy 23.160018 -42.467518) (xy 23.179786 -42.477182) (xy 23.212207 -42.492884) (xy 23.273608 -42.530561)
			(xy 23.330356 -42.574939) (xy 23.381723 -42.625448) (xy 23.427051 -42.68144) (xy 23.465757 -42.742198)
			(xy 23.497347 -42.806942) (xy 23.521415 -42.874842) (xy 23.537652 -42.945028) (xy 23.545851 -43.016599)
			(xy 23.545905 -43.088639) (xy 23.537815 -43.160223) (xy 23.521684 -43.230433) (xy 23.497719 -43.29837)
			(xy 23.466227 -43.363162) (xy 23.427613 -43.423978) (xy 23.405338 -43.452288) (xy 23.391891 -43.469695)
			(xy 23.370576 -43.508167) (xy 23.356203 -43.549734) (xy 23.349202 -43.593155) (xy 23.349782 -43.637133)
			(xy 23.357926 -43.680355) (xy 23.37339 -43.721528) (xy 23.395713 -43.759424) (xy 23.424227 -43.792911)
			(xy 23.458081 -43.820988) (xy 23.496264 -43.842816) (xy 23.537635 -43.857744) (xy 23.580959 -43.865325)
			(xy 23.60295 -43.8658) (xy 23.92045 -43.8658) (xy 23.942448 -43.865337) (xy 23.985787 -43.857768)
			(xy 24.027175 -43.842848) (xy 24.065374 -43.821023) (xy 24.099244 -43.792944) (xy 24.127772 -43.759452)
			(xy 24.150105 -43.721547) (xy 24.165575 -43.680361) (xy 24.173722 -43.637127) (xy 24.1743 -43.593136)
			(xy 24.167292 -43.549702) (xy 24.152909 -43.508125) (xy 24.13158 -43.469646) (xy 24.118062 -43.452288)
			(xy 24.095974 -43.424156) (xy 24.057573 -43.363811) (xy 24.026188 -43.299536) (xy 24.002218 -43.232145)
			(xy 23.985965 -43.162488) (xy 23.977635 -43.091447) (xy 23.977333 -43.01992) (xy 23.985062 -42.948811)
			(xy 24.000726 -42.87902) (xy 24.024126 -42.811428) (xy 24.054966 -42.74689) (xy 24.092856 -42.686223)
			(xy 24.137318 -42.630193) (xy 24.187789 -42.579509) (xy 24.24363 -42.534811) (xy 24.304137 -42.496664)
			(xy 24.368544 -42.465552) (xy 24.436036 -42.441867) (xy 24.505761 -42.425908) (xy 24.576836 -42.417878)
			(xy 24.648364 -42.417878) (xy 24.719439 -42.425908) (xy 24.789164 -42.441867) (xy 24.856656 -42.465552)
			(xy 24.921063 -42.496664) (xy 24.98157 -42.534811) (xy 25.037411 -42.579509) (xy 25.087882 -42.630193)
			(xy 25.132344 -42.686223) (xy 25.170234 -42.74689) (xy 25.201074 -42.811428) (xy 25.224474 -42.87902)
			(xy 25.240138 -42.948811) (xy 25.247867 -43.01992) (xy 25.247565 -43.091447) (xy 25.239235 -43.162488)
			(xy 25.222982 -43.232145) (xy 25.199012 -43.299536) (xy 25.167627 -43.363811) (xy 25.129226 -43.424156)
			(xy 25.107138 -43.452288) (xy 25.093691 -43.469695) (xy 25.072376 -43.508167) (xy 25.058003 -43.549734)
			(xy 25.051002 -43.593155) (xy 25.051582 -43.637133) (xy 25.059726 -43.680355) (xy 25.07519 -43.721528)
			(xy 25.097513 -43.759424) (xy 25.126027 -43.792911) (xy 25.159881 -43.820988) (xy 25.198064 -43.842816)
			(xy 25.239435 -43.857744) (xy 25.282759 -43.865325) (xy 25.30475 -43.8658) (xy 26.23566 -43.8658)
			(xy 26.258563 -43.865307) (xy 26.303627 -43.85709) (xy 26.34649 -43.840932) (xy 26.385765 -43.817356)
			(xy 26.42018 -43.787126) (xy 26.448622 -43.751219) (xy 26.470171 -43.710797) (xy 26.48413 -43.667168)
			(xy 26.490046 -43.621745) (xy 26.487729 -43.575996) (xy 26.477253 -43.531403) (xy 26.468578 -43.5102)
			(xy 26.454798 -43.477351) (xy 26.433806 -43.409277) (xy 26.420559 -43.339282) (xy 26.415223 -43.268245)
			(xy 26.417865 -43.197056) (xy 26.428452 -43.12661) (xy 26.44685 -43.05779) (xy 26.47283 -42.991458)
			(xy 26.506065 -42.928449) (xy 26.546138 -42.869551) (xy 26.592546 -42.815505) (xy 26.644707 -42.766987)
			(xy 26.673048 -42.745406) (xy 26.690584 -42.731834) (xy 26.721114 -42.69968) (xy 26.745598 -42.662715)
			(xy 26.763296 -42.622062) (xy 26.773668 -42.578953) (xy 26.776401 -42.534699) (xy 26.771412 -42.490642)
			(xy 26.758851 -42.44812) (xy 26.7391 -42.408423) (xy 26.712759 -42.372757) (xy 26.680628 -42.342204)
			(xy 26.66238 -42.329608) (xy 26.639374 -42.313773) (xy 26.597821 -42.276457) (xy 26.562152 -42.233482)
			(xy 26.533128 -42.185766) (xy 26.511371 -42.134329) (xy 26.497345 -42.08027) (xy 26.491349 -42.024743)
			(xy 26.493513 -41.968936) (xy 26.503789 -41.91404) (xy 26.521958 -41.861228) (xy 26.547632 -41.81163)
			(xy 26.580262 -41.766304) (xy 26.619151 -41.72622) (xy 26.663469 -41.692233) (xy 26.712267 -41.66507)
			(xy 26.764504 -41.645311) (xy 26.819064 -41.633378) (xy 26.874781 -41.629526) (xy 26.930463 -41.633839)
			(xy 26.984922 -41.646222) (xy 27.036994 -41.666413) (xy 27.085567 -41.693979) (xy 27.129601 -41.728331)
			(xy 27.168158 -41.768736) (xy 27.200412 -41.814331) (xy 27.225674 -41.86414) (xy 27.243406 -41.917099)
			(xy 27.253227 -41.972078) (xy 27.254929 -42.027902) (xy 27.248474 -42.083377) (xy 27.234001 -42.137318)
			(xy 27.211819 -42.188574) (xy 27.182402 -42.236048) (xy 27.164792 -42.257726) (xy 27.150804 -42.274955)
			(xy 27.128452 -42.31329) (xy 27.1131 -42.354925) (xy 27.105215 -42.398595) (xy 27.105036 -42.44297)
			(xy 27.112571 -42.486701) (xy 27.127588 -42.528458) (xy 27.149631 -42.566971) (xy 27.178031 -42.601069)
			(xy 27.211922 -42.629714) (xy 27.250275 -42.652035) (xy 27.270964 -42.660062) (xy 27.303177 -42.672432)
			(xy 27.364948 -42.703194) (xy 27.423021 -42.740469) (xy 27.476714 -42.783816) (xy 27.525394 -42.832727)
			(xy 27.568487 -42.886624) (xy 27.605486 -42.944874) (xy 27.635956 -43.00679) (xy 27.659537 -43.071642)
			(xy 27.675952 -43.138668) (xy 27.685008 -43.207078) (xy 27.686597 -43.276067) (xy 27.680702 -43.344821)
			(xy 27.667392 -43.412532) (xy 27.646823 -43.478402) (xy 27.633422 -43.5102) (xy 27.624706 -43.531393)
			(xy 27.614203 -43.575993) (xy 27.611866 -43.621753) (xy 27.617772 -43.667191) (xy 27.631728 -43.710834)
			(xy 27.653283 -43.751267) (xy 27.681737 -43.787181) (xy 27.71617 -43.817411) (xy 27.755465 -43.840978)
			(xy 27.798348 -43.857118) (xy 27.84343 -43.865308) (xy 27.86634 -43.8658) (xy 28.482544 -43.8658)
			(xy 28.505796 -43.865258) (xy 28.551517 -43.856757) (xy 28.594929 -43.840083) (xy 28.634585 -43.815791)
			(xy 28.669162 -43.784693) (xy 28.697507 -43.747825) (xy 28.718674 -43.706417) (xy 28.731958 -43.66185)
			(xy 28.736915 -43.61561) (xy 28.73338 -43.56924) (xy 28.721471 -43.524286) (xy 28.711906 -43.503088)
			(xy 28.697119 -43.470747) (xy 28.674016 -43.403488) (xy 28.658565 -43.334071) (xy 28.650959 -43.263363)
			(xy 28.651295 -43.192247) (xy 28.659567 -43.121614) (xy 28.675672 -43.052345) (xy 28.699408 -42.985308)
			(xy 28.73048 -42.921339) (xy 28.768499 -42.861238) (xy 28.812988 -42.805757) (xy 28.863393 -42.755589)
			(xy 28.919084 -42.711361) (xy 28.979363 -42.673627) (xy 29.043478 -42.642857) (xy 29.110627 -42.619437)
			(xy 29.17997 -42.603659) (xy 29.250642 -42.59572) (xy 29.321758 -42.59572) (xy 29.39243 -42.603659)
			(xy 29.461773 -42.619437) (xy 29.528922 -42.642857) (xy 29.593037 -42.673627) (xy 29.653316 -42.711361)
			(xy 29.709007 -42.755589) (xy 29.759412 -42.805757) (xy 29.803901 -42.861238) (xy 29.84192 -42.921339)
			(xy 29.872992 -42.985308) (xy 29.896728 -43.052345) (xy 29.912833 -43.121614) (xy 29.921105 -43.192247)
			(xy 29.921441 -43.263363) (xy 29.913835 -43.334071) (xy 29.898384 -43.403488) (xy 29.875281 -43.470747)
			(xy 29.860494 -43.503088) (xy 29.851012 -43.524322) (xy 29.839084 -43.569265) (xy 29.835533 -43.615627)
			(xy 29.840477 -43.661862) (xy 29.85375 -43.706426) (xy 29.87491 -43.747831) (xy 29.903251 -43.784695)
			(xy 29.937825 -43.815787) (xy 29.977479 -43.840069) (xy 30.02089 -43.856732) (xy 30.066607 -43.865218)
			(xy 30.089856 -43.8658) (xy 48.0822 -43.8658) (xy 51.3969 -40.5511) (xy 57.0611 -40.5511) (xy 58.9026 -42.3926)
			(xy 58.9026 -45.730261) (xy 63.576192 -45.730261) (xy 63.576192 -45.658939) (xy 63.584178 -45.588065)
			(xy 63.600048 -45.51853) (xy 63.623605 -45.45121) (xy 63.65455 -45.386951) (xy 63.692496 -45.32656)
			(xy 63.736965 -45.270798) (xy 63.787398 -45.220365) (xy 63.84316 -45.175896) (xy 63.903551 -45.13795)
			(xy 63.96781 -45.107005) (xy 64.03513 -45.083448) (xy 64.104665 -45.067578) (xy 64.175539 -45.059592)
			(xy 64.246861 -45.059592) (xy 64.317735 -45.067578) (xy 64.38727 -45.083448) (xy 64.45459 -45.107005)
			(xy 64.518849 -45.13795) (xy 64.57924 -45.175896) (xy 64.635002 -45.220365) (xy 64.685435 -45.270798)
			(xy 64.729904 -45.32656) (xy 64.76785 -45.386951) (xy 64.798795 -45.45121) (xy 64.822352 -45.51853)
			(xy 64.838222 -45.588065) (xy 64.846208 -45.658939) (xy 64.846708 -45.6946) (xy 64.846208 -45.730261)
			(xy 64.838222 -45.801135) (xy 64.822352 -45.87067) (xy 64.80038 -45.933461) (xy 70.738992 -45.933461)
			(xy 70.738992 -45.862139) (xy 70.746978 -45.791265) (xy 70.762848 -45.72173) (xy 70.786405 -45.65441)
			(xy 70.81735 -45.590151) (xy 70.855296 -45.52976) (xy 70.899765 -45.473998) (xy 70.950198 -45.423565)
			(xy 71.00596 -45.379096) (xy 71.066351 -45.34115) (xy 71.13061 -45.310205) (xy 71.19793 -45.286648)
			(xy 71.267465 -45.270778) (xy 71.338339 -45.262792) (xy 71.409661 -45.262792) (xy 71.480535 -45.270778)
			(xy 71.55007 -45.286648) (xy 71.61739 -45.310205) (xy 71.681649 -45.34115) (xy 71.74204 -45.379096)
			(xy 71.797802 -45.423565) (xy 71.848235 -45.473998) (xy 71.892704 -45.52976) (xy 71.93065 -45.590151)
			(xy 71.961595 -45.65441) (xy 71.985152 -45.72173) (xy 72.001022 -45.791265) (xy 72.009008 -45.862139)
			(xy 72.009508 -45.8978) (xy 72.009008 -45.933461) (xy 72.001022 -46.004335) (xy 71.985152 -46.07387)
			(xy 71.961595 -46.14119) (xy 71.93065 -46.205449) (xy 71.892704 -46.26584) (xy 71.848235 -46.321602)
			(xy 71.797802 -46.372035) (xy 71.74204 -46.416504) (xy 71.681649 -46.45445) (xy 71.61739 -46.485395)
			(xy 71.55007 -46.508952) (xy 71.480535 -46.524822) (xy 71.409661 -46.532808) (xy 71.338339 -46.532808)
			(xy 71.267465 -46.524822) (xy 71.19793 -46.508952) (xy 71.13061 -46.485395) (xy 71.066351 -46.45445)
			(xy 71.00596 -46.416504) (xy 70.950198 -46.372035) (xy 70.899765 -46.321602) (xy 70.855296 -46.26584)
			(xy 70.81735 -46.205449) (xy 70.786405 -46.14119) (xy 70.762848 -46.07387) (xy 70.746978 -46.004335)
			(xy 70.738992 -45.933461) (xy 64.80038 -45.933461) (xy 64.798795 -45.93799) (xy 64.76785 -46.002249)
			(xy 64.729904 -46.06264) (xy 64.685435 -46.118402) (xy 64.635002 -46.168835) (xy 64.57924 -46.213304)
			(xy 64.518849 -46.25125) (xy 64.45459 -46.282195) (xy 64.38727 -46.305752) (xy 64.317735 -46.321622)
			(xy 64.246861 -46.329608) (xy 64.175539 -46.329608) (xy 64.104665 -46.321622) (xy 64.03513 -46.305752)
			(xy 63.96781 -46.282195) (xy 63.903551 -46.25125) (xy 63.84316 -46.213304) (xy 63.787398 -46.168835)
			(xy 63.736965 -46.118402) (xy 63.692496 -46.06264) (xy 63.65455 -46.002249) (xy 63.623605 -45.93799)
			(xy 63.600048 -45.87067) (xy 63.584178 -45.801135) (xy 63.576192 -45.730261) (xy 58.9026 -45.730261)
			(xy 58.9026 -48.3108) (xy 60.8838 -50.292) (xy 77.032358 -50.292) (xy 77.054953 -50.291503) (xy 77.099429 -50.283501)
			(xy 77.141789 -50.267759) (xy 77.180697 -50.244774) (xy 77.214926 -50.21527) (xy 77.243398 -50.180178)
			(xy 77.265216 -50.140603) (xy 77.27969 -50.097794) (xy 77.286365 -50.0531) (xy 77.285031 -50.007929)
			(xy 77.275729 -49.963707) (xy 77.258753 -49.921827) (xy 77.234638 -49.883609) (xy 77.21981 -49.86655)
			(xy 77.164478 -49.80527) (xy 77.058961 -49.678255) (xy 76.959536 -49.546417) (xy 76.866423 -49.410048)
			(xy 76.779829 -49.26945) (xy 76.699944 -49.124934) (xy 76.626946 -48.97682) (xy 76.560996 -48.825435)
			(xy 76.502241 -48.671116) (xy 76.450811 -48.514204) (xy 76.406818 -48.355046) (xy 76.370362 -48.193995)
			(xy 76.341522 -48.031407) (xy 76.320363 -47.867643) (xy 76.306931 -47.703064) (xy 76.301256 -47.538036)
			(xy 76.303351 -47.372923) (xy 76.31321 -47.208092) (xy 76.330813 -47.043907) (xy 76.356119 -46.880732)
			(xy 76.389074 -46.718928) (xy 76.429604 -46.558854) (xy 76.47762 -46.400863) (xy 76.533014 -46.245306)
			(xy 76.595665 -46.092527) (xy 76.665434 -45.942864) (xy 76.742165 -45.79665) (xy 76.82569 -45.654206)
			(xy 76.915824 -45.51585) (xy 77.012366 -45.381887) (xy 77.115103 -45.252614) (xy 77.223808 -45.128316)
			(xy 77.33824 -45.009271) (xy 77.397864 -44.952158) (xy 77.421653 -44.92886) (xy 77.463365 -44.876958)
			(xy 77.497684 -44.819897) (xy 77.523982 -44.758725) (xy 77.541776 -44.694561) (xy 77.550741 -44.628581)
			(xy 77.55128 -44.595288) (xy 77.55128 -41.500044) (xy 77.551776 -41.433093) (xy 77.559709 -41.299426)
			(xy 77.575546 -41.166463) (xy 77.599232 -41.034673) (xy 77.630683 -40.904517) (xy 77.669791 -40.776453)
			(xy 77.716415 -40.65093) (xy 77.770395 -40.52839) (xy 77.831538 -40.409263) (xy 77.899632 -40.293967)
			(xy 77.974436 -40.182908) (xy 78.055688 -40.076475) (xy 78.143102 -39.975043) (xy 78.236372 -39.878967)
			(xy 78.335169 -39.788585) (xy 78.439148 -39.704215) (xy 78.547941 -39.626153) (xy 78.661168 -39.554673)
			(xy 78.778431 -39.490026) (xy 78.899318 -39.432439) (xy 79.023404 -39.382115) (xy 79.150253 -39.33923)
			(xy 79.27942 -39.303935) (xy 79.410451 -39.276354) (xy 79.542885 -39.256584) (xy 79.676259 -39.244694)
			(xy 79.810102 -39.240726) (xy 79.943945 -39.244694) (xy 80.077319 -39.256584) (xy 80.209753 -39.276354)
			(xy 80.340784 -39.303935) (xy 80.469951 -39.33923) (xy 80.5968 -39.382115) (xy 80.720886 -39.432439)
			(xy 80.841773 -39.490026) (xy 80.959036 -39.554673) (xy 81.072263 -39.626153) (xy 81.181056 -39.704215)
			(xy 81.285035 -39.788585) (xy 81.383832 -39.878967) (xy 81.477102 -39.975043) (xy 81.564516 -40.076475)
			(xy 81.645768 -40.182908) (xy 81.720572 -40.293967) (xy 81.788666 -40.409263) (xy 81.849809 -40.52839)
			(xy 81.903789 -40.65093) (xy 81.950413 -40.776453) (xy 81.989521 -40.904517) (xy 82.020972 -41.034673)
			(xy 82.038619 -41.132861) (xy 88.264992 -41.132861) (xy 88.264992 -41.061539) (xy 88.272978 -40.990665)
			(xy 88.288848 -40.92113) (xy 88.312405 -40.85381) (xy 88.34335 -40.789551) (xy 88.381296 -40.72916)
			(xy 88.425765 -40.673398) (xy 88.476198 -40.622965) (xy 88.53196 -40.578496) (xy 88.592351 -40.54055)
			(xy 88.65661 -40.509605) (xy 88.72393 -40.486048) (xy 88.793465 -40.470178) (xy 88.864339 -40.462192)
			(xy 88.935661 -40.462192) (xy 89.006535 -40.470178) (xy 89.07607 -40.486048) (xy 89.14339 -40.509605)
			(xy 89.207649 -40.54055) (xy 89.26804 -40.578496) (xy 89.323802 -40.622965) (xy 89.374235 -40.673398)
			(xy 89.418704 -40.72916) (xy 89.45665 -40.789551) (xy 89.487595 -40.85381) (xy 89.511152 -40.92113)
			(xy 89.527022 -40.990665) (xy 89.535008 -41.061539) (xy 89.535508 -41.0972) (xy 89.535008 -41.132861)
			(xy 89.527022 -41.203735) (xy 89.511152 -41.27327) (xy 89.487595 -41.34059) (xy 89.45665 -41.404849)
			(xy 89.418704 -41.46524) (xy 89.374235 -41.521002) (xy 89.323802 -41.571435) (xy 89.26804 -41.615904)
			(xy 89.207649 -41.65385) (xy 89.14339 -41.684795) (xy 89.07607 -41.708352) (xy 89.006535 -41.724222)
			(xy 88.935661 -41.732208) (xy 88.864339 -41.732208) (xy 88.793465 -41.724222) (xy 88.72393 -41.708352)
			(xy 88.65661 -41.684795) (xy 88.592351 -41.65385) (xy 88.53196 -41.615904) (xy 88.476198 -41.571435)
			(xy 88.425765 -41.521002) (xy 88.381296 -41.46524) (xy 88.34335 -41.404849) (xy 88.312405 -41.34059)
			(xy 88.288848 -41.27327) (xy 88.272978 -41.203735) (xy 88.264992 -41.132861) (xy 82.038619 -41.132861)
			(xy 82.044658 -41.166463) (xy 82.060495 -41.299426) (xy 82.068428 -41.433093) (xy 82.068924 -41.500044)
			(xy 82.06867 -44.595288) (xy 82.069218 -44.628591) (xy 82.078209 -44.694588) (xy 82.09604 -44.758763)
			(xy 82.122383 -44.819938) (xy 82.156756 -44.876989) (xy 82.198527 -44.92887) (xy 82.22234 -44.952158)
			(xy 82.281965 -45.009271) (xy 82.396404 -45.128313) (xy 82.505116 -45.252606) (xy 82.607861 -45.381877)
			(xy 82.70441 -45.515838) (xy 82.794549 -45.654193) (xy 82.87808 -45.796635) (xy 82.954818 -45.94285)
			(xy 82.997807 -46.035061) (xy 88.315792 -46.035061) (xy 88.315792 -45.963739) (xy 88.323778 -45.892865)
			(xy 88.339648 -45.82333) (xy 88.363205 -45.75601) (xy 88.39415 -45.691751) (xy 88.432096 -45.63136)
			(xy 88.476565 -45.575598) (xy 88.526998 -45.525165) (xy 88.58276 -45.480696) (xy 88.643151 -45.44275)
			(xy 88.70741 -45.411805) (xy 88.77473 -45.388248) (xy 88.844265 -45.372378) (xy 88.915139 -45.364392)
			(xy 88.986461 -45.364392) (xy 89.057335 -45.372378) (xy 89.12687 -45.388248) (xy 89.19419 -45.411805)
			(xy 89.258449 -45.44275) (xy 89.31884 -45.480696) (xy 89.374602 -45.525165) (xy 89.425035 -45.575598)
			(xy 89.469504 -45.63136) (xy 89.50745 -45.691751) (xy 89.538395 -45.75601) (xy 89.561952 -45.82333)
			(xy 89.577822 -45.892865) (xy 89.585808 -45.963739) (xy 89.586308 -45.9994) (xy 89.585808 -46.035061)
			(xy 89.577822 -46.105935) (xy 89.561952 -46.17547) (xy 89.538395 -46.24279) (xy 89.50745 -46.307049)
			(xy 89.469504 -46.36744) (xy 89.425035 -46.423202) (xy 89.374602 -46.473635) (xy 89.31884 -46.518104)
			(xy 89.258449 -46.55605) (xy 89.19419 -46.586995) (xy 89.12687 -46.610552) (xy 89.057335 -46.626422)
			(xy 88.986461 -46.634408) (xy 88.915139 -46.634408) (xy 88.844265 -46.626422) (xy 88.77473 -46.610552)
			(xy 88.70741 -46.586995) (xy 88.643151 -46.55605) (xy 88.58276 -46.518104) (xy 88.526998 -46.473635)
			(xy 88.476565 -46.423202) (xy 88.432096 -46.36744) (xy 88.39415 -46.307049) (xy 88.363205 -46.24279)
			(xy 88.339648 -46.17547) (xy 88.323778 -46.105935) (xy 88.315792 -46.035061) (xy 82.997807 -46.035061)
			(xy 83.024591 -46.092512) (xy 83.087247 -46.245292) (xy 83.142645 -46.40085) (xy 83.190664 -46.558841)
			(xy 83.231197 -46.718918) (xy 83.264154 -46.880723) (xy 83.289462 -47.0439) (xy 83.307066 -47.208087)
			(xy 83.316926 -47.372921) (xy 83.31902 -47.538035) (xy 83.313344 -47.703066) (xy 83.29991 -47.867646)
			(xy 83.278749 -48.031413) (xy 83.249907 -48.194002) (xy 83.213447 -48.355055) (xy 83.169451 -48.514214)
			(xy 83.118016 -48.671127) (xy 83.059256 -48.825447) (xy 82.993301 -48.976831) (xy 82.920297 -49.124944)
			(xy 82.840405 -49.26946) (xy 82.753804 -49.410056) (xy 82.660684 -49.546423) (xy 82.561251 -49.678258)
			(xy 82.455727 -49.805269) (xy 82.400394 -49.86655) (xy 82.385501 -49.883558) (xy 82.36137 -49.921782)
			(xy 82.344382 -49.963672) (xy 82.335072 -50.007906) (xy 82.333734 -50.05309) (xy 82.340411 -50.097798)
			(xy 82.354891 -50.140619) (xy 82.376718 -50.180203) (xy 82.405204 -50.215302) (xy 82.43945 -50.244808)
			(xy 82.478375 -50.26779) (xy 82.520752 -50.283524) (xy 82.565244 -50.291512) (xy 82.587846 -50.292)
			(xy 93.4974 -50.292) (xy 96.012 -47.7774) (xy 112.776 -47.7774) (xy 115.2398 -50.2412) (xy 131.5974 -50.2412)
			(xy 134.4422 -47.3964) (xy 150.9522 -47.3964) (xy 153.4922 -49.9364) (xy 158.2928 -49.9364) (xy 159.7406 -48.4886)
			(xy 204.724 -48.4886) (xy 206.5528 -50.3174) (xy 207.05572 -50.3174) (xy 207.0784 -50.316899) (xy 207.123039 -50.308844)
			(xy 207.16554 -50.292992) (xy 207.204551 -50.269847) (xy 207.238835 -50.240145) (xy 207.267301 -50.204829)
			(xy 207.289046 -50.165021) (xy 207.303379 -50.121985) (xy 207.309845 -50.077087) (xy 207.308239 -50.031756)
			(xy 207.29861 -49.987429) (xy 207.281267 -49.945515) (xy 207.256758 -49.907346) (xy 207.241648 -49.890426)
			(xy 207.18542 -49.829297) (xy 207.078133 -49.702481) (xy 206.976968 -49.57073) (xy 206.882151 -49.434339)
			(xy 206.793896 -49.293614) (xy 206.712398 -49.14887) (xy 206.637842 -49.000431) (xy 206.570394 -48.84863)
			(xy 206.510206 -48.693807) (xy 206.457412 -48.53631) (xy 206.41213 -48.37649) (xy 206.374463 -48.214707)
			(xy 206.344494 -48.051323) (xy 206.322291 -47.886703) (xy 206.307903 -47.721217) (xy 206.301362 -47.555235)
			(xy 206.302684 -47.38913) (xy 206.311865 -47.223273) (xy 206.328885 -47.058037) (xy 206.353706 -46.893791)
			(xy 206.386272 -46.730904) (xy 206.426509 -46.569741) (xy 206.474329 -46.410663) (xy 206.529623 -46.254025)
			(xy 206.592267 -46.10018) (xy 206.662123 -45.949472) (xy 206.739032 -45.802239) (xy 206.822823 -45.65881)
			(xy 206.913307 -45.519507) (xy 207.010282 -45.384643) (xy 207.113532 -45.254519) (xy 207.222823 -45.129426)
			(xy 207.337912 -45.009646) (xy 207.397858 -44.952158) (xy 207.416762 -44.93382) (xy 207.450947 -44.893753)
			(xy 207.480636 -44.850248) (xy 207.493362 -44.82719) (xy 207.507203 -44.800347) (xy 207.52896 -44.744007)
			(xy 207.543654 -44.685425) (xy 207.551061 -44.625486) (xy 207.551528 -44.595288) (xy 207.551528 -43.481244)
			(xy 207.551274 -42.3672) (xy 207.551274 -41.500044) (xy 207.551778 -41.431804) (xy 207.560016 -41.295573)
			(xy 207.576464 -41.160088) (xy 207.601063 -41.025843) (xy 207.633723 -40.893328) (xy 207.674324 -40.763027)
			(xy 207.722718 -40.635415) (xy 207.77873 -40.510958) (xy 207.842153 -40.39011) (xy 207.912758 -40.273312)
			(xy 207.990286 -40.16099) (xy 208.074455 -40.053554) (xy 208.164957 -39.951397) (xy 208.261462 -39.85489)
			(xy 208.363617 -39.764386) (xy 208.471052 -39.680215) (xy 208.583372 -39.602684) (xy 208.700168 -39.532077)
			(xy 208.821015 -39.468651) (xy 208.945471 -39.412637) (xy 209.073081 -39.36424) (xy 209.203382 -39.323636)
			(xy 209.335896 -39.290973) (xy 209.47014 -39.266371) (xy 209.605625 -39.24992) (xy 209.741856 -39.241679)
			(xy 209.810096 -39.241222) (xy 209.878333 -39.241727) (xy 210.014557 -39.249968) (xy 210.150035 -39.266418)
			(xy 210.284272 -39.29102) (xy 210.416779 -39.323682) (xy 210.547072 -39.364286) (xy 210.674675 -39.412683)
			(xy 210.799123 -39.468696) (xy 210.919962 -39.532123) (xy 211.036751 -39.602729) (xy 211.149063 -39.68026)
			(xy 211.256488 -39.76443) (xy 211.358635 -39.854933) (xy 211.455131 -39.951439) (xy 211.545624 -40.053596)
			(xy 211.629783 -40.161031) (xy 211.707301 -40.273351) (xy 211.777895 -40.390147) (xy 211.841309 -40.510993)
			(xy 211.897309 -40.635447) (xy 211.945693 -40.763055) (xy 211.986282 -40.893352) (xy 212.018931 -41.025863)
			(xy 212.043518 -41.160103) (xy 212.059954 -41.295582) (xy 212.06818 -41.431807) (xy 212.068664 -41.500044)
			(xy 212.068664 -44.595288) (xy 212.069125 -44.625486) (xy 212.076528 -44.685427) (xy 212.091224 -44.744008)
			(xy 212.112991 -44.800345) (xy 212.12683 -44.82719) (xy 212.13958 -44.850233) (xy 212.169282 -44.893724)
			(xy 212.203451 -44.933801) (xy 212.222334 -44.952158) (xy 212.282312 -45.009613) (xy 212.397397 -45.129398)
			(xy 212.506684 -45.254494) (xy 212.609929 -45.384622) (xy 212.706901 -45.51949) (xy 212.797381 -45.658795)
			(xy 212.881169 -45.802226) (xy 212.958075 -45.949462) (xy 213.027927 -46.100172) (xy 213.090569 -46.254018)
			(xy 213.145861 -46.410657) (xy 213.193678 -46.569737) (xy 213.233914 -46.730901) (xy 213.266478 -46.893788)
			(xy 213.291297 -47.058035) (xy 213.308316 -47.223271) (xy 213.317497 -47.389128) (xy 213.318819 -47.555234)
			(xy 213.312279 -47.721216) (xy 213.297892 -47.886703) (xy 213.27569 -48.051323) (xy 213.245722 -48.214708)
			(xy 213.238702 -48.244861) (xy 217.042992 -48.244861) (xy 217.042992 -48.173539) (xy 217.050978 -48.102665)
			(xy 217.066848 -48.03313) (xy 217.090405 -47.96581) (xy 217.12135 -47.901551) (xy 217.159296 -47.84116)
			(xy 217.203765 -47.785398) (xy 217.254198 -47.734965) (xy 217.30996 -47.690496) (xy 217.370351 -47.65255)
			(xy 217.43461 -47.621605) (xy 217.50193 -47.598048) (xy 217.571465 -47.582178) (xy 217.642339 -47.574192)
			(xy 217.713661 -47.574192) (xy 217.784535 -47.582178) (xy 217.85407 -47.598048) (xy 217.92139 -47.621605)
			(xy 217.985649 -47.65255) (xy 218.04604 -47.690496) (xy 218.101802 -47.734965) (xy 218.152235 -47.785398)
			(xy 218.196704 -47.84116) (xy 218.23465 -47.901551) (xy 218.265595 -47.96581) (xy 218.289152 -48.03313)
			(xy 218.305022 -48.102665) (xy 218.313008 -48.173539) (xy 218.313508 -48.2092) (xy 218.313008 -48.244861)
			(xy 224.662992 -48.244861) (xy 224.662992 -48.173539) (xy 224.670978 -48.102665) (xy 224.686848 -48.03313)
			(xy 224.710405 -47.96581) (xy 224.74135 -47.901551) (xy 224.779296 -47.84116) (xy 224.823765 -47.785398)
			(xy 224.874198 -47.734965) (xy 224.92996 -47.690496) (xy 224.990351 -47.65255) (xy 225.05461 -47.621605)
			(xy 225.12193 -47.598048) (xy 225.191465 -47.582178) (xy 225.262339 -47.574192) (xy 225.333661 -47.574192)
			(xy 225.404535 -47.582178) (xy 225.47407 -47.598048) (xy 225.54139 -47.621605) (xy 225.605649 -47.65255)
			(xy 225.66604 -47.690496) (xy 225.721802 -47.734965) (xy 225.772235 -47.785398) (xy 225.816704 -47.84116)
			(xy 225.85465 -47.901551) (xy 225.885595 -47.96581) (xy 225.909152 -48.03313) (xy 225.925022 -48.102665)
			(xy 225.933008 -48.173539) (xy 225.933508 -48.2092) (xy 225.933008 -48.244861) (xy 232.282992 -48.244861)
			(xy 232.282992 -48.173539) (xy 232.290978 -48.102665) (xy 232.306848 -48.03313) (xy 232.330405 -47.96581)
			(xy 232.36135 -47.901551) (xy 232.399296 -47.84116) (xy 232.443765 -47.785398) (xy 232.494198 -47.734965)
			(xy 232.54996 -47.690496) (xy 232.610351 -47.65255) (xy 232.67461 -47.621605) (xy 232.74193 -47.598048)
			(xy 232.811465 -47.582178) (xy 232.882339 -47.574192) (xy 232.953661 -47.574192) (xy 233.024535 -47.582178)
			(xy 233.09407 -47.598048) (xy 233.16139 -47.621605) (xy 233.225649 -47.65255) (xy 233.28604 -47.690496)
			(xy 233.341802 -47.734965) (xy 233.392235 -47.785398) (xy 233.436704 -47.84116) (xy 233.47465 -47.901551)
			(xy 233.505595 -47.96581) (xy 233.529152 -48.03313) (xy 233.545022 -48.102665) (xy 233.553008 -48.173539)
			(xy 233.553508 -48.2092) (xy 233.553008 -48.244861) (xy 239.902992 -48.244861) (xy 239.902992 -48.173539)
			(xy 239.910978 -48.102665) (xy 239.926848 -48.03313) (xy 239.950405 -47.96581) (xy 239.98135 -47.901551)
			(xy 240.019296 -47.84116) (xy 240.063765 -47.785398) (xy 240.114198 -47.734965) (xy 240.16996 -47.690496)
			(xy 240.230351 -47.65255) (xy 240.29461 -47.621605) (xy 240.36193 -47.598048) (xy 240.431465 -47.582178)
			(xy 240.502339 -47.574192) (xy 240.573661 -47.574192) (xy 240.644535 -47.582178) (xy 240.71407 -47.598048)
			(xy 240.78139 -47.621605) (xy 240.845649 -47.65255) (xy 240.90604 -47.690496) (xy 240.961802 -47.734965)
			(xy 241.012235 -47.785398) (xy 241.056704 -47.84116) (xy 241.09465 -47.901551) (xy 241.125595 -47.96581)
			(xy 241.149152 -48.03313) (xy 241.165022 -48.102665) (xy 241.173008 -48.173539) (xy 241.173508 -48.2092)
			(xy 241.173008 -48.244861) (xy 247.522992 -48.244861) (xy 247.522992 -48.173539) (xy 247.530978 -48.102665)
			(xy 247.546848 -48.03313) (xy 247.570405 -47.96581) (xy 247.60135 -47.901551) (xy 247.639296 -47.84116)
			(xy 247.683765 -47.785398) (xy 247.734198 -47.734965) (xy 247.78996 -47.690496) (xy 247.850351 -47.65255)
			(xy 247.91461 -47.621605) (xy 247.98193 -47.598048) (xy 248.051465 -47.582178) (xy 248.122339 -47.574192)
			(xy 248.193661 -47.574192) (xy 248.264535 -47.582178) (xy 248.33407 -47.598048) (xy 248.40139 -47.621605)
			(xy 248.465649 -47.65255) (xy 248.52604 -47.690496) (xy 248.581802 -47.734965) (xy 248.632235 -47.785398)
			(xy 248.676704 -47.84116) (xy 248.71465 -47.901551) (xy 248.745595 -47.96581) (xy 248.769152 -48.03313)
			(xy 248.785022 -48.102665) (xy 248.793008 -48.173539) (xy 248.793508 -48.2092) (xy 248.793008 -48.244861)
			(xy 255.142992 -48.244861) (xy 255.142992 -48.173539) (xy 255.150978 -48.102665) (xy 255.166848 -48.03313)
			(xy 255.190405 -47.96581) (xy 255.22135 -47.901551) (xy 255.259296 -47.84116) (xy 255.303765 -47.785398)
			(xy 255.354198 -47.734965) (xy 255.40996 -47.690496) (xy 255.470351 -47.65255) (xy 255.53461 -47.621605)
			(xy 255.60193 -47.598048) (xy 255.671465 -47.582178) (xy 255.742339 -47.574192) (xy 255.813661 -47.574192)
			(xy 255.884535 -47.582178) (xy 255.95407 -47.598048) (xy 256.02139 -47.621605) (xy 256.085649 -47.65255)
			(xy 256.14604 -47.690496) (xy 256.201802 -47.734965) (xy 256.252235 -47.785398) (xy 256.296704 -47.84116)
			(xy 256.33465 -47.901551) (xy 256.365595 -47.96581) (xy 256.389152 -48.03313) (xy 256.405022 -48.102665)
			(xy 256.413008 -48.173539) (xy 256.413508 -48.2092) (xy 256.413008 -48.244861) (xy 262.762992 -48.244861)
			(xy 262.762992 -48.173539) (xy 262.770978 -48.102665) (xy 262.786848 -48.03313) (xy 262.810405 -47.96581)
			(xy 262.84135 -47.901551) (xy 262.879296 -47.84116) (xy 262.923765 -47.785398) (xy 262.974198 -47.734965)
			(xy 263.02996 -47.690496) (xy 263.090351 -47.65255) (xy 263.15461 -47.621605) (xy 263.22193 -47.598048)
			(xy 263.291465 -47.582178) (xy 263.362339 -47.574192) (xy 263.433661 -47.574192) (xy 263.504535 -47.582178)
			(xy 263.57407 -47.598048) (xy 263.64139 -47.621605) (xy 263.705649 -47.65255) (xy 263.76604 -47.690496)
			(xy 263.821802 -47.734965) (xy 263.872235 -47.785398) (xy 263.916704 -47.84116) (xy 263.95465 -47.901551)
			(xy 263.985595 -47.96581) (xy 264.009152 -48.03313) (xy 264.025022 -48.102665) (xy 264.033008 -48.173539)
			(xy 264.033508 -48.2092) (xy 264.033008 -48.244861) (xy 270.382992 -48.244861) (xy 270.382992 -48.173539)
			(xy 270.390978 -48.102665) (xy 270.406848 -48.03313) (xy 270.430405 -47.96581) (xy 270.46135 -47.901551)
			(xy 270.499296 -47.84116) (xy 270.543765 -47.785398) (xy 270.594198 -47.734965) (xy 270.64996 -47.690496)
			(xy 270.710351 -47.65255) (xy 270.77461 -47.621605) (xy 270.84193 -47.598048) (xy 270.911465 -47.582178)
			(xy 270.982339 -47.574192) (xy 271.053661 -47.574192) (xy 271.124535 -47.582178) (xy 271.19407 -47.598048)
			(xy 271.26139 -47.621605) (xy 271.325649 -47.65255) (xy 271.38604 -47.690496) (xy 271.441802 -47.734965)
			(xy 271.492235 -47.785398) (xy 271.536704 -47.84116) (xy 271.57465 -47.901551) (xy 271.605595 -47.96581)
			(xy 271.629152 -48.03313) (xy 271.645022 -48.102665) (xy 271.653008 -48.173539) (xy 271.653508 -48.2092)
			(xy 271.653008 -48.244861) (xy 278.002992 -48.244861) (xy 278.002992 -48.173539) (xy 278.010978 -48.102665)
			(xy 278.026848 -48.03313) (xy 278.050405 -47.96581) (xy 278.08135 -47.901551) (xy 278.119296 -47.84116)
			(xy 278.163765 -47.785398) (xy 278.214198 -47.734965) (xy 278.26996 -47.690496) (xy 278.330351 -47.65255)
			(xy 278.39461 -47.621605) (xy 278.46193 -47.598048) (xy 278.531465 -47.582178) (xy 278.602339 -47.574192)
			(xy 278.673661 -47.574192) (xy 278.744535 -47.582178) (xy 278.81407 -47.598048) (xy 278.88139 -47.621605)
			(xy 278.945649 -47.65255) (xy 279.00604 -47.690496) (xy 279.061802 -47.734965) (xy 279.112235 -47.785398)
			(xy 279.156704 -47.84116) (xy 279.19465 -47.901551) (xy 279.225595 -47.96581) (xy 279.249152 -48.03313)
			(xy 279.265022 -48.102665) (xy 279.273008 -48.173539) (xy 279.273508 -48.2092) (xy 279.273008 -48.244861)
			(xy 285.622992 -48.244861) (xy 285.622992 -48.173539) (xy 285.630978 -48.102665) (xy 285.646848 -48.03313)
			(xy 285.670405 -47.96581) (xy 285.70135 -47.901551) (xy 285.739296 -47.84116) (xy 285.783765 -47.785398)
			(xy 285.834198 -47.734965) (xy 285.88996 -47.690496) (xy 285.950351 -47.65255) (xy 286.01461 -47.621605)
			(xy 286.08193 -47.598048) (xy 286.151465 -47.582178) (xy 286.222339 -47.574192) (xy 286.293661 -47.574192)
			(xy 286.364535 -47.582178) (xy 286.43407 -47.598048) (xy 286.50139 -47.621605) (xy 286.565649 -47.65255)
			(xy 286.62604 -47.690496) (xy 286.681802 -47.734965) (xy 286.732235 -47.785398) (xy 286.776704 -47.84116)
			(xy 286.81465 -47.901551) (xy 286.845595 -47.96581) (xy 286.869152 -48.03313) (xy 286.885022 -48.102665)
			(xy 286.893008 -48.173539) (xy 286.893508 -48.2092) (xy 286.893008 -48.244861) (xy 293.242992 -48.244861)
			(xy 293.242992 -48.173539) (xy 293.250978 -48.102665) (xy 293.266848 -48.03313) (xy 293.290405 -47.96581)
			(xy 293.32135 -47.901551) (xy 293.359296 -47.84116) (xy 293.403765 -47.785398) (xy 293.454198 -47.734965)
			(xy 293.50996 -47.690496) (xy 293.570351 -47.65255) (xy 293.63461 -47.621605) (xy 293.70193 -47.598048)
			(xy 293.771465 -47.582178) (xy 293.842339 -47.574192) (xy 293.913661 -47.574192) (xy 293.984535 -47.582178)
			(xy 294.05407 -47.598048) (xy 294.12139 -47.621605) (xy 294.185649 -47.65255) (xy 294.24604 -47.690496)
			(xy 294.301802 -47.734965) (xy 294.352235 -47.785398) (xy 294.396704 -47.84116) (xy 294.43465 -47.901551)
			(xy 294.465595 -47.96581) (xy 294.489152 -48.03313) (xy 294.505022 -48.102665) (xy 294.513008 -48.173539)
			(xy 294.513508 -48.2092) (xy 294.513008 -48.244861) (xy 294.505022 -48.315735) (xy 294.489152 -48.38527)
			(xy 294.465595 -48.45259) (xy 294.43465 -48.516849) (xy 294.396704 -48.57724) (xy 294.352235 -48.633002)
			(xy 294.301802 -48.683435) (xy 294.24604 -48.727904) (xy 294.185649 -48.76585) (xy 294.12139 -48.796795)
			(xy 294.05407 -48.820352) (xy 293.984535 -48.836222) (xy 293.913661 -48.844208) (xy 293.842339 -48.844208)
			(xy 293.771465 -48.836222) (xy 293.70193 -48.820352) (xy 293.63461 -48.796795) (xy 293.570351 -48.76585)
			(xy 293.50996 -48.727904) (xy 293.454198 -48.683435) (xy 293.403765 -48.633002) (xy 293.359296 -48.57724)
			(xy 293.32135 -48.516849) (xy 293.290405 -48.45259) (xy 293.266848 -48.38527) (xy 293.250978 -48.315735)
			(xy 293.242992 -48.244861) (xy 286.893008 -48.244861) (xy 286.885022 -48.315735) (xy 286.869152 -48.38527)
			(xy 286.845595 -48.45259) (xy 286.81465 -48.516849) (xy 286.776704 -48.57724) (xy 286.732235 -48.633002)
			(xy 286.681802 -48.683435) (xy 286.62604 -48.727904) (xy 286.565649 -48.76585) (xy 286.50139 -48.796795)
			(xy 286.43407 -48.820352) (xy 286.364535 -48.836222) (xy 286.293661 -48.844208) (xy 286.222339 -48.844208)
			(xy 286.151465 -48.836222) (xy 286.08193 -48.820352) (xy 286.01461 -48.796795) (xy 285.950351 -48.76585)
			(xy 285.88996 -48.727904) (xy 285.834198 -48.683435) (xy 285.783765 -48.633002) (xy 285.739296 -48.57724)
			(xy 285.70135 -48.516849) (xy 285.670405 -48.45259) (xy 285.646848 -48.38527) (xy 285.630978 -48.315735)
			(xy 285.622992 -48.244861) (xy 279.273008 -48.244861) (xy 279.265022 -48.315735) (xy 279.249152 -48.38527)
			(xy 279.225595 -48.45259) (xy 279.19465 -48.516849) (xy 279.156704 -48.57724) (xy 279.112235 -48.633002)
			(xy 279.061802 -48.683435) (xy 279.00604 -48.727904) (xy 278.945649 -48.76585) (xy 278.88139 -48.796795)
			(xy 278.81407 -48.820352) (xy 278.744535 -48.836222) (xy 278.673661 -48.844208) (xy 278.602339 -48.844208)
			(xy 278.531465 -48.836222) (xy 278.46193 -48.820352) (xy 278.39461 -48.796795) (xy 278.330351 -48.76585)
			(xy 278.26996 -48.727904) (xy 278.214198 -48.683435) (xy 278.163765 -48.633002) (xy 278.119296 -48.57724)
			(xy 278.08135 -48.516849) (xy 278.050405 -48.45259) (xy 278.026848 -48.38527) (xy 278.010978 -48.315735)
			(xy 278.002992 -48.244861) (xy 271.653008 -48.244861) (xy 271.645022 -48.315735) (xy 271.629152 -48.38527)
			(xy 271.605595 -48.45259) (xy 271.57465 -48.516849) (xy 271.536704 -48.57724) (xy 271.492235 -48.633002)
			(xy 271.441802 -48.683435) (xy 271.38604 -48.727904) (xy 271.325649 -48.76585) (xy 271.26139 -48.796795)
			(xy 271.19407 -48.820352) (xy 271.124535 -48.836222) (xy 271.053661 -48.844208) (xy 270.982339 -48.844208)
			(xy 270.911465 -48.836222) (xy 270.84193 -48.820352) (xy 270.77461 -48.796795) (xy 270.710351 -48.76585)
			(xy 270.64996 -48.727904) (xy 270.594198 -48.683435) (xy 270.543765 -48.633002) (xy 270.499296 -48.57724)
			(xy 270.46135 -48.516849) (xy 270.430405 -48.45259) (xy 270.406848 -48.38527) (xy 270.390978 -48.315735)
			(xy 270.382992 -48.244861) (xy 264.033008 -48.244861) (xy 264.025022 -48.315735) (xy 264.009152 -48.38527)
			(xy 263.985595 -48.45259) (xy 263.95465 -48.516849) (xy 263.916704 -48.57724) (xy 263.872235 -48.633002)
			(xy 263.821802 -48.683435) (xy 263.76604 -48.727904) (xy 263.705649 -48.76585) (xy 263.64139 -48.796795)
			(xy 263.57407 -48.820352) (xy 263.504535 -48.836222) (xy 263.433661 -48.844208) (xy 263.362339 -48.844208)
			(xy 263.291465 -48.836222) (xy 263.22193 -48.820352) (xy 263.15461 -48.796795) (xy 263.090351 -48.76585)
			(xy 263.02996 -48.727904) (xy 262.974198 -48.683435) (xy 262.923765 -48.633002) (xy 262.879296 -48.57724)
			(xy 262.84135 -48.516849) (xy 262.810405 -48.45259) (xy 262.786848 -48.38527) (xy 262.770978 -48.315735)
			(xy 262.762992 -48.244861) (xy 256.413008 -48.244861) (xy 256.405022 -48.315735) (xy 256.389152 -48.38527)
			(xy 256.365595 -48.45259) (xy 256.33465 -48.516849) (xy 256.296704 -48.57724) (xy 256.252235 -48.633002)
			(xy 256.201802 -48.683435) (xy 256.14604 -48.727904) (xy 256.085649 -48.76585) (xy 256.02139 -48.796795)
			(xy 255.95407 -48.820352) (xy 255.884535 -48.836222) (xy 255.813661 -48.844208) (xy 255.742339 -48.844208)
			(xy 255.671465 -48.836222) (xy 255.60193 -48.820352) (xy 255.53461 -48.796795) (xy 255.470351 -48.76585)
			(xy 255.40996 -48.727904) (xy 255.354198 -48.683435) (xy 255.303765 -48.633002) (xy 255.259296 -48.57724)
			(xy 255.22135 -48.516849) (xy 255.190405 -48.45259) (xy 255.166848 -48.38527) (xy 255.150978 -48.315735)
			(xy 255.142992 -48.244861) (xy 248.793008 -48.244861) (xy 248.785022 -48.315735) (xy 248.769152 -48.38527)
			(xy 248.745595 -48.45259) (xy 248.71465 -48.516849) (xy 248.676704 -48.57724) (xy 248.632235 -48.633002)
			(xy 248.581802 -48.683435) (xy 248.52604 -48.727904) (xy 248.465649 -48.76585) (xy 248.40139 -48.796795)
			(xy 248.33407 -48.820352) (xy 248.264535 -48.836222) (xy 248.193661 -48.844208) (xy 248.122339 -48.844208)
			(xy 248.051465 -48.836222) (xy 247.98193 -48.820352) (xy 247.91461 -48.796795) (xy 247.850351 -48.76585)
			(xy 247.78996 -48.727904) (xy 247.734198 -48.683435) (xy 247.683765 -48.633002) (xy 247.639296 -48.57724)
			(xy 247.60135 -48.516849) (xy 247.570405 -48.45259) (xy 247.546848 -48.38527) (xy 247.530978 -48.315735)
			(xy 247.522992 -48.244861) (xy 241.173008 -48.244861) (xy 241.165022 -48.315735) (xy 241.149152 -48.38527)
			(xy 241.125595 -48.45259) (xy 241.09465 -48.516849) (xy 241.056704 -48.57724) (xy 241.012235 -48.633002)
			(xy 240.961802 -48.683435) (xy 240.90604 -48.727904) (xy 240.845649 -48.76585) (xy 240.78139 -48.796795)
			(xy 240.71407 -48.820352) (xy 240.644535 -48.836222) (xy 240.573661 -48.844208) (xy 240.502339 -48.844208)
			(xy 240.431465 -48.836222) (xy 240.36193 -48.820352) (xy 240.29461 -48.796795) (xy 240.230351 -48.76585)
			(xy 240.16996 -48.727904) (xy 240.114198 -48.683435) (xy 240.063765 -48.633002) (xy 240.019296 -48.57724)
			(xy 239.98135 -48.516849) (xy 239.950405 -48.45259) (xy 239.926848 -48.38527) (xy 239.910978 -48.315735)
			(xy 239.902992 -48.244861) (xy 233.553008 -48.244861) (xy 233.545022 -48.315735) (xy 233.529152 -48.38527)
			(xy 233.505595 -48.45259) (xy 233.47465 -48.516849) (xy 233.436704 -48.57724) (xy 233.392235 -48.633002)
			(xy 233.341802 -48.683435) (xy 233.28604 -48.727904) (xy 233.225649 -48.76585) (xy 233.16139 -48.796795)
			(xy 233.09407 -48.820352) (xy 233.024535 -48.836222) (xy 232.953661 -48.844208) (xy 232.882339 -48.844208)
			(xy 232.811465 -48.836222) (xy 232.74193 -48.820352) (xy 232.67461 -48.796795) (xy 232.610351 -48.76585)
			(xy 232.54996 -48.727904) (xy 232.494198 -48.683435) (xy 232.443765 -48.633002) (xy 232.399296 -48.57724)
			(xy 232.36135 -48.516849) (xy 232.330405 -48.45259) (xy 232.306848 -48.38527) (xy 232.290978 -48.315735)
			(xy 232.282992 -48.244861) (xy 225.933008 -48.244861) (xy 225.925022 -48.315735) (xy 225.909152 -48.38527)
			(xy 225.885595 -48.45259) (xy 225.85465 -48.516849) (xy 225.816704 -48.57724) (xy 225.772235 -48.633002)
			(xy 225.721802 -48.683435) (xy 225.66604 -48.727904) (xy 225.605649 -48.76585) (xy 225.54139 -48.796795)
			(xy 225.47407 -48.820352) (xy 225.404535 -48.836222) (xy 225.333661 -48.844208) (xy 225.262339 -48.844208)
			(xy 225.191465 -48.836222) (xy 225.12193 -48.820352) (xy 225.05461 -48.796795) (xy 224.990351 -48.76585)
			(xy 224.92996 -48.727904) (xy 224.874198 -48.683435) (xy 224.823765 -48.633002) (xy 224.779296 -48.57724)
			(xy 224.74135 -48.516849) (xy 224.710405 -48.45259) (xy 224.686848 -48.38527) (xy 224.670978 -48.315735)
			(xy 224.662992 -48.244861) (xy 218.313008 -48.244861) (xy 218.305022 -48.315735) (xy 218.289152 -48.38527)
			(xy 218.265595 -48.45259) (xy 218.23465 -48.516849) (xy 218.196704 -48.57724) (xy 218.152235 -48.633002)
			(xy 218.101802 -48.683435) (xy 218.04604 -48.727904) (xy 217.985649 -48.76585) (xy 217.92139 -48.796795)
			(xy 217.85407 -48.820352) (xy 217.784535 -48.836222) (xy 217.713661 -48.844208) (xy 217.642339 -48.844208)
			(xy 217.571465 -48.836222) (xy 217.50193 -48.820352) (xy 217.43461 -48.796795) (xy 217.370351 -48.76585)
			(xy 217.30996 -48.727904) (xy 217.254198 -48.683435) (xy 217.203765 -48.633002) (xy 217.159296 -48.57724)
			(xy 217.12135 -48.516849) (xy 217.090405 -48.45259) (xy 217.066848 -48.38527) (xy 217.050978 -48.315735)
			(xy 217.042992 -48.244861) (xy 213.238702 -48.244861) (xy 213.208057 -48.376492) (xy 213.162777 -48.536313)
			(xy 213.109985 -48.693812) (xy 213.0498 -48.848636) (xy 212.982355 -49.000438) (xy 212.907802 -49.148879)
			(xy 212.826308 -49.293626) (xy 212.738056 -49.434354) (xy 212.643244 -49.570748) (xy 212.542083 -49.702502)
			(xy 212.4348 -49.829322) (xy 212.378544 -49.890426) (xy 212.363464 -49.90737) (xy 212.33896 -49.945534)
			(xy 212.321619 -49.987441) (xy 212.311993 -50.031761) (xy 212.310387 -50.077086) (xy 212.316852 -50.121977)
			(xy 212.331183 -50.165007) (xy 212.352925 -50.204809) (xy 212.381386 -50.24012) (xy 212.415664 -50.269819)
			(xy 212.454669 -50.29296) (xy 212.497163 -50.308811) (xy 212.541795 -50.316866) (xy 212.564472 -50.3174)
			(xy 298.055792 -50.3174) (xy 298.078474 -50.316902) (xy 298.123118 -50.30885) (xy 298.165623 -50.293)
			(xy 298.204639 -50.269856) (xy 298.238926 -50.240154) (xy 298.267396 -50.204836) (xy 298.289144 -50.165025)
			(xy 298.303479 -50.121985) (xy 298.309945 -50.077085) (xy 298.308338 -50.031749) (xy 298.298707 -49.987419)
			(xy 298.28136 -49.945503) (xy 298.256847 -49.907332) (xy 298.24172 -49.890426) (xy 298.185492 -49.829296)
			(xy 298.078206 -49.70248) (xy 297.977042 -49.570729) (xy 297.882226 -49.434338) (xy 297.793971 -49.293613)
			(xy 297.712474 -49.148868) (xy 297.637919 -49.000429) (xy 297.570472 -48.848629) (xy 297.510284 -48.693806)
			(xy 297.45749 -48.536309) (xy 297.412209 -48.376489) (xy 297.374542 -48.214706) (xy 297.344573 -48.051322)
			(xy 297.32237 -47.886702) (xy 297.307982 -47.721216) (xy 297.301442 -47.555235) (xy 297.302764 -47.38913)
			(xy 297.311945 -47.223273) (xy 297.328965 -47.058037) (xy 297.353785 -46.893792) (xy 297.38635 -46.730905)
			(xy 297.426588 -46.569742) (xy 297.474407 -46.410664) (xy 297.5297 -46.254026) (xy 297.592345 -46.100181)
			(xy 297.662199 -45.949473) (xy 297.739108 -45.80224) (xy 297.822898 -45.658811) (xy 297.913382 -45.519508)
			(xy 298.010356 -45.384643) (xy 298.113605 -45.254519) (xy 298.222895 -45.129426) (xy 298.337983 -45.009646)
			(xy 298.39793 -44.952158) (xy 298.416835 -44.933821) (xy 298.451022 -44.893754) (xy 298.480712 -44.850251)
			(xy 298.493434 -44.82719) (xy 298.507276 -44.800347) (xy 298.529034 -44.744007) (xy 298.543728 -44.685426)
			(xy 298.551137 -44.625486) (xy 298.5516 -44.595288) (xy 298.5516 -41.500044) (xy 298.552096 -41.4331)
			(xy 298.560028 -41.299448) (xy 298.575863 -41.166501) (xy 298.599546 -41.034725) (xy 298.630994 -40.904584)
			(xy 298.670097 -40.776534) (xy 298.716717 -40.651025) (xy 298.77069 -40.528499) (xy 298.831827 -40.409386)
			(xy 298.899913 -40.294103) (xy 298.974708 -40.183056) (xy 299.055951 -40.076635) (xy 299.143355 -39.975214)
			(xy 299.236615 -39.879149) (xy 299.335401 -39.788778) (xy 299.439368 -39.704417) (xy 299.548149 -39.626363)
			(xy 299.661364 -39.554891) (xy 299.778613 -39.490252) (xy 299.899486 -39.432671) (xy 300.023558 -39.382353)
			(xy 300.150393 -39.339473) (xy 300.279545 -39.304182) (xy 300.410562 -39.276604) (xy 300.542981 -39.256836)
			(xy 300.67634 -39.244948) (xy 300.810168 -39.24098) (xy 300.943996 -39.244948) (xy 301.077355 -39.256836)
			(xy 301.209774 -39.276604) (xy 301.340791 -39.304182) (xy 301.469943 -39.339473) (xy 301.596778 -39.382353)
			(xy 301.72085 -39.432671) (xy 301.841723 -39.490252) (xy 301.958972 -39.554891) (xy 302.072187 -39.626363)
			(xy 302.180968 -39.704417) (xy 302.284935 -39.788778) (xy 302.383721 -39.879149) (xy 302.476981 -39.975214)
			(xy 302.564385 -40.076635) (xy 302.645628 -40.183056) (xy 302.720423 -40.294103) (xy 302.788509 -40.409386)
			(xy 302.849646 -40.528499) (xy 302.903619 -40.651025) (xy 302.950239 -40.776534) (xy 302.989342 -40.904584)
			(xy 303.02079 -41.034725) (xy 303.044473 -41.166501) (xy 303.060308 -41.299448) (xy 303.06824 -41.4331)
			(xy 303.068736 -41.500044) (xy 303.068736 -43.047666) (xy 303.06899 -44.595288) (xy 303.069523 -44.628583)
			(xy 303.078479 -44.694566) (xy 303.096268 -44.758734) (xy 303.122564 -44.819911) (xy 303.156885 -44.876973)
			(xy 303.198601 -44.928874) (xy 303.202858 -44.933038) (xy 336.785706 -44.933038) (xy 336.785706 -44.805162)
			(xy 336.793735 -44.677538) (xy 336.809763 -44.55067) (xy 336.833724 -44.425058) (xy 336.865526 -44.3012)
			(xy 336.905042 -44.179582) (xy 336.952116 -44.060685) (xy 337.006563 -43.944979) (xy 337.068168 -43.83292)
			(xy 337.136688 -43.724951) (xy 337.211852 -43.621497) (xy 337.293363 -43.522966) (xy 337.3809 -43.429748)
			(xy 337.474118 -43.342211) (xy 337.572649 -43.2607) (xy 337.676103 -43.185536) (xy 337.784072 -43.117016)
			(xy 337.896131 -43.055411) (xy 338.011837 -43.000964) (xy 338.130734 -42.95389) (xy 338.252352 -42.914374)
			(xy 338.37621 -42.882572) (xy 338.501822 -42.858611) (xy 338.62869 -42.842583) (xy 338.756314 -42.834554)
			(xy 338.88419 -42.834554) (xy 339.011814 -42.842583) (xy 339.138682 -42.858611) (xy 339.264294 -42.882572)
			(xy 339.388152 -42.914374) (xy 339.50977 -42.95389) (xy 339.628667 -43.000964) (xy 339.744373 -43.055411)
			(xy 339.856432 -43.117016) (xy 339.964401 -43.185536) (xy 340.067855 -43.2607) (xy 340.166386 -43.342211)
			(xy 340.259604 -43.429748) (xy 340.347141 -43.522966) (xy 340.428652 -43.621497) (xy 340.503816 -43.724951)
			(xy 340.572336 -43.83292) (xy 340.633941 -43.944979) (xy 340.688388 -44.060685) (xy 340.735462 -44.179582)
			(xy 340.774978 -44.3012) (xy 340.80678 -44.425058) (xy 340.830741 -44.55067) (xy 340.846769 -44.677538)
			(xy 340.854798 -44.805162) (xy 340.8553 -44.8691) (xy 340.854798 -44.932982) (xy 348.217484 -44.932982)
			(xy 348.217484 -44.805218) (xy 348.225506 -44.677705) (xy 348.241519 -44.550948) (xy 348.26546 -44.425446)
			(xy 348.297234 -44.301696) (xy 348.336715 -44.180184) (xy 348.383748 -44.061392) (xy 348.438148 -43.945787)
			(xy 348.499699 -43.833826) (xy 348.568159 -43.725951) (xy 348.643257 -43.622587) (xy 348.724697 -43.524142)
			(xy 348.812158 -43.431006) (xy 348.905294 -43.343545) (xy 349.003739 -43.262105) (xy 349.107103 -43.187007)
			(xy 349.214978 -43.118547) (xy 349.326939 -43.056996) (xy 349.442544 -43.002596) (xy 349.561336 -42.955563)
			(xy 349.682848 -42.916082) (xy 349.806598 -42.884308) (xy 349.9321 -42.860367) (xy 350.058857 -42.844354)
			(xy 350.18637 -42.836332) (xy 350.314134 -42.836332) (xy 350.441647 -42.844354) (xy 350.568404 -42.860367)
			(xy 350.693906 -42.884308) (xy 350.817656 -42.916082) (xy 350.939168 -42.955563) (xy 351.05796 -43.002596)
			(xy 351.173565 -43.056996) (xy 351.285526 -43.118547) (xy 351.393401 -43.187007) (xy 351.496765 -43.262105)
			(xy 351.59521 -43.343545) (xy 351.688346 -43.431006) (xy 351.775807 -43.524142) (xy 351.857247 -43.622587)
			(xy 351.932345 -43.725951) (xy 352.000805 -43.833826) (xy 352.062356 -43.945787) (xy 352.116756 -44.061392)
			(xy 352.163789 -44.180184) (xy 352.20327 -44.301696) (xy 352.235044 -44.425446) (xy 352.258985 -44.550948)
			(xy 352.274998 -44.677705) (xy 352.28302 -44.805218) (xy 352.283522 -44.8691) (xy 352.28302 -44.932982)
			(xy 352.274998 -45.060495) (xy 352.258985 -45.187252) (xy 352.235044 -45.312754) (xy 352.20327 -45.436504)
			(xy 352.163789 -45.558016) (xy 352.116756 -45.676808) (xy 352.062356 -45.792413) (xy 352.000805 -45.904374)
			(xy 351.932345 -46.012249) (xy 351.857247 -46.115613) (xy 351.775807 -46.214058) (xy 351.688346 -46.307194)
			(xy 351.59521 -46.394655) (xy 351.496765 -46.476095) (xy 351.393401 -46.551193) (xy 351.285526 -46.619653)
			(xy 351.173565 -46.681204) (xy 351.05796 -46.735604) (xy 350.939168 -46.782637) (xy 350.817656 -46.822118)
			(xy 350.693906 -46.853892) (xy 350.568404 -46.877833) (xy 350.441647 -46.893846) (xy 350.314134 -46.901868)
			(xy 350.18637 -46.901868) (xy 350.058857 -46.893846) (xy 349.9321 -46.877833) (xy 349.806598 -46.853892)
			(xy 349.682848 -46.822118) (xy 349.561336 -46.782637) (xy 349.442544 -46.735604) (xy 349.326939 -46.681204)
			(xy 349.214978 -46.619653) (xy 349.107103 -46.551193) (xy 349.003739 -46.476095) (xy 348.905294 -46.394655)
			(xy 348.812158 -46.307194) (xy 348.724697 -46.214058) (xy 348.643257 -46.115613) (xy 348.568159 -46.012249)
			(xy 348.499699 -45.904374) (xy 348.438148 -45.792413) (xy 348.383748 -45.676808) (xy 348.336715 -45.558016)
			(xy 348.297234 -45.436504) (xy 348.26546 -45.312754) (xy 348.241519 -45.187252) (xy 348.225506 -45.060495)
			(xy 348.217484 -44.932982) (xy 340.854798 -44.932982) (xy 340.854798 -44.933038) (xy 340.846769 -45.060662)
			(xy 340.830741 -45.18753) (xy 340.80678 -45.313142) (xy 340.774978 -45.437) (xy 340.735462 -45.558618)
			(xy 340.688388 -45.677515) (xy 340.633941 -45.793221) (xy 340.572336 -45.90528) (xy 340.503816 -46.013249)
			(xy 340.428652 -46.116703) (xy 340.347141 -46.215234) (xy 340.259604 -46.308452) (xy 340.166386 -46.395989)
			(xy 340.067855 -46.4775) (xy 339.964401 -46.552664) (xy 339.856432 -46.621184) (xy 339.744373 -46.682789)
			(xy 339.628667 -46.737236) (xy 339.50977 -46.78431) (xy 339.388152 -46.823826) (xy 339.264294 -46.855628)
			(xy 339.138682 -46.879589) (xy 339.011814 -46.895617) (xy 338.88419 -46.903646) (xy 338.756314 -46.903646)
			(xy 338.62869 -46.895617) (xy 338.501822 -46.879589) (xy 338.37621 -46.855628) (xy 338.252352 -46.823826)
			(xy 338.130734 -46.78431) (xy 338.011837 -46.737236) (xy 337.896131 -46.682789) (xy 337.784072 -46.621184)
			(xy 337.676103 -46.552664) (xy 337.572649 -46.4775) (xy 337.474118 -46.395989) (xy 337.3809 -46.308452)
			(xy 337.293363 -46.215234) (xy 337.211852 -46.116703) (xy 337.136688 -46.013249) (xy 337.068168 -45.90528)
			(xy 337.006563 -45.793221) (xy 336.952116 -45.677515) (xy 336.905042 -45.558618) (xy 336.865526 -45.437)
			(xy 336.833724 -45.313142) (xy 336.809763 -45.18753) (xy 336.793735 -45.060662) (xy 336.785706 -44.933038)
			(xy 303.202858 -44.933038) (xy 303.222406 -44.952158) (xy 303.282384 -45.009613) (xy 303.39747 -45.129397)
			(xy 303.506758 -45.254493) (xy 303.610004 -45.38462) (xy 303.706976 -45.519488) (xy 303.797458 -45.658794)
			(xy 303.881246 -45.802225) (xy 303.958152 -45.94946) (xy 304.028005 -46.10017) (xy 304.090648 -46.254017)
			(xy 304.14594 -46.410656) (xy 304.193758 -46.569735) (xy 304.233994 -46.7309) (xy 304.266558 -46.893788)
			(xy 304.291378 -47.058034) (xy 304.308397 -47.223271) (xy 304.317578 -47.389128) (xy 304.3189 -47.555234)
			(xy 304.31236 -47.721216) (xy 304.297972 -47.886703) (xy 304.27577 -48.051324) (xy 304.245802 -48.21471)
			(xy 304.208136 -48.376494) (xy 304.162856 -48.536315) (xy 304.110064 -48.693814) (xy 304.049878 -48.848638)
			(xy 303.982433 -49.00044) (xy 303.907879 -49.148881) (xy 303.826385 -49.293628) (xy 303.738132 -49.434356)
			(xy 303.643319 -49.57075) (xy 303.542157 -49.702504) (xy 303.434873 -49.829323) (xy 303.378616 -49.890426)
			(xy 303.363538 -49.907371) (xy 303.339036 -49.945536) (xy 303.321697 -49.987445) (xy 303.312072 -50.031765)
			(xy 303.310467 -50.07709) (xy 303.316932 -50.121981) (xy 303.331262 -50.165011) (xy 303.353003 -50.204814)
			(xy 303.381463 -50.240126) (xy 303.41574 -50.269826) (xy 303.454743 -50.292971) (xy 303.497236 -50.308825)
			(xy 303.541867 -50.316884) (xy 303.564544 -50.3174) (xy 313.3344 -50.3174) (xy 315.9506 -47.7012)
			(xy 333.883 -47.7012) (xy 336.6516 -50.4698) (xy 352.552 -50.4698)
		)
		(stroke
			(width 0)
			(type solid)
		)
		(fill yes)
		(layer "In5.Cu")
		(net "GND")
	)
	(gr_line
		(start 0 -51.799998)
		(end 0 -1.999996)
		(stroke
			(width 1.016)
			(type default)
		)
		(layer "In6.Cu")
	)
	(gr_poly
		(pts
			(xy 94.713298 -51.81092) (xy 94.744102 -51.808459) (xy 94.804792 -51.796812) (xy 94.863545 -51.777656)
			(xy 94.919437 -51.751294) (xy 94.971588 -51.71814) (xy 95.019176 -51.678716) (xy 95.061453 -51.633644)
			(xy 95.097754 -51.583632) (xy 95.127505 -51.529468) (xy 95.15024 -51.472004) (xy 95.1656 -51.412147)
			(xy 95.173343 -51.350837) (xy 95.1738 -51.319938) (xy 95.1738 -50.8) (xy 95.174281 -50.746159) (xy 95.181963 -50.638751)
			(xy 95.197287 -50.532165) (xy 95.220177 -50.426943) (xy 95.250514 -50.323623) (xy 95.288146 -50.22273)
			(xy 95.332878 -50.124779) (xy 95.384485 -50.030268) (xy 95.442702 -49.93968) (xy 95.507234 -49.853476)
			(xy 95.577751 -49.772095) (xy 95.653894 -49.695952) (xy 95.735274 -49.625435) (xy 95.821478 -49.560903)
			(xy 95.912066 -49.502686) (xy 96.006577 -49.451079) (xy 96.104528 -49.406346) (xy 96.205421 -49.368715)
			(xy 96.308741 -49.338377) (xy 96.413963 -49.315488) (xy 96.520549 -49.300163) (xy 96.627957 -49.292481)
			(xy 96.681798 -49.292002) (xy 97.01911 -49.292002) (xy 97.06991 -49.290986) (xy 112.06988 -49.290986)
			(xy 112.123758 -49.291455) (xy 112.23124 -49.299141) (xy 112.3379 -49.314475) (xy 112.443194 -49.337379)
			(xy 112.546586 -49.367737) (xy 112.647549 -49.405393) (xy 112.745568 -49.450155) (xy 112.840144 -49.501797)
			(xy 112.930795 -49.560053) (xy 113.017059 -49.624629) (xy 113.098497 -49.695194) (xy 113.174693 -49.771389)
			(xy 113.245259 -49.852825) (xy 113.309835 -49.939088) (xy 113.368093 -50.029738) (xy 113.419736 -50.124314)
			(xy 113.4645 -50.222332) (xy 113.502157 -50.323295) (xy 113.532516 -50.426686) (xy 113.555421 -50.53198)
			(xy 113.570757 -50.63864) (xy 113.578444 -50.746122) (xy 113.578894 -50.8) (xy 113.578894 -51.319938)
			(xy 113.579422 -51.352083) (xy 113.587818 -51.415823) (xy 113.604461 -51.477922) (xy 113.629066 -51.537317)
			(xy 113.661213 -51.592993) (xy 113.700352 -51.643997) (xy 113.745813 -51.689457) (xy 113.796818 -51.728594)
			(xy 113.852495 -51.76074) (xy 113.911891 -51.785344) (xy 113.973991 -51.801985) (xy 114.037731 -51.810379)
			(xy 114.069876 -51.81092) (xy 132.990082 -51.81092) (xy 133.02223 -51.810396) (xy 133.085976 -51.802006)
			(xy 133.148082 -51.785368) (xy 133.207484 -51.760766) (xy 133.263168 -51.728621) (xy 133.314179 -51.689483)
			(xy 133.359646 -51.644021) (xy 133.398789 -51.593014) (xy 133.430941 -51.537335) (xy 133.45555 -51.477935)
			(xy 133.472195 -51.415831) (xy 133.480592 -51.352086) (xy 133.481064 -51.319938) (xy 133.481064 -50.8)
			(xy 133.481545 -50.746122) (xy 133.489232 -50.638641) (xy 133.504567 -50.531983) (xy 133.527472 -50.42669)
			(xy 133.55783 -50.323299) (xy 133.595486 -50.222338) (xy 133.640249 -50.12432) (xy 133.69189 -50.029745)
			(xy 133.750147 -49.939095) (xy 133.814721 -49.852832) (xy 133.885286 -49.771396) (xy 133.96148 -49.695201)
			(xy 134.042915 -49.624635) (xy 134.129177 -49.560059) (xy 134.219826 -49.501801) (xy 134.3144 -49.450159)
			(xy 134.412418 -49.405394) (xy 134.513379 -49.367737) (xy 134.616769 -49.337377) (xy 134.722061 -49.314471)
			(xy 134.82872 -49.299134) (xy 134.9362 -49.291446) (xy 134.990078 -49.290986) (xy 149.990048 -49.290986)
			(xy 150.043924 -49.291468) (xy 150.151402 -49.299159) (xy 150.258058 -49.314497) (xy 150.363347 -49.337404)
			(xy 150.466734 -49.367764) (xy 150.567692 -49.405422) (xy 150.665706 -49.450187) (xy 150.760277 -49.501829)
			(xy 150.850923 -49.560086) (xy 150.937183 -49.624662) (xy 151.018615 -49.695226) (xy 151.094807 -49.77142)
			(xy 151.165369 -49.852855) (xy 151.229941 -49.939116) (xy 151.288196 -50.029764) (xy 151.339835 -50.124337)
			(xy 151.384596 -50.222352) (xy 151.422251 -50.323311) (xy 151.452608 -50.426699) (xy 151.475512 -50.53199)
			(xy 151.490846 -50.638646) (xy 151.498533 -50.746124) (xy 151.499062 -50.8) (xy 151.499062 -51.319938)
			(xy 151.499567 -51.352083) (xy 151.507964 -51.415823) (xy 151.524608 -51.477921) (xy 151.549216 -51.537315)
			(xy 151.581365 -51.592989) (xy 151.620507 -51.643991) (xy 151.665971 -51.689447) (xy 151.716979 -51.72858)
			(xy 151.772659 -51.76072) (xy 151.832057 -51.785318) (xy 151.894158 -51.801952) (xy 151.957899 -51.810338)
			(xy 151.990044 -51.81092) (xy 158.939992 -51.81092) (xy 159.173926 -51.764438) (xy 159.330136 -51.660044)
			(xy 159.4358 -51.501802) (xy 159.485076 -51.26609) (xy 159.596582 -50.787554) (xy 159.92475 -50.30724)
			(xy 160.414462 -49.984152) (xy 160.940496 -49.881028) (xy 203.039472 -49.881028) (xy 203.565506 -49.984152)
			(xy 204.055218 -50.30724) (xy 204.383386 -50.787554) (xy 204.494892 -51.26609) (xy 204.544168 -51.501802)
			(xy 204.649832 -51.660044) (xy 204.806042 -51.764438) (xy 205.039976 -51.81092) (xy 316.06998 -51.81092)
			(xy 316.102128 -51.810396) (xy 316.165874 -51.802006) (xy 316.22798 -51.785368) (xy 316.287383 -51.760766)
			(xy 316.343067 -51.728621) (xy 316.394078 -51.689483) (xy 316.439545 -51.644022) (xy 316.478689 -51.593015)
			(xy 316.510841 -51.537335) (xy 316.53545 -51.477935) (xy 316.552095 -51.415831) (xy 316.560492 -51.352086)
			(xy 316.560962 -51.319938) (xy 316.560962 -50.8) (xy 316.561443 -50.746122) (xy 316.56913 -50.638641)
			(xy 316.584465 -50.531983) (xy 316.60737 -50.42669) (xy 316.637728 -50.323299) (xy 316.675384 -50.222338)
			(xy 316.720147 -50.12432) (xy 316.771788 -50.029745) (xy 316.830044 -49.939095) (xy 316.894619 -49.852832)
			(xy 316.965184 -49.771395) (xy 317.041377 -49.6952) (xy 317.122813 -49.624634) (xy 317.209075 -49.560058)
			(xy 317.299724 -49.5018) (xy 317.394298 -49.450158) (xy 317.492315 -49.405393) (xy 317.593276 -49.367735)
			(xy 317.696667 -49.337376) (xy 317.801959 -49.314469) (xy 317.908618 -49.299132) (xy 318.016098 -49.291444)
			(xy 318.069976 -49.290986) (xy 333.069946 -49.290986) (xy 333.123822 -49.291468) (xy 333.2313 -49.299159)
			(xy 333.337956 -49.314496) (xy 333.443245 -49.337404) (xy 333.546633 -49.367764) (xy 333.647591 -49.405422)
			(xy 333.745605 -49.450186) (xy 333.840176 -49.501828) (xy 333.930822 -49.560086) (xy 334.017082 -49.624661)
			(xy 334.098515 -49.695225) (xy 334.174706 -49.771419) (xy 334.245268 -49.852854) (xy 334.309841 -49.939115)
			(xy 334.368095 -50.029763) (xy 334.419735 -50.124336) (xy 334.464496 -50.222352) (xy 334.502151 -50.323311)
			(xy 334.532508 -50.426699) (xy 334.555412 -50.531989) (xy 334.570746 -50.638645) (xy 334.578433 -50.746124)
			(xy 334.57896 -50.8) (xy 334.57896 -51.319938) (xy 334.579465 -51.352083) (xy 334.587862 -51.415823)
			(xy 334.604506 -51.477921) (xy 334.629114 -51.537315) (xy 334.661263 -51.59299) (xy 334.700405 -51.643992)
			(xy 334.745869 -51.689448) (xy 334.796877 -51.728581) (xy 334.852556 -51.760722) (xy 334.911955 -51.785319)
			(xy 334.974056 -51.801954) (xy 335.037797 -51.81034) (xy 335.069942 -51.81092) (xy 353.989894 -51.81092)
			(xy 354.022041 -51.810395) (xy 354.085786 -51.802004) (xy 354.147891 -51.785365) (xy 354.207292 -51.760762)
			(xy 354.262974 -51.728616) (xy 354.313984 -51.689478) (xy 354.359449 -51.644017) (xy 354.398592 -51.593011)
			(xy 354.430742 -51.537331) (xy 354.455351 -51.477932) (xy 354.471995 -51.415829) (xy 354.480392 -51.352085)
			(xy 354.480876 -51.319938) (xy 354.480876 -50.8) (xy 354.481357 -50.746122) (xy 354.489044 -50.638642)
			(xy 354.504379 -50.531984) (xy 354.527284 -50.426691) (xy 354.557642 -50.323301) (xy 354.595298 -50.22234)
			(xy 354.640061 -50.124322) (xy 354.691702 -50.029748) (xy 354.749959 -49.939098) (xy 354.814534 -49.852836)
			(xy 354.885098 -49.7714) (xy 354.961292 -49.695205) (xy 355.042728 -49.62464) (xy 355.12899 -49.560065)
			(xy 355.219639 -49.501808) (xy 355.314213 -49.450166) (xy 355.412231 -49.405402) (xy 355.513191 -49.367745)
			(xy 355.616581 -49.337386) (xy 355.721874 -49.314481) (xy 355.828532 -49.299145) (xy 355.936012 -49.291457)
			(xy 355.98989 -49.290986) (xy 370.990114 -49.290986) (xy 371.043991 -49.291467) (xy 371.151471 -49.299155)
			(xy 371.258128 -49.314491) (xy 371.363419 -49.337397) (xy 371.466808 -49.367756) (xy 371.567768 -49.405412)
			(xy 371.665785 -49.450176) (xy 371.760358 -49.501818) (xy 371.851006 -49.560074) (xy 371.937268 -49.624649)
			(xy 372.018702 -49.695214) (xy 372.094896 -49.771408) (xy 372.165459 -49.852843) (xy 372.230034 -49.939105)
			(xy 372.28829 -50.029754) (xy 372.33993 -50.124328) (xy 372.384693 -50.222345) (xy 372.422349 -50.323305)
			(xy 372.452707 -50.426694) (xy 372.475611 -50.531986) (xy 372.490946 -50.638643) (xy 372.498633 -50.746123)
			(xy 372.499128 -50.8) (xy 372.499128 -51.319938) (xy 372.499656 -51.352082) (xy 372.508052 -51.41582)
			(xy 372.524696 -51.477918) (xy 372.549302 -51.537311) (xy 372.581449 -51.592985) (xy 372.620588 -51.643986)
			(xy 372.66605 -51.689443) (xy 372.717055 -51.728577) (xy 372.772732 -51.76072) (xy 372.832128 -51.78532)
			(xy 372.894227 -51.801957) (xy 372.957966 -51.810347) (xy 372.99011 -51.81092) (xy 379.940058 -51.81092)
			(xy 380.173992 -51.764438) (xy 380.330202 -51.660044) (xy 380.435866 -51.501802) (xy 380.485142 -51.26609)
			(xy 380.596648 -50.787554) (xy 380.924816 -50.30724) (xy 381.414528 -49.984152) (xy 381.940562 -49.881028)
			(xy 425.61002 -49.881028) (xy 425.665789 -49.880506) (xy 425.777016 -49.872169) (xy 425.887308 -49.855544)
			(xy 425.99605 -49.830724) (xy 426.102633 -49.797847) (xy 426.206461 -49.757097) (xy 426.306953 -49.708702)
			(xy 426.403549 -49.652933) (xy 426.495706 -49.590102) (xy 426.582911 -49.520559) (xy 426.664675 -49.444695)
			(xy 426.740541 -49.362932) (xy 426.810085 -49.275729) (xy 426.872918 -49.183572) (xy 426.928689 -49.086978)
			(xy 426.977086 -48.986486) (xy 427.017838 -48.882659) (xy 427.050717 -48.776077) (xy 427.075539 -48.667336)
			(xy 427.092166 -48.557043) (xy 427.100505 -48.445817) (xy 427.101 -48.390048) (xy 427.101 -42.13606)
			(xy 427.100452 -42.119415) (xy 427.091827 -42.087262) (xy 427.075176 -42.058435) (xy 427.051633 -42.034899)
			(xy 427.022801 -42.018257) (xy 426.990645 -42.009643) (xy 426.974 -42.00906) (xy 425.509944 -42.00906)
			(xy 425.465908 -42.008595) (xy 425.37817 -42.000921) (xy 425.291435 -41.985628) (xy 425.206363 -41.962832)
			(xy 425.123602 -41.932707) (xy 425.043783 -41.895482) (xy 424.967512 -41.851441) (xy 424.895371 -41.800918)
			(xy 424.827909 -41.7443) (xy 424.76564 -41.682015) (xy 424.709037 -41.61454) (xy 424.658531 -41.542387)
			(xy 424.614508 -41.466106) (xy 424.577302 -41.386278) (xy 424.547196 -41.30351) (xy 424.52442 -41.218433)
			(xy 424.509148 -41.131694) (xy 424.501495 -41.043955) (xy 424.501056 -40.999918) (xy 424.501056 -31.999936)
			(xy 424.501521 -31.955907) (xy 424.509193 -31.868184) (xy 424.524482 -31.781464) (xy 424.547271 -31.696406)
			(xy 424.577387 -31.613658) (xy 424.614601 -31.53385) (xy 424.658629 -31.457589) (xy 424.709137 -31.385456)
			(xy 424.765739 -31.318) (xy 424.828006 -31.255734) (xy 424.895462 -31.199132) (xy 424.967596 -31.148625)
			(xy 425.043857 -31.104597) (xy 425.123665 -31.067384) (xy 425.206413 -31.037269) (xy 425.291471 -31.01448)
			(xy 425.378192 -30.999192) (xy 425.465915 -30.991521) (xy 425.509944 -30.991048) (xy 426.974 -30.991048)
			(xy 426.990651 -30.990505) (xy 427.022818 -30.981888) (xy 427.05166 -30.965241) (xy 427.075212 -30.941698)
			(xy 427.091869 -30.912862) (xy 427.100499 -30.880698) (xy 427.101 -30.864048) (xy 427.101 -10.999978)
			(xy 427.101481 -10.95595) (xy 427.109157 -10.86823) (xy 427.12445 -10.781513) (xy 427.147241 -10.696459)
			(xy 427.177359 -10.613714) (xy 427.214574 -10.53391) (xy 427.258602 -10.457652) (xy 427.309109 -10.385522)
			(xy 427.365711 -10.318068) (xy 427.427975 -10.255804) (xy 427.49543 -10.199203) (xy 427.56756 -10.148697)
			(xy 427.643819 -10.104669) (xy 427.723624 -10.067455) (xy 427.806368 -10.037338) (xy 427.891423 -10.014547)
			(xy 427.97814 -9.999256) (xy 428.06586 -9.991581) (xy 428.109888 -9.99109) (xy 428.173896 -9.99109)
			(xy 428.190551 -9.990596) (xy 428.222725 -9.981975) (xy 428.251572 -9.96532) (xy 428.275124 -9.941767)
			(xy 428.291778 -9.912919) (xy 428.300397 -9.880745) (xy 428.300896 -9.86409) (xy 428.300896 -1.999996)
			(xy 428.300374 -1.944227) (xy 428.292039 -1.833) (xy 428.275415 -1.722708) (xy 428.250595 -1.613966)
			(xy 428.217719 -1.507383) (xy 428.176969 -1.403555) (xy 428.128575 -1.303063) (xy 428.072806 -1.206468)
			(xy 428.009974 -1.11431) (xy 427.940431 -1.027106) (xy 427.864566 -0.945342) (xy 427.782803 -0.869476)
			(xy 427.6956 -0.799933) (xy 427.603443 -0.737101) (xy 427.506848 -0.681331) (xy 427.406356 -0.632936)
			(xy 427.302528 -0.592185) (xy 427.195945 -0.559308) (xy 427.087204 -0.534487) (xy 426.976911 -0.517862)
			(xy 426.865685 -0.509526) (xy 426.809916 -0.509016) (xy 1.999996 -0.509016) (xy 1.944227 -0.509538)
			(xy 1.833001 -0.517873) (xy 1.722709 -0.534497) (xy 1.613967 -0.559317) (xy 1.507385 -0.592194) (xy 1.403557 -0.632943)
			(xy 1.303065 -0.681338) (xy 1.20647 -0.737107) (xy 1.114313 -0.799938) (xy 1.027109 -0.869481) (xy 0.945346 -0.945346)
			(xy 0.869481 -1.027109) (xy 0.799938 -1.114313) (xy 0.737107 -1.20647) (xy 0.681338 -1.303065) (xy 0.632943 -1.403557)
			(xy 0.592194 -1.507385) (xy 0.559317 -1.613967) (xy 0.534497 -1.722709) (xy 0.517873 -1.833001) (xy 0.509538 -1.944227)
			(xy 0.509016 -1.999996) (xy 0.509016 -4.700016) (xy 2.187458 -4.700016) (xy 2.191444 -4.564291) (xy 2.203388 -4.429035)
			(xy 2.22325 -4.294712) (xy 2.250961 -4.161787) (xy 2.286425 -4.030717) (xy 2.32952 -3.901954) (xy 2.380098 -3.775942)
			(xy 2.437983 -3.653116) (xy 2.502978 -3.533899) (xy 2.574857 -3.418701) (xy 2.653372 -3.307921) (xy 2.738254 -3.201939)
			(xy 2.829209 -3.101122) (xy 2.925925 -3.005816) (xy 3.028066 -2.91635) (xy 3.135283 -2.833034) (xy 3.247204 -2.756153)
			(xy 3.363444 -2.685972) (xy 3.483603 -2.622735) (xy 3.607266 -2.566659) (xy 3.734006 -2.517936) (xy 3.863388 -2.476736)
			(xy 3.994964 -2.4432) (xy 4.128282 -2.417444) (xy 4.262882 -2.399556) (xy 4.398299 -2.389598) (xy 4.534067 -2.387605)
			(xy 4.669719 -2.393583) (xy 4.804786 -2.407512) (xy 4.938802 -2.429343) (xy 5.071306 -2.459002) (xy 5.201842 -2.496387)
			(xy 5.329958 -2.541367) (xy 5.455213 -2.593789) (xy 5.577177 -2.653472) (xy 5.695427 -2.720209) (xy 5.809557 -2.793771)
			(xy 5.919173 -2.873905) (xy 6.023897 -2.960333) (xy 6.123369 -3.052759) (xy 6.217244 -3.150863) (xy 6.305201 -3.254307)
			(xy 6.386935 -3.362735) (xy 6.462165 -3.475773) (xy 6.530631 -3.59303) (xy 6.592097 -3.714104) (xy 6.646352 -3.838577)
			(xy 6.693209 -3.966019) (xy 6.732505 -4.095992) (xy 6.764106 -4.228046) (xy 6.787903 -4.361728) (xy 6.803813 -4.496575)
			(xy 6.811782 -4.632124) (xy 6.81228 -4.700016) (xy 6.811782 -4.767908) (xy 6.803813 -4.903457) (xy 6.787903 -5.038304)
			(xy 6.764106 -5.171986) (xy 6.732505 -5.30404) (xy 6.693209 -5.434013) (xy 6.646352 -5.561455) (xy 6.592097 -5.685928)
			(xy 6.540201 -5.788152) (xy 101.226874 -5.788152) (xy 101.226874 -5.367528) (xy 101.524562 -5.06984)
			(xy 103.215186 -5.06984) (xy 103.512874 -5.367528) (xy 103.512874 -5.437632) (xy 132.4102 -5.437632)
			(xy 132.4102 -3.747008) (xy 132.707888 -3.44932) (xy 133.128512 -3.44932) (xy 133.4262 -3.747008)
			(xy 133.4262 -5.437632) (xy 133.128512 -5.73532) (xy 132.707888 -5.73532) (xy 132.4102 -5.437632)
			(xy 103.512874 -5.437632) (xy 103.512874 -5.574538) (xy 127.80518 -5.574538) (xy 129.25298 -5.574538)
			(xy 129.25298 -5.925312) (xy 143.947134 -5.925312) (xy 143.947134 -5.504688) (xy 144.244822 -5.207)
			(xy 145.935446 -5.207) (xy 146.145758 -5.417312) (xy 164.2364 -5.417312) (xy 164.2364 -2.699512)
			(xy 165.5318 -2.699512) (xy 165.5318 -4.16306) (xy 166.236396 -4.16306) (xy 166.236396 -1.345184)
			(xy 167.531796 -1.345184) (xy 167.531796 -4.21386) (xy 166.261796 -4.21386) (xy 166.261796 -4.16306)
			(xy 166.236396 -4.16306) (xy 165.5318 -4.16306) (xy 165.5318 -5.417312) (xy 172.236384 -5.417312)
			(xy 172.236384 -2.699512) (xy 173.531784 -2.699512) (xy 173.531784 -4.16306) (xy 174.23638 -4.16306)
			(xy 174.23638 -1.345184) (xy 175.53178 -1.345184) (xy 175.53178 -4.21386) (xy 174.26178 -4.21386)
			(xy 174.26178 -4.16306) (xy 174.23638 -4.16306) (xy 173.531784 -4.16306) (xy 173.531784 -5.468112)
			(xy 172.261784 -5.468112) (xy 172.261784 -5.417312) (xy 172.236384 -5.417312) (xy 165.5318 -5.417312)
			(xy 165.5318 -5.468112) (xy 164.2618 -5.468112) (xy 164.2618 -5.417312) (xy 164.2364 -5.417312) (xy 146.145758 -5.417312)
			(xy 146.233134 -5.504688) (xy 146.233134 -5.925312) (xy 145.935446 -6.223) (xy 144.244822 -6.223)
			(xy 143.947134 -5.925312) (xy 129.25298 -5.925312) (xy 129.25298 -8.393938) (xy 127.80518 -8.393938)
			(xy 127.80518 -5.574538) (xy 103.512874 -5.574538) (xy 103.512874 -5.788152) (xy 103.215186 -6.08584)
			(xy 101.524562 -6.08584) (xy 101.226874 -5.788152) (xy 6.540201 -5.788152) (xy 6.530631 -5.807002)
			(xy 6.462165 -5.924259) (xy 6.386935 -6.037297) (xy 6.305201 -6.145725) (xy 6.217244 -6.249169) (xy 6.123369 -6.347273)
			(xy 6.023897 -6.439699) (xy 5.919173 -6.526127) (xy 5.809557 -6.606261) (xy 5.695427 -6.679823) (xy 5.577177 -6.74656)
			(xy 5.455213 -6.806243) (xy 5.329958 -6.858665) (xy 5.201842 -6.903645) (xy 5.071306 -6.94103) (xy 4.938802 -6.970689)
			(xy 4.804786 -6.99252) (xy 4.669719 -7.006449) (xy 4.534067 -7.012427) (xy 4.398299 -7.010434) (xy 4.262882 -7.000476)
			(xy 4.128282 -6.982588) (xy 3.994964 -6.956832) (xy 3.863388 -6.923296) (xy 3.734006 -6.882096) (xy 3.607266 -6.833373)
			(xy 3.483603 -6.777297) (xy 3.363444 -6.71406) (xy 3.247204 -6.643879) (xy 3.135283 -6.566998) (xy 3.028066 -6.483682)
			(xy 2.925925 -6.394216) (xy 2.829209 -6.29891) (xy 2.738254 -6.198093) (xy 2.653372 -6.092111) (xy 2.574857 -5.981331)
			(xy 2.502978 -5.866133) (xy 2.437983 -5.746916) (xy 2.380098 -5.62409) (xy 2.32952 -5.498078) (xy 2.286425 -5.369315)
			(xy 2.250961 -5.238245) (xy 2.22325 -5.10532) (xy 2.203388 -4.970997) (xy 2.191444 -4.835741) (xy 2.187458 -4.700016)
			(xy 0.509016 -4.700016) (xy 0.509016 -7.500112) (xy 9.403341 -7.500112) (xy 9.407346 -7.412204) (xy 9.419329 -7.325024)
			(xy 9.439189 -7.239295) (xy 9.466764 -7.155727) (xy 9.501823 -7.075013) (xy 9.544076 -6.997821) (xy 9.593174 -6.924792)
			(xy 9.64871 -6.85653) (xy 9.710222 -6.7936) (xy 9.777203 -6.736526) (xy 9.849096 -6.685778) (xy 9.925305 -6.641778)
			(xy 10.0052 -6.604891) (xy 10.088119 -6.575422) (xy 10.173374 -6.553615) (xy 10.260258 -6.539651)
			(xy 10.348052 -6.533645) (xy 10.436029 -6.535649) (xy 10.523459 -6.545644) (xy 10.609618 -6.563548)
			(xy 10.693792 -6.589212) (xy 10.775283 -6.622425) (xy 10.853417 -6.662911) (xy 10.927545 -6.710333)
			(xy 10.997053 -6.7643) (xy 11.061367 -6.824365) (xy 11.106105 -6.87451) (xy 117.8052 -6.87451) (xy 119.253 -6.87451)
			(xy 119.253 -9.0678) (xy 139.3698 -9.0678) (xy 141.1986 -9.0678) (xy 144.169892 -9.0678) (xy 145.998692 -9.0678)
			(xy 145.998692 -9.617456) (xy 164.2364 -9.617456) (xy 164.2364 -6.899656) (xy 165.5318 -6.899656)
			(xy 165.5318 -8.363204) (xy 166.236396 -8.363204) (xy 166.236396 -5.545328) (xy 167.531796 -5.545328)
			(xy 167.531796 -8.414004) (xy 166.261796 -8.414004) (xy 166.261796 -8.363204) (xy 166.236396 -8.363204)
			(xy 165.5318 -8.363204) (xy 165.5318 -9.617456) (xy 168.236392 -9.617456) (xy 168.236392 -6.899656)
			(xy 169.531792 -6.899656) (xy 169.531792 -8.363204) (xy 170.236388 -8.363204) (xy 170.236388 -5.545328)
			(xy 171.531788 -5.545328) (xy 171.531788 -8.414004) (xy 170.261788 -8.414004) (xy 170.261788 -8.363204)
			(xy 170.236388 -8.363204) (xy 169.531792 -8.363204) (xy 169.531792 -9.617456) (xy 172.236384 -9.617456)
			(xy 172.236384 -6.899656) (xy 173.531784 -6.899656) (xy 173.531784 -8.363204) (xy 174.23638 -8.363204)
			(xy 174.23638 -5.545328) (xy 175.53178 -5.545328) (xy 175.53178 -8.414004) (xy 174.26178 -8.414004)
			(xy 174.26178 -8.363204) (xy 174.23638 -8.363204) (xy 173.531784 -8.363204) (xy 173.531784 -9.668256)
			(xy 172.261784 -9.668256) (xy 172.261784 -9.617456) (xy 172.236384 -9.617456) (xy 169.531792 -9.617456)
			(xy 169.531792 -9.668256) (xy 168.261792 -9.668256) (xy 168.261792 -9.617456) (xy 168.236392 -9.617456)
			(xy 165.5318 -9.617456) (xy 165.5318 -9.668256) (xy 164.2618 -9.668256) (xy 164.2618 -9.617456) (xy 164.2364 -9.617456)
			(xy 145.998692 -9.617456) (xy 145.998692 -11.5062) (xy 144.169892 -11.5062) (xy 144.169892 -9.0678)
			(xy 141.1986 -9.0678) (xy 141.1986 -11.5062) (xy 139.3698 -11.5062) (xy 139.3698 -9.0678) (xy 119.253 -9.0678)
			(xy 119.253 -9.69391) (xy 117.8052 -9.69391) (xy 117.8052 -6.87451) (xy 11.106105 -6.87451) (xy 11.119951 -6.890029)
			(xy 11.172322 -6.960748) (xy 11.218045 -7.035936) (xy 11.256742 -7.114971) (xy 11.288091 -7.197197)
			(xy 11.311833 -7.281933) (xy 11.327771 -7.368477) (xy 11.335773 -7.456112) (xy 11.336274 -7.500112)
			(xy 11.335773 -7.544112) (xy 11.327771 -7.631747) (xy 11.311833 -7.718291) (xy 11.288091 -7.803027)
			(xy 11.256742 -7.885253) (xy 11.218045 -7.964288) (xy 11.172322 -8.039476) (xy 11.119951 -8.110195)
			(xy 11.061367 -8.175859) (xy 10.997053 -8.235924) (xy 10.927545 -8.289891) (xy 10.853417 -8.337313)
			(xy 10.775283 -8.377799) (xy 10.693792 -8.411012) (xy 10.609618 -8.436676) (xy 10.523459 -8.45458)
			(xy 10.436029 -8.464575) (xy 10.348052 -8.466579) (xy 10.260258 -8.460573) (xy 10.173374 -8.446609)
			(xy 10.088119 -8.424802) (xy 10.0052 -8.395333) (xy 9.925305 -8.358446) (xy 9.849096 -8.314446) (xy 9.777203 -8.263698)
			(xy 9.710222 -8.206624) (xy 9.64871 -8.143694) (xy 9.593174 -8.075432) (xy 9.544076 -8.002403) (xy 9.501823 -7.925211)
			(xy 9.466764 -7.844497) (xy 9.439189 -7.760929) (xy 9.419329 -7.6752) (xy 9.407346 -7.58802) (xy 9.403341 -7.500112)
			(xy 0.509016 -7.500112) (xy 0.509016 -9.554177) (xy 87.833696 -9.554177) (xy 87.833696 -9.445531)
			(xy 87.841627 -9.337174) (xy 87.857446 -9.229685) (xy 87.881069 -9.123638) (xy 87.91237 -9.019598)
			(xy 87.951182 -8.91812) (xy 87.997297 -8.819746) (xy 88.050471 -8.725001) (xy 88.110419 -8.63439)
			(xy 88.176821 -8.548396) (xy 88.249323 -8.467479) (xy 88.327538 -8.392071) (xy 88.411049 -8.322572)
			(xy 88.49941 -8.259355) (xy 88.59215 -8.202757) (xy 88.688774 -8.153079) (xy 88.788766 -8.110587)
			(xy 88.891594 -8.075507) (xy 88.996708 -8.048027) (xy 89.103547 -8.028292) (xy 89.211542 -8.016409)
			(xy 89.320116 -8.012442) (xy 89.42869 -8.016409) (xy 89.536685 -8.028292) (xy 89.643524 -8.048027)
			(xy 89.748638 -8.075507) (xy 89.851466 -8.110587) (xy 89.951458 -8.153079) (xy 90.048082 -8.202757)
			(xy 90.140822 -8.259355) (xy 90.229183 -8.322572) (xy 90.312694 -8.392071) (xy 90.390909 -8.467479)
			(xy 90.463411 -8.548396) (xy 90.529813 -8.63439) (xy 90.589761 -8.725001) (xy 90.642935 -8.819746)
			(xy 90.68905 -8.91812) (xy 90.727862 -9.019598) (xy 90.742287 -9.067546) (xy 101.449632 -9.067546)
			(xy 103.278432 -9.067546) (xy 106.249724 -9.067546) (xy 108.078524 -9.067546) (xy 108.078524 -9.405112)
			(xy 113.25352 -9.405112) (xy 113.25352 -8.984488) (xy 113.551208 -8.6868) (xy 115.394232 -8.6868)
			(xy 115.69192 -8.984488) (xy 115.69192 -9.405112) (xy 115.394232 -9.7028) (xy 113.551208 -9.7028)
			(xy 113.25352 -9.405112) (xy 108.078524 -9.405112) (xy 108.078524 -9.774428) (xy 127.80518 -9.774428)
			(xy 129.25298 -9.774428) (xy 129.25298 -12.593828) (xy 127.80518 -12.593828) (xy 127.80518 -9.774428)
			(xy 108.078524 -9.774428) (xy 108.078524 -11.0744) (xy 117.8052 -11.0744) (xy 119.253 -11.0744) (xy 119.253 -13.8938)
			(xy 117.8052 -13.8938) (xy 117.8052 -11.0744) (xy 108.078524 -11.0744) (xy 108.078524 -11.505946)
			(xy 106.249724 -11.505946) (xy 106.249724 -9.067546) (xy 103.278432 -9.067546) (xy 103.278432 -11.505946)
			(xy 101.449632 -11.505946) (xy 101.449632 -9.067546) (xy 90.742287 -9.067546) (xy 90.759163 -9.123638)
			(xy 90.782786 -9.229685) (xy 90.798605 -9.337174) (xy 90.806536 -9.445531) (xy 90.807032 -9.499854)
			(xy 90.806536 -9.554177) (xy 90.798605 -9.662534) (xy 90.782786 -9.770023) (xy 90.759163 -9.87607)
			(xy 90.727862 -9.98011) (xy 90.68905 -10.081588) (xy 90.642935 -10.179962) (xy 90.589761 -10.274707)
			(xy 90.529813 -10.365318) (xy 90.463411 -10.451312) (xy 90.390909 -10.532229) (xy 90.312694 -10.607637)
			(xy 90.229183 -10.677136) (xy 90.140822 -10.740353) (xy 90.048082 -10.796951) (xy 89.951458 -10.846629)
			(xy 89.851466 -10.889121) (xy 89.748638 -10.924201) (xy 89.643524 -10.951681) (xy 89.536685 -10.971416)
			(xy 89.42869 -10.983299) (xy 89.320116 -10.987267) (xy 89.211542 -10.983299) (xy 89.103547 -10.971416)
			(xy 88.996708 -10.951681) (xy 88.891594 -10.924201) (xy 88.788766 -10.889121) (xy 88.688774 -10.846629)
			(xy 88.59215 -10.796951) (xy 88.49941 -10.740353) (xy 88.411049 -10.677136) (xy 88.327538 -10.607637)
			(xy 88.249323 -10.532229) (xy 88.176821 -10.451312) (xy 88.110419 -10.365318) (xy 88.050471 -10.274707)
			(xy 87.997297 -10.179962) (xy 87.951182 -10.081588) (xy 87.91237 -9.98011) (xy 87.881069 -9.87607)
			(xy 87.857446 -9.770023) (xy 87.841627 -9.662534) (xy 87.833696 -9.554177) (xy 0.509016 -9.554177)
			(xy 0.509016 -14.439005) (xy 98.549955 -14.439005) (xy 98.549955 -14.340719) (xy 98.557864 -14.242752)
			(xy 98.57363 -14.145739) (xy 98.597151 -14.05031) (xy 98.628275 -13.957082) (xy 98.6668 -13.866661)
			(xy 98.712475 -13.779634) (xy 98.765006 -13.696563) (xy 98.82405 -13.61799) (xy 98.889225 -13.544422)
			(xy 98.960109 -13.476337) (xy 99.036242 -13.414176) (xy 99.117129 -13.358344) (xy 99.202247 -13.309201)
			(xy 99.291044 -13.267067) (xy 99.382942 -13.232214) (xy 99.477348 -13.204869) (xy 99.573647 -13.18521)
			(xy 99.671216 -13.173363) (xy 99.769422 -13.169405) (xy 99.867628 -13.173363) (xy 99.965197 -13.18521)
			(xy 100.061496 -13.204869) (xy 100.155902 -13.232214) (xy 100.2478 -13.267067) (xy 100.336597 -13.309201)
			(xy 100.421715 -13.358344) (xy 100.502602 -13.414176) (xy 100.578735 -13.476337) (xy 100.649619 -13.544422)
			(xy 100.714794 -13.61799) (xy 100.773838 -13.696563) (xy 100.826369 -13.779634) (xy 100.872044 -13.866661)
			(xy 100.910569 -13.957082) (xy 100.941693 -14.05031) (xy 100.965214 -14.145739) (xy 100.98098 -14.242752)
			(xy 100.988889 -14.340719) (xy 100.989384 -14.389862) (xy 100.988889 -14.439005) (xy 100.98098 -14.536972)
			(xy 100.965214 -14.633985) (xy 100.941693 -14.729414) (xy 100.936335 -14.745462) (xy 108.48086 -14.745462)
			(xy 108.48086 -14.059662) (xy 108.481364 -14.017301) (xy 108.489417 -13.932964) (xy 108.505451 -13.849774)
			(xy 108.529319 -13.768484) (xy 108.560807 -13.689832) (xy 108.599629 -13.614529) (xy 108.645432 -13.543257)
			(xy 108.697803 -13.476661) (xy 108.756268 -13.415346) (xy 108.820296 -13.359865) (xy 108.889308 -13.310722)
			(xy 108.962678 -13.268362) (xy 109.039743 -13.233167) (xy 109.119805 -13.205458) (xy 109.202138 -13.185484)
			(xy 109.285997 -13.173427) (xy 109.370622 -13.169396) (xy 109.455247 -13.173427) (xy 109.539106 -13.185484)
			(xy 109.621439 -13.205458) (xy 109.701501 -13.233167) (xy 109.778566 -13.268362) (xy 109.851936 -13.310722)
			(xy 109.920948 -13.359865) (xy 109.984976 -13.415346) (xy 110.043441 -13.476661) (xy 110.095812 -13.543257)
			(xy 110.141615 -13.614529) (xy 110.180437 -13.689832) (xy 110.211925 -13.768484) (xy 110.235793 -13.849774)
			(xy 110.251827 -13.932964) (xy 110.25988 -14.017301) (xy 110.260384 -14.059662) (xy 110.260384 -14.439259)
			(xy 136.470123 -14.439259) (xy 136.470123 -14.340973) (xy 136.478032 -14.243006) (xy 136.493798 -14.145993)
			(xy 136.517319 -14.050564) (xy 136.548443 -13.957336) (xy 136.586968 -13.866915) (xy 136.632643 -13.779888)
			(xy 136.685174 -13.696817) (xy 136.744218 -13.618244) (xy 136.809393 -13.544676) (xy 136.880277 -13.476591)
			(xy 136.95641 -13.41443) (xy 137.037297 -13.358598) (xy 137.122415 -13.309455) (xy 137.211212 -13.267321)
			(xy 137.30311 -13.232468) (xy 137.397516 -13.205123) (xy 137.493815 -13.185464) (xy 137.591384 -13.173617)
			(xy 137.68959 -13.169659) (xy 137.787796 -13.173617) (xy 137.885365 -13.185464) (xy 137.981664 -13.205123)
			(xy 138.07607 -13.232468) (xy 138.167968 -13.267321) (xy 138.256765 -13.309455) (xy 138.341883 -13.358598)
			(xy 138.42277 -13.41443) (xy 138.498903 -13.476591) (xy 138.569787 -13.544676) (xy 138.634962 -13.618244)
			(xy 138.694006 -13.696817) (xy 138.746537 -13.779888) (xy 138.792212 -13.866915) (xy 138.830737 -13.957336)
			(xy 138.861861 -14.050564) (xy 138.885382 -14.145993) (xy 138.901148 -14.243006) (xy 138.909057 -14.340973)
			(xy 138.909552 -14.390116) (xy 138.909057 -14.439259) (xy 138.901148 -14.537226) (xy 138.885382 -14.634239)
			(xy 138.861861 -14.729668) (xy 138.856503 -14.745716) (xy 146.401028 -14.745716) (xy 146.401028 -14.059916)
			(xy 146.401532 -14.017555) (xy 146.409585 -13.933218) (xy 146.425619 -13.850028) (xy 146.449487 -13.768738)
			(xy 146.480975 -13.690086) (xy 146.519797 -13.614783) (xy 146.5656 -13.543511) (xy 146.617971 -13.476915)
			(xy 146.676436 -13.4156) (xy 146.740464 -13.360119) (xy 146.809476 -13.310976) (xy 146.882846 -13.268616)
			(xy 146.959911 -13.233421) (xy 147.039973 -13.205712) (xy 147.122306 -13.185738) (xy 147.206165 -13.173681)
			(xy 147.29079 -13.16965) (xy 147.375415 -13.173681) (xy 147.459274 -13.185738) (xy 147.541607 -13.205712)
			(xy 147.621669 -13.233421) (xy 147.698734 -13.268616) (xy 147.772104 -13.310976) (xy 147.841116 -13.360119)
			(xy 147.905144 -13.4156) (xy 147.963609 -13.476915) (xy 148.01598 -13.543511) (xy 148.061783 -13.614783)
			(xy 148.100605 -13.690086) (xy 148.132093 -13.768738) (xy 148.14644 -13.8176) (xy 164.2364 -13.8176)
			(xy 164.2364 -11.0998) (xy 165.5318 -11.0998) (xy 165.5318 -12.563348) (xy 166.236396 -12.563348)
			(xy 166.236396 -9.745472) (xy 167.531796 -9.745472) (xy 167.531796 -12.614148) (xy 166.261796 -12.614148)
			(xy 166.261796 -12.563348) (xy 166.236396 -12.563348) (xy 165.5318 -12.563348) (xy 165.5318 -13.8176)
			(xy 168.236392 -13.8176) (xy 168.236392 -11.0998) (xy 169.531792 -11.0998) (xy 169.531792 -12.563348)
			(xy 170.236388 -12.563348) (xy 170.236388 -9.745472) (xy 171.531788 -9.745472) (xy 171.531788 -12.614148)
			(xy 170.261788 -12.614148) (xy 170.261788 -12.563348) (xy 170.236388 -12.563348) (xy 169.531792 -12.563348)
			(xy 169.531792 -13.8176) (xy 172.236384 -13.8176) (xy 172.236384 -11.0998) (xy 173.531784 -11.0998)
			(xy 173.531784 -12.563348) (xy 174.23638 -12.563348) (xy 174.23638 -9.745472) (xy 175.53178 -9.745472)
			(xy 175.53178 -10.61511) (xy 195.541919 -10.61511) (xy 195.550132 -10.44552) (xy 195.566539 -10.276526)
			(xy 195.591101 -10.108524) (xy 195.623761 -9.941907) (xy 195.664442 -9.777064) (xy 195.71305 -9.614382)
			(xy 195.740782 -9.534144) (xy 195.747894 -9.51357) (xy 195.747894 -9.332214) (xy 195.876164 -9.203944)
			(xy 195.885562 -9.184386) (xy 195.920655 -9.112187) (xy 195.996552 -8.970709) (xy 196.07884 -8.832851)
			(xy 196.167348 -8.698901) (xy 196.261889 -8.56914) (xy 196.362268 -8.443839) (xy 196.468272 -8.32326)
			(xy 196.57968 -8.207655) (xy 196.637656 -8.15213) (xy 196.661438 -8.128824) (xy 196.703154 -8.076926)
			(xy 196.737476 -8.019868) (xy 196.763776 -7.958696) (xy 196.781571 -7.894533) (xy 196.790534 -7.828553)
			(xy 196.791072 -7.79526) (xy 196.791072 -4.700016) (xy 196.791568 -4.633065) (xy 196.799501 -4.499398)
			(xy 196.815338 -4.366435) (xy 196.839024 -4.234645) (xy 196.870475 -4.104489) (xy 196.909583 -3.976425)
			(xy 196.956207 -3.850902) (xy 197.010187 -3.728362) (xy 197.07133 -3.609235) (xy 197.139424 -3.493939)
			(xy 197.214228 -3.38288) (xy 197.29548 -3.276447) (xy 197.382894 -3.175015) (xy 197.476164 -3.078939)
			(xy 197.574961 -2.988557) (xy 197.67894 -2.904187) (xy 197.787733 -2.826125) (xy 197.90096 -2.754645)
			(xy 198.018223 -2.689998) (xy 198.13911 -2.632411) (xy 198.263196 -2.582087) (xy 198.390045 -2.539202)
			(xy 198.519212 -2.503907) (xy 198.650243 -2.476326) (xy 198.782677 -2.456556) (xy 198.916051 -2.444666)
			(xy 199.049894 -2.440698) (xy 199.183737 -2.444666) (xy 199.317111 -2.456556) (xy 199.449545 -2.476326)
			(xy 199.580576 -2.503907) (xy 199.709743 -2.539202) (xy 199.836592 -2.582087) (xy 199.960678 -2.632411)
			(xy 200.081565 -2.689998) (xy 200.198828 -2.754645) (xy 200.312055 -2.826125) (xy 200.420848 -2.904187)
			(xy 200.524827 -2.988557) (xy 200.623624 -3.078939) (xy 200.716894 -3.175015) (xy 200.804308 -3.276447)
			(xy 200.88556 -3.38288) (xy 200.960364 -3.493939) (xy 201.028458 -3.609235) (xy 201.089601 -3.728362)
			(xy 201.143581 -3.850902) (xy 201.190205 -3.976425) (xy 201.229313 -4.104489) (xy 201.260764 -4.234645)
			(xy 201.28445 -4.366435) (xy 201.300287 -4.499398) (xy 201.30822 -4.633065) (xy 201.308716 -4.700016)
			(xy 201.308716 -7.79526) (xy 201.309274 -7.828552) (xy 201.318236 -7.894531) (xy 201.336026 -7.958695)
			(xy 201.362321 -8.019868) (xy 201.396636 -8.076928) (xy 201.438345 -8.128831) (xy 201.462132 -8.15213)
			(xy 201.520116 -8.207647) (xy 201.631527 -8.32325) (xy 201.737533 -8.443828) (xy 201.837913 -8.569129)
			(xy 201.932455 -8.698891) (xy 202.020962 -8.832842) (xy 202.103249 -8.970702) (xy 202.179143 -9.112182)
			(xy 202.214226 -9.184386) (xy 202.223624 -9.203944) (xy 202.351894 -9.332214) (xy 202.351894 -9.51357)
			(xy 202.359006 -9.534144) (xy 202.386741 -9.614382) (xy 202.435349 -9.777063) (xy 202.47603 -9.941906)
			(xy 202.50869 -10.108524) (xy 202.533252 -10.276526) (xy 202.549659 -10.44552) (xy 202.557872 -10.61511)
			(xy 202.557872 -10.615283) (xy 276.302174 -10.615283) (xy 276.310378 -10.445788) (xy 276.326768 -10.276889)
			(xy 276.351306 -10.108979) (xy 276.383934 -9.942453) (xy 276.424577 -9.777699) (xy 276.473138 -9.615103)
			(xy 276.500844 -9.534906) (xy 276.507956 -9.514332) (xy 276.507956 -9.33196) (xy 276.636988 -9.202928)
			(xy 276.646386 -9.18337) (xy 276.68148 -9.111251) (xy 276.757353 -8.969923) (xy 276.839603 -8.832209)
			(xy 276.928058 -8.698396) (xy 277.022534 -8.568764) (xy 277.122833 -8.443583) (xy 277.228746 -8.323114)
			(xy 277.340052 -8.20761) (xy 277.397972 -8.15213) (xy 277.421756 -8.128827) (xy 277.463472 -8.076928)
			(xy 277.497794 -8.019869) (xy 277.524093 -7.958697) (xy 277.541887 -7.894533) (xy 277.55085 -7.828553)
			(xy 277.551388 -7.79526) (xy 277.551388 -4.700016) (xy 277.551884 -4.633854) (xy 277.559647 -4.501758)
			(xy 277.57513 -4.370343) (xy 277.598279 -4.240059) (xy 277.629016 -4.111354) (xy 277.667234 -3.98467)
			(xy 277.712803 -3.86044) (xy 277.765567 -3.73909) (xy 277.825344 -3.621038) (xy 277.85822 -3.56362)
			(xy 277.8916 -3.507161) (xy 277.964053 -3.397811) (xy 278.042731 -3.292851) (xy 278.127369 -3.192636)
			(xy 278.217683 -3.097504) (xy 278.313367 -3.007774) (xy 278.414098 -2.923751) (xy 278.519537 -2.845717)
			(xy 278.629329 -2.773935) (xy 278.743102 -2.708649) (xy 278.801576 -2.678938) (xy 278.862284 -2.649288)
			(xy 278.986571 -2.596283) (xy 279.113804 -2.550803) (xy 279.243529 -2.51301) (xy 279.375281 -2.48304)
			(xy 279.508589 -2.460999) (xy 279.642977 -2.446967) (xy 279.777962 -2.440994) (xy 279.913064 -2.443101)
			(xy 280.047798 -2.45328) (xy 280.181682 -2.471496) (xy 280.314238 -2.497683) (xy 280.444991 -2.531747)
			(xy 280.573475 -2.573567) (xy 280.699228 -2.622992) (xy 280.821802 -2.679847) (xy 280.940758 -2.743928)
			(xy 281.05567 -2.815005) (xy 281.166128 -2.892824) (xy 281.271737 -2.977108) (xy 281.372118 -3.067554)
			(xy 281.466912 -3.163839) (xy 281.555781 -3.265619) (xy 281.638407 -3.372529) (xy 281.714494 -3.484188)
			(xy 281.78377 -3.600195) (xy 281.845987 -3.720136) (xy 281.900922 -3.843582) (xy 281.94838 -3.970091)
			(xy 281.98819 -4.099211) (xy 282.020211 -4.23048) (xy 282.044326 -4.363429) (xy 282.060451 -4.497581)
			(xy 282.068528 -4.632457) (xy 282.069032 -4.700016) (xy 282.069032 -5.788152) (xy 322.22694 -5.788152)
			(xy 322.22694 -5.367528) (xy 322.524628 -5.06984) (xy 324.215252 -5.06984) (xy 324.51294 -5.367528)
			(xy 324.51294 -5.437632) (xy 353.410266 -5.437632) (xy 353.410266 -3.747008) (xy 353.707954 -3.44932)
			(xy 354.128578 -3.44932) (xy 354.426266 -3.747008) (xy 354.426266 -5.437632) (xy 354.128578 -5.73532)
			(xy 353.707954 -5.73532) (xy 353.410266 -5.437632) (xy 324.51294 -5.437632) (xy 324.51294 -5.574538)
			(xy 348.805246 -5.574538) (xy 350.253046 -5.574538) (xy 350.253046 -5.925312) (xy 364.9472 -5.925312)
			(xy 364.9472 -5.504688) (xy 365.244888 -5.207) (xy 366.935512 -5.207) (xy 367.145824 -5.417312) (xy 385.236466 -5.417312)
			(xy 385.236466 -2.699512) (xy 386.531866 -2.699512) (xy 386.531866 -4.16306) (xy 387.236462 -4.16306)
			(xy 387.236462 -1.345184) (xy 388.531862 -1.345184) (xy 388.531862 -4.21386) (xy 387.261862 -4.21386)
			(xy 387.261862 -4.16306) (xy 387.236462 -4.16306) (xy 386.531866 -4.16306) (xy 386.531866 -5.417312)
			(xy 393.23645 -5.417312) (xy 393.23645 -2.699512) (xy 394.53185 -2.699512) (xy 394.53185 -4.16306)
			(xy 395.236446 -4.16306) (xy 395.236446 -1.345184) (xy 396.531846 -1.345184) (xy 396.531846 -4.21386)
			(xy 395.261846 -4.21386) (xy 395.261846 -4.16306) (xy 395.236446 -4.16306) (xy 394.53185 -4.16306)
			(xy 394.53185 -4.700016) (xy 421.997388 -4.700016) (xy 422.001374 -4.564291) (xy 422.013318 -4.429035)
			(xy 422.03318 -4.294712) (xy 422.060891 -4.161787) (xy 422.096355 -4.030717) (xy 422.13945 -3.901954)
			(xy 422.190028 -3.775942) (xy 422.247913 -3.653116) (xy 422.312908 -3.533899) (xy 422.384787 -3.418701)
			(xy 422.463302 -3.307921) (xy 422.548184 -3.201939) (xy 422.639139 -3.101122) (xy 422.735855 -3.005816)
			(xy 422.837996 -2.91635) (xy 422.945213 -2.833034) (xy 423.057134 -2.756153) (xy 423.173374 -2.685972)
			(xy 423.293533 -2.622735) (xy 423.417196 -2.566659) (xy 423.543936 -2.517936) (xy 423.673318 -2.476736)
			(xy 423.804894 -2.4432) (xy 423.938212 -2.417444) (xy 424.072812 -2.399556) (xy 424.208229 -2.389598)
			(xy 424.343997 -2.387605) (xy 424.479649 -2.393583) (xy 424.614716 -2.407512) (xy 424.748732 -2.429343)
			(xy 424.881236 -2.459002) (xy 425.011772 -2.496387) (xy 425.139888 -2.541367) (xy 425.265143 -2.593789)
			(xy 425.387107 -2.653472) (xy 425.505357 -2.720209) (xy 425.619487 -2.793771) (xy 425.729103 -2.873905)
			(xy 425.833827 -2.960333) (xy 425.933299 -3.052759) (xy 426.027174 -3.150863) (xy 426.115131 -3.254307)
			(xy 426.196865 -3.362735) (xy 426.272095 -3.475773) (xy 426.340561 -3.59303) (xy 426.402027 -3.714104)
			(xy 426.456282 -3.838577) (xy 426.503139 -3.966019) (xy 426.542435 -4.095992) (xy 426.574036 -4.228046)
			(xy 426.597833 -4.361728) (xy 426.613743 -4.496575) (xy 426.621712 -4.632124) (xy 426.62221 -4.700016)
			(xy 426.621712 -4.767908) (xy 426.613743 -4.903457) (xy 426.597833 -5.038304) (xy 426.574036 -5.171986)
			(xy 426.542435 -5.30404) (xy 426.503139 -5.434013) (xy 426.456282 -5.561455) (xy 426.402027 -5.685928)
			(xy 426.340561 -5.807002) (xy 426.272095 -5.924259) (xy 426.196865 -6.037297) (xy 426.115131 -6.145725)
			(xy 426.027174 -6.249169) (xy 425.933299 -6.347273) (xy 425.833827 -6.439699) (xy 425.729103 -6.526127)
			(xy 425.619487 -6.606261) (xy 425.505357 -6.679823) (xy 425.387107 -6.74656) (xy 425.265143 -6.806243)
			(xy 425.139888 -6.858665) (xy 425.011772 -6.903645) (xy 424.881236 -6.94103) (xy 424.748732 -6.970689)
			(xy 424.614716 -6.99252) (xy 424.479649 -7.006449) (xy 424.343997 -7.012427) (xy 424.208229 -7.010434)
			(xy 424.072812 -7.000476) (xy 423.938212 -6.982588) (xy 423.804894 -6.956832) (xy 423.673318 -6.923296)
			(xy 423.543936 -6.882096) (xy 423.417196 -6.833373) (xy 423.293533 -6.777297) (xy 423.173374 -6.71406)
			(xy 423.057134 -6.643879) (xy 422.945213 -6.566998) (xy 422.837996 -6.483682) (xy 422.735855 -6.394216)
			(xy 422.639139 -6.29891) (xy 422.548184 -6.198093) (xy 422.463302 -6.092111) (xy 422.384787 -5.981331)
			(xy 422.312908 -5.866133) (xy 422.247913 -5.746916) (xy 422.190028 -5.62409) (xy 422.13945 -5.498078)
			(xy 422.096355 -5.369315) (xy 422.060891 -5.238245) (xy 422.03318 -5.10532) (xy 422.013318 -4.970997)
			(xy 422.001374 -4.835741) (xy 421.997388 -4.700016) (xy 394.53185 -4.700016) (xy 394.53185 -5.468112)
			(xy 393.26185 -5.468112) (xy 393.26185 -5.417312) (xy 393.23645 -5.417312) (xy 386.531866 -5.417312)
			(xy 386.531866 -5.468112) (xy 385.261866 -5.468112) (xy 385.261866 -5.417312) (xy 385.236466 -5.417312)
			(xy 367.145824 -5.417312) (xy 367.2332 -5.504688) (xy 367.2332 -5.925312) (xy 366.935512 -6.223)
			(xy 365.244888 -6.223) (xy 364.9472 -5.925312) (xy 350.253046 -5.925312) (xy 350.253046 -8.393938)
			(xy 348.805246 -8.393938) (xy 348.805246 -5.574538) (xy 324.51294 -5.574538) (xy 324.51294 -5.788152)
			(xy 324.215252 -6.08584) (xy 322.524628 -6.08584) (xy 322.22694 -5.788152) (xy 282.069032 -5.788152)
			(xy 282.069032 -6.87451) (xy 338.805266 -6.87451) (xy 340.253066 -6.87451) (xy 340.253066 -9.067546)
			(xy 360.369866 -9.067546) (xy 362.198666 -9.067546) (xy 365.169958 -9.067546) (xy 366.998758 -9.067546)
			(xy 366.998758 -9.617456) (xy 385.236466 -9.617456) (xy 385.236466 -6.899656) (xy 386.531866 -6.899656)
			(xy 386.531866 -8.363204) (xy 387.236462 -8.363204) (xy 387.236462 -5.545328) (xy 388.531862 -5.545328)
			(xy 388.531862 -8.414004) (xy 387.261862 -8.414004) (xy 387.261862 -8.363204) (xy 387.236462 -8.363204)
			(xy 386.531866 -8.363204) (xy 386.531866 -9.617456) (xy 389.236458 -9.617456) (xy 389.236458 -6.899656)
			(xy 390.531858 -6.899656) (xy 390.531858 -8.363204) (xy 391.236454 -8.363204) (xy 391.236454 -5.545328)
			(xy 392.531854 -5.545328) (xy 392.531854 -8.414004) (xy 391.261854 -8.414004) (xy 391.261854 -8.363204)
			(xy 391.236454 -8.363204) (xy 390.531858 -8.363204) (xy 390.531858 -9.617456) (xy 393.23645 -9.617456)
			(xy 393.23645 -6.899656) (xy 394.53185 -6.899656) (xy 394.53185 -8.363204) (xy 395.236446 -8.363204)
			(xy 395.236446 -5.545328) (xy 396.531846 -5.545328) (xy 396.531846 -8.414004) (xy 395.261846 -8.414004)
			(xy 395.261846 -8.363204) (xy 395.236446 -8.363204) (xy 394.53185 -8.363204) (xy 394.53185 -9.668256)
			(xy 393.26185 -9.668256) (xy 393.26185 -9.617456) (xy 393.23645 -9.617456) (xy 390.531858 -9.617456)
			(xy 390.531858 -9.668256) (xy 389.261858 -9.668256) (xy 389.261858 -9.617456) (xy 389.236458 -9.617456)
			(xy 386.531866 -9.617456) (xy 386.531866 -9.668256) (xy 385.261866 -9.668256) (xy 385.261866 -9.617456)
			(xy 385.236466 -9.617456) (xy 366.998758 -9.617456) (xy 366.998758 -11.505946) (xy 365.169958 -11.505946)
			(xy 365.169958 -9.067546) (xy 362.198666 -9.067546) (xy 362.198666 -11.505946) (xy 360.369866 -11.505946)
			(xy 360.369866 -9.067546) (xy 340.253066 -9.067546) (xy 340.253066 -9.69391) (xy 338.805266 -9.69391)
			(xy 338.805266 -6.87451) (xy 282.069032 -6.87451) (xy 282.069032 -7.79526) (xy 282.069585 -7.828553)
			(xy 282.078547 -7.894532) (xy 282.096338 -7.958696) (xy 282.122633 -8.019869) (xy 282.15695 -8.076929)
			(xy 282.19866 -8.128831) (xy 282.222448 -8.15213) (xy 282.28042 -8.207659) (xy 282.391833 -8.32326)
			(xy 282.497841 -8.443836) (xy 282.598222 -8.569135) (xy 282.692766 -8.698896) (xy 282.781274 -8.832845)
			(xy 282.863563 -8.970704) (xy 282.939458 -9.112182) (xy 282.974542 -9.184386) (xy 282.98394 -9.203944)
			(xy 283.111956 -9.33196) (xy 283.111956 -9.513062) (xy 283.119068 -9.533382) (xy 283.12617 -9.553914)
			(xy 308.833762 -9.553914) (xy 308.833762 -9.445286) (xy 308.841691 -9.336948) (xy 308.857508 -9.229477)
			(xy 308.881127 -9.123448) (xy 308.912423 -9.019426) (xy 308.951228 -8.917965) (xy 308.997336 -8.819608)
			(xy 309.0505 -8.724879) (xy 309.110438 -8.634284) (xy 309.176828 -8.548305) (xy 309.249318 -8.467402)
			(xy 309.327519 -8.392006) (xy 309.411016 -8.32252) (xy 309.499362 -8.259313) (xy 309.592086 -8.202725)
			(xy 309.688694 -8.153055) (xy 309.788669 -8.11057) (xy 309.891479 -8.075497) (xy 309.996575 -8.048021)
			(xy 310.103396 -8.02829) (xy 310.211372 -8.016409) (xy 310.319928 -8.012442) (xy 310.428484 -8.016409)
			(xy 310.53646 -8.02829) (xy 310.643281 -8.048021) (xy 310.748377 -8.075497) (xy 310.851187 -8.11057)
			(xy 310.951162 -8.153055) (xy 311.04777 -8.202725) (xy 311.140494 -8.259313) (xy 311.22884 -8.32252)
			(xy 311.312337 -8.392006) (xy 311.390538 -8.467402) (xy 311.463028 -8.548305) (xy 311.529418 -8.634284)
			(xy 311.589356 -8.724879) (xy 311.64252 -8.819608) (xy 311.688628 -8.917965) (xy 311.727433 -9.019426)
			(xy 311.741987 -9.0678) (xy 322.449698 -9.0678) (xy 324.278498 -9.0678) (xy 327.24979 -9.0678) (xy 329.07859 -9.0678)
			(xy 329.07859 -9.405112) (xy 334.253586 -9.405112) (xy 334.253586 -8.984488) (xy 334.551274 -8.6868)
			(xy 336.394298 -8.6868) (xy 336.691986 -8.984488) (xy 336.691986 -9.405112) (xy 336.394298 -9.7028)
			(xy 334.551274 -9.7028) (xy 334.253586 -9.405112) (xy 329.07859 -9.405112) (xy 329.07859 -9.774428)
			(xy 348.805246 -9.774428) (xy 350.253046 -9.774428) (xy 350.253046 -12.593828) (xy 348.805246 -12.593828)
			(xy 348.805246 -9.774428) (xy 329.07859 -9.774428) (xy 329.07859 -11.0744) (xy 338.805266 -11.0744)
			(xy 340.253066 -11.0744) (xy 340.253066 -13.8938) (xy 338.805266 -13.8938) (xy 338.805266 -11.0744)
			(xy 329.07859 -11.0744) (xy 329.07859 -11.5062) (xy 327.24979 -11.5062) (xy 327.24979 -9.0678) (xy 324.278498 -9.0678)
			(xy 324.278498 -11.5062) (xy 322.449698 -11.5062) (xy 322.449698 -9.0678) (xy 311.741987 -9.0678)
			(xy 311.758729 -9.123448) (xy 311.782348 -9.229477) (xy 311.798165 -9.336948) (xy 311.806094 -9.445286)
			(xy 311.80659 -9.4996) (xy 311.806094 -9.553914) (xy 311.798165 -9.662252) (xy 311.782348 -9.769723)
			(xy 311.758729 -9.875752) (xy 311.727433 -9.979774) (xy 311.688628 -10.081235) (xy 311.64252 -10.179592)
			(xy 311.589356 -10.274321) (xy 311.529418 -10.364916) (xy 311.463028 -10.450895) (xy 311.390538 -10.531798)
			(xy 311.312337 -10.607194) (xy 311.22884 -10.67668) (xy 311.140494 -10.739887) (xy 311.04777 -10.796475)
			(xy 310.951162 -10.846145) (xy 310.851187 -10.88863) (xy 310.748377 -10.923703) (xy 310.643281 -10.951179)
			(xy 310.53646 -10.97091) (xy 310.428484 -10.982791) (xy 310.319928 -10.986758) (xy 310.211372 -10.982791)
			(xy 310.103396 -10.97091) (xy 309.996575 -10.951179) (xy 309.891479 -10.923703) (xy 309.788669 -10.88863)
			(xy 309.688694 -10.846145) (xy 309.592086 -10.796475) (xy 309.499362 -10.739887) (xy 309.411016 -10.67668)
			(xy 309.327519 -10.607194) (xy 309.249318 -10.531798) (xy 309.176828 -10.450895) (xy 309.110438 -10.364916)
			(xy 309.0505 -10.274321) (xy 308.997336 -10.179592) (xy 308.951228 -10.081235) (xy 308.912423 -9.979774)
			(xy 308.881127 -9.875752) (xy 308.857508 -9.769723) (xy 308.841691 -9.662252) (xy 308.833762 -9.553914)
			(xy 283.12617 -9.553914) (xy 283.146839 -9.613668) (xy 283.195511 -9.776451) (xy 283.236247 -9.941399)
			(xy 283.268951 -10.108126) (xy 283.293547 -10.27624) (xy 283.309975 -10.445347) (xy 283.318199 -10.615052)
			(xy 283.318199 -10.784956) (xy 283.309975 -10.95466) (xy 283.293546 -11.123768) (xy 283.26895 -11.291882)
			(xy 283.236246 -11.458608) (xy 283.195509 -11.623556) (xy 283.146837 -11.786339) (xy 283.119068 -11.866626)
			(xy 283.111956 -11.8872) (xy 283.111956 -12.067794) (xy 282.984194 -12.195556) (xy 282.974796 -12.215114)
			(xy 282.93766 -12.291498) (xy 282.85698 -12.440978) (xy 282.769161 -12.586378) (xy 282.674408 -12.727359)
			(xy 282.572944 -12.863588) (xy 282.465007 -12.994749) (xy 282.350849 -13.120532) (xy 282.230738 -13.240643)
			(xy 282.104955 -13.354802) (xy 281.973795 -13.462739) (xy 281.837565 -13.564204) (xy 281.696585 -13.658956)
			(xy 281.551185 -13.746776) (xy 281.401705 -13.827456) (xy 281.32532 -13.86459) (xy 281.305762 -13.873988)
			(xy 281.177746 -14.002004) (xy 280.996644 -14.002004) (xy 280.976324 -14.009116) (xy 280.896069 -14.03686)
			(xy 280.733354 -14.085488) (xy 280.568476 -14.126187) (xy 280.401822 -14.158861) (xy 280.233783 -14.183434)
			(xy 280.064751 -14.199847) (xy 279.895123 -14.208064) (xy 279.725297 -14.208064) (xy 279.555669 -14.199847)
			(xy 279.386637 -14.183434) (xy 279.218598 -14.158861) (xy 279.051944 -14.126187) (xy 278.887066 -14.085488)
			(xy 278.724351 -14.03686) (xy 278.644096 -14.009116) (xy 278.623776 -14.002004) (xy 278.442166 -14.002004)
			(xy 278.313642 -13.87348) (xy 278.294084 -13.864082) (xy 278.217786 -13.826955) (xy 278.068472 -13.746311)
			(xy 277.923232 -13.658543) (xy 277.782404 -13.563856) (xy 277.646319 -13.462471) (xy 277.515295 -13.354626)
			(xy 277.389637 -13.240572) (xy 277.269641 -13.120576) (xy 277.155586 -12.99492) (xy 277.04774 -12.863896)
			(xy 276.946355 -12.727811) (xy 276.851667 -12.586984) (xy 276.763898 -12.441744) (xy 276.683254 -12.29243)
			(xy 276.646132 -12.21613) (xy 276.636734 -12.196572) (xy 276.507956 -12.067794) (xy 276.507956 -11.885676)
			(xy 276.500844 -11.865356) (xy 276.473156 -11.785153) (xy 276.424592 -11.622557) (xy 276.383947 -11.457804)
			(xy 276.351316 -11.291278) (xy 276.326775 -11.123369) (xy 276.310382 -10.95447) (xy 276.302175 -10.784976)
			(xy 276.302174 -10.615283) (xy 202.557872 -10.615283) (xy 202.557872 -10.784898) (xy 202.549659 -10.954488)
			(xy 202.533251 -11.123481) (xy 202.508689 -11.291484) (xy 202.476028 -11.458101) (xy 202.435347 -11.622944)
			(xy 202.386738 -11.785626) (xy 202.359006 -11.865864) (xy 202.351894 -11.886438) (xy 202.351894 -12.068048)
			(xy 202.22337 -12.196572) (xy 202.213972 -12.21613) (xy 202.176855 -12.292433) (xy 202.09621 -12.441746)
			(xy 202.008442 -12.586987) (xy 201.913754 -12.727814) (xy 201.812368 -12.863899) (xy 201.704521 -12.994923)
			(xy 201.590467 -13.12058) (xy 201.47047 -13.240576) (xy 201.344813 -13.35463) (xy 201.213789 -13.462476)
			(xy 201.077703 -13.563861) (xy 200.936876 -13.658549) (xy 200.791635 -13.746317) (xy 200.642321 -13.826961)
			(xy 200.56602 -13.864082) (xy 200.546462 -13.87348) (xy 200.417684 -14.002258) (xy 200.235566 -14.002258)
			(xy 200.215246 -14.00937) (xy 200.13504 -14.037078) (xy 199.972425 -14.085641) (xy 199.807653 -14.126285)
			(xy 199.641108 -14.158916) (xy 199.47318 -14.183455) (xy 199.304262 -14.199847) (xy 199.13475 -14.208052)
			(xy 198.965038 -14.208052) (xy 198.795526 -14.199847) (xy 198.626608 -14.183455) (xy 198.45868 -14.158916)
			(xy 198.292135 -14.126285) (xy 198.127363 -14.085641) (xy 197.964748 -14.037078) (xy 197.884542 -14.00937)
			(xy 197.864222 -14.002258) (xy 197.682104 -14.002258) (xy 197.553326 -13.87348) (xy 197.533768 -13.864082)
			(xy 197.457467 -13.826961) (xy 197.308153 -13.746317) (xy 197.162913 -13.658549) (xy 197.022085 -13.563861)
			(xy 196.886001 -13.462475) (xy 196.754976 -13.354629) (xy 196.629319 -13.240575) (xy 196.509323 -13.120579)
			(xy 196.395269 -12.994922) (xy 196.287423 -12.863897) (xy 196.186038 -12.727812) (xy 196.09135 -12.586985)
			(xy 196.003581 -12.441745) (xy 195.922937 -12.292431) (xy 195.885816 -12.21613) (xy 195.876418 -12.196572)
			(xy 195.747894 -12.068048) (xy 195.747894 -11.886438) (xy 195.740782 -11.865864) (xy 195.713052 -11.785625)
			(xy 195.664444 -11.622943) (xy 195.623763 -11.458101) (xy 195.591102 -11.291483) (xy 195.56654 -11.123481)
			(xy 195.550133 -10.954487) (xy 195.54192 -10.784898) (xy 195.541919 -10.61511) (xy 175.53178 -10.61511)
			(xy 175.53178 -12.614148) (xy 174.26178 -12.614148) (xy 174.26178 -12.563348) (xy 174.23638 -12.563348)
			(xy 173.531784 -12.563348) (xy 173.531784 -13.8684) (xy 172.261784 -13.8684) (xy 172.261784 -13.8176)
			(xy 172.236384 -13.8176) (xy 169.531792 -13.8176) (xy 169.531792 -13.8684) (xy 168.261792 -13.8684)
			(xy 168.261792 -13.8176) (xy 168.236392 -13.8176) (xy 165.5318 -13.8176) (xy 165.5318 -13.8684) (xy 164.2618 -13.8684)
			(xy 164.2618 -13.8176) (xy 164.2364 -13.8176) (xy 148.14644 -13.8176) (xy 148.155961 -13.850028)
			(xy 148.171995 -13.933218) (xy 148.180048 -14.017555) (xy 148.180552 -14.059916) (xy 148.180552 -14.439259)
			(xy 319.550021 -14.439259) (xy 319.550021 -14.340973) (xy 319.55793 -14.243006) (xy 319.573696 -14.145993)
			(xy 319.597217 -14.050564) (xy 319.628341 -13.957336) (xy 319.666866 -13.866915) (xy 319.712541 -13.779888)
			(xy 319.765072 -13.696817) (xy 319.824116 -13.618244) (xy 319.889291 -13.544676) (xy 319.960175 -13.476591)
			(xy 320.036308 -13.41443) (xy 320.117195 -13.358598) (xy 320.202313 -13.309455) (xy 320.29111 -13.267321)
			(xy 320.383008 -13.232468) (xy 320.477414 -13.205123) (xy 320.573713 -13.185464) (xy 320.671282 -13.173617)
			(xy 320.769488 -13.169659) (xy 320.867694 -13.173617) (xy 320.965263 -13.185464) (xy 321.061562 -13.205123)
			(xy 321.155968 -13.232468) (xy 321.247866 -13.267321) (xy 321.336663 -13.309455) (xy 321.421781 -13.358598)
			(xy 321.502668 -13.41443) (xy 321.578801 -13.476591) (xy 321.649685 -13.544676) (xy 321.71486 -13.618244)
			(xy 321.773904 -13.696817) (xy 321.826435 -13.779888) (xy 321.87211 -13.866915) (xy 321.910635 -13.957336)
			(xy 321.941759 -14.050564) (xy 321.944064 -14.059916) (xy 329.480926 -14.059916) (xy 329.481436 -14.017565)
			(xy 329.489498 -13.933249) (xy 329.505539 -13.85008) (xy 329.529411 -13.768812) (xy 329.5609 -13.690182)
			(xy 329.59972 -13.6149) (xy 329.645519 -13.543649) (xy 329.697884 -13.477073) (xy 329.756339 -13.415776)
			(xy 329.820356 -13.360313) (xy 329.889354 -13.311185) (xy 329.96271 -13.268838) (xy 330.039758 -13.233655)
			(xy 330.119802 -13.205954) (xy 330.202116 -13.185987) (xy 330.285956 -13.173933) (xy 330.370561 -13.169903)
			(xy 330.455166 -13.173933) (xy 330.539006 -13.185987) (xy 330.62132 -13.205954) (xy 330.701364 -13.233655)
			(xy 330.778412 -13.268838) (xy 330.851768 -13.311185) (xy 330.920766 -13.360313) (xy 330.984783 -13.415776)
			(xy 331.043238 -13.477073) (xy 331.095603 -13.543649) (xy 331.141402 -13.6149) (xy 331.180222 -13.690182)
			(xy 331.211711 -13.768812) (xy 331.235583 -13.85008) (xy 331.251624 -13.933249) (xy 331.259686 -14.017565)
			(xy 331.260196 -14.059916) (xy 331.260196 -14.439005) (xy 357.470189 -14.439005) (xy 357.470189 -14.340719)
			(xy 357.478098 -14.242752) (xy 357.493864 -14.145739) (xy 357.517385 -14.05031) (xy 357.548509 -13.957082)
			(xy 357.587034 -13.866661) (xy 357.632709 -13.779634) (xy 357.68524 -13.696563) (xy 357.744284 -13.61799)
			(xy 357.809459 -13.544422) (xy 357.880343 -13.476337) (xy 357.956476 -13.414176) (xy 358.037363 -13.358344)
			(xy 358.122481 -13.309201) (xy 358.211278 -13.267067) (xy 358.303176 -13.232214) (xy 358.397582 -13.204869)
			(xy 358.493881 -13.18521) (xy 358.59145 -13.173363) (xy 358.689656 -13.169405) (xy 358.787862 -13.173363)
			(xy 358.885431 -13.18521) (xy 358.98173 -13.204869) (xy 359.076136 -13.232214) (xy 359.168034 -13.267067)
			(xy 359.256831 -13.309201) (xy 359.341949 -13.358344) (xy 359.422836 -13.414176) (xy 359.498969 -13.476337)
			(xy 359.569853 -13.544422) (xy 359.635028 -13.61799) (xy 359.694072 -13.696563) (xy 359.746603 -13.779634)
			(xy 359.792278 -13.866661) (xy 359.830803 -13.957082) (xy 359.861927 -14.05031) (xy 359.885448 -14.145739)
			(xy 359.901214 -14.242752) (xy 359.909123 -14.340719) (xy 359.909618 -14.389862) (xy 359.909123 -14.439005)
			(xy 359.901214 -14.536972) (xy 359.885448 -14.633985) (xy 359.861927 -14.729414) (xy 359.856569 -14.745462)
			(xy 367.401348 -14.745462) (xy 367.401348 -14.059662) (xy 367.401852 -14.017314) (xy 367.409903 -13.933)
			(xy 367.425932 -13.849834) (xy 367.449793 -13.768567) (xy 367.481272 -13.689937) (xy 367.520083 -13.614656)
			(xy 367.565873 -13.543404) (xy 367.618229 -13.476828) (xy 367.676677 -13.41553) (xy 367.740687 -13.360065)
			(xy 367.809679 -13.310936) (xy 367.883029 -13.268587) (xy 367.960072 -13.233403) (xy 368.040111 -13.205701)
			(xy 368.12242 -13.185733) (xy 368.206255 -13.17368) (xy 368.290856 -13.16965) (xy 368.375457 -13.17368)
			(xy 368.459292 -13.185733) (xy 368.541601 -13.205701) (xy 368.62164 -13.233403) (xy 368.698683 -13.268587)
			(xy 368.772033 -13.310936) (xy 368.841025 -13.360065) (xy 368.905035 -13.41553) (xy 368.963483 -13.476828)
			(xy 369.015839 -13.543404) (xy 369.061629 -13.614656) (xy 369.10044 -13.689937) (xy 369.131919 -13.768567)
			(xy 369.146316 -13.8176) (xy 385.236466 -13.8176) (xy 385.236466 -11.0998) (xy 386.531866 -11.0998)
			(xy 386.531866 -12.563348) (xy 387.236462 -12.563348) (xy 387.236462 -9.745472) (xy 388.531862 -9.745472)
			(xy 388.531862 -12.614148) (xy 387.261862 -12.614148) (xy 387.261862 -12.563348) (xy 387.236462 -12.563348)
			(xy 386.531866 -12.563348) (xy 386.531866 -13.8176) (xy 389.236458 -13.8176) (xy 389.236458 -11.0998)
			(xy 390.531858 -11.0998) (xy 390.531858 -12.563348) (xy 391.236454 -12.563348) (xy 391.236454 -9.745472)
			(xy 392.531854 -9.745472) (xy 392.531854 -12.614148) (xy 391.261854 -12.614148) (xy 391.261854 -12.563348)
			(xy 391.236454 -12.563348) (xy 390.531858 -12.563348) (xy 390.531858 -13.8176) (xy 393.23645 -13.8176)
			(xy 393.23645 -11.0998) (xy 394.53185 -11.0998) (xy 394.53185 -12.563348) (xy 395.236446 -12.563348)
			(xy 395.236446 -9.745472) (xy 396.531846 -9.745472) (xy 396.531846 -12.614148) (xy 395.261846 -12.614148)
			(xy 395.261846 -12.563348) (xy 395.236446 -12.563348) (xy 394.53185 -12.563348) (xy 394.53185 -13.8684)
			(xy 393.26185 -13.8684) (xy 393.26185 -13.8176) (xy 393.23645 -13.8176) (xy 390.531858 -13.8176)
			(xy 390.531858 -13.8684) (xy 389.261858 -13.8684) (xy 389.261858 -13.8176) (xy 389.236458 -13.8176)
			(xy 386.531866 -13.8176) (xy 386.531866 -13.8684) (xy 385.261866 -13.8684) (xy 385.261866 -13.8176)
			(xy 385.236466 -13.8176) (xy 369.146316 -13.8176) (xy 369.15578 -13.849834) (xy 369.171809 -13.933)
			(xy 369.17986 -14.017314) (xy 369.180364 -14.059662) (xy 369.180364 -14.694662) (xy 369.179898 -14.73694)
			(xy 369.1721 -14.821134) (xy 369.156565 -14.90425) (xy 369.133428 -14.985578) (xy 369.102885 -15.064424)
			(xy 369.065196 -15.140115) (xy 369.020685 -15.212005) (xy 368.969729 -15.279482) (xy 368.912765 -15.341969)
			(xy 368.850277 -15.398933) (xy 368.7828 -15.449888) (xy 368.71091 -15.494399) (xy 368.635218 -15.532087)
			(xy 368.556372 -15.56263) (xy 368.475044 -15.585767) (xy 368.391928 -15.601301) (xy 368.307734 -15.609099)
			(xy 368.265456 -15.60957) (xy 368.223029 -15.609129) (xy 368.138583 -15.600808) (xy 368.05536 -15.584249)
			(xy 367.97416 -15.559613) (xy 367.895766 -15.527137) (xy 367.820933 -15.487133) (xy 367.750381 -15.439987)
			(xy 367.684791 -15.386153) (xy 367.624792 -15.326149) (xy 367.570964 -15.260553) (xy 367.523825 -15.189996)
			(xy 367.483828 -15.115159) (xy 367.451359 -15.036763) (xy 367.426731 -14.955561) (xy 367.41018 -14.872336)
			(xy 367.401867 -14.787889) (xy 367.401348 -14.745462) (xy 359.856569 -14.745462) (xy 359.830803 -14.822642)
			(xy 359.792278 -14.913063) (xy 359.746603 -15.000091) (xy 359.694072 -15.083161) (xy 359.635028 -15.161734)
			(xy 359.569853 -15.235302) (xy 359.498969 -15.303387) (xy 359.422836 -15.365548) (xy 359.341949 -15.42138)
			(xy 359.256831 -15.470523) (xy 359.168034 -15.512657) (xy 359.076136 -15.54751) (xy 358.98173 -15.574855)
			(xy 358.885431 -15.594514) (xy 358.787862 -15.606361) (xy 358.689656 -15.610319) (xy 358.59145 -15.606361)
			(xy 358.493881 -15.594514) (xy 358.397582 -15.574855) (xy 358.303176 -15.54751) (xy 358.211278 -15.512657)
			(xy 358.122481 -15.470523) (xy 358.037363 -15.42138) (xy 357.956476 -15.365548) (xy 357.880343 -15.303387)
			(xy 357.809459 -15.235302) (xy 357.744284 -15.161734) (xy 357.68524 -15.083161) (xy 357.632709 -15.000091)
			(xy 357.587034 -14.913063) (xy 357.548509 -14.822642) (xy 357.517385 -14.729414) (xy 357.493864 -14.633985)
			(xy 357.478098 -14.536972) (xy 357.470189 -14.439005) (xy 331.260196 -14.439005) (xy 331.260196 -14.694916)
			(xy 331.259735 -14.737193) (xy 331.251932 -14.821386) (xy 331.236394 -14.904499) (xy 331.213253 -14.985825)
			(xy 331.182708 -15.064668) (xy 331.145018 -15.140357) (xy 331.100505 -15.212245) (xy 331.049549 -15.279719)
			(xy 330.992584 -15.342204) (xy 330.930098 -15.399167) (xy 330.862622 -15.450121) (xy 330.790732 -15.494631)
			(xy 330.715042 -15.532319) (xy 330.636198 -15.562862) (xy 330.554872 -15.586) (xy 330.471758 -15.601536)
			(xy 330.387565 -15.609336) (xy 330.345288 -15.609824) (xy 330.302863 -15.609299) (xy 330.218422 -15.600981)
			(xy 330.135202 -15.584427) (xy 330.054006 -15.559796) (xy 329.975615 -15.527324) (xy 329.900784 -15.487326)
			(xy 329.830233 -15.440186) (xy 329.764643 -15.386357) (xy 329.704645 -15.32636) (xy 329.650817 -15.26077)
			(xy 329.603676 -15.19022) (xy 329.563677 -15.115389) (xy 329.531206 -15.036998) (xy 329.506574 -14.955802)
			(xy 329.490019 -14.872582) (xy 329.481701 -14.788141) (xy 329.48118 -14.745716) (xy 329.480926 -14.059916)
			(xy 321.944064 -14.059916) (xy 321.96528 -14.145993) (xy 321.981046 -14.243006) (xy 321.988955 -14.340973)
			(xy 321.98945 -14.390116) (xy 321.988955 -14.439259) (xy 321.981046 -14.537226) (xy 321.96528 -14.634239)
			(xy 321.941759 -14.729668) (xy 321.910635 -14.822896) (xy 321.87211 -14.913317) (xy 321.826435 -15.000345)
			(xy 321.773904 -15.083415) (xy 321.71486 -15.161988) (xy 321.649685 -15.235556) (xy 321.578801 -15.303641)
			(xy 321.502668 -15.365802) (xy 321.421781 -15.421634) (xy 321.336663 -15.470777) (xy 321.247866 -15.512911)
			(xy 321.155968 -15.547764) (xy 321.061562 -15.575109) (xy 320.965263 -15.594768) (xy 320.867694 -15.606615)
			(xy 320.769488 -15.610573) (xy 320.671282 -15.606615) (xy 320.573713 -15.594768) (xy 320.477414 -15.575109)
			(xy 320.383008 -15.547764) (xy 320.29111 -15.512911) (xy 320.202313 -15.470777) (xy 320.117195 -15.421634)
			(xy 320.036308 -15.365802) (xy 319.960175 -15.303641) (xy 319.889291 -15.235556) (xy 319.824116 -15.161988)
			(xy 319.765072 -15.083415) (xy 319.712541 -15.000345) (xy 319.666866 -14.913317) (xy 319.628341 -14.822896)
			(xy 319.597217 -14.729668) (xy 319.573696 -14.634239) (xy 319.55793 -14.537226) (xy 319.550021 -14.439259)
			(xy 148.180552 -14.439259) (xy 148.180552 -14.694916) (xy 148.18005 -14.737199) (xy 148.172244 -14.821405)
			(xy 148.156702 -14.904531) (xy 148.133555 -14.985868) (xy 148.103 -15.064722) (xy 148.0653 -15.14042)
			(xy 148.020774 -15.212316) (xy 147.969805 -15.279796) (xy 147.912825 -15.342285) (xy 147.850322 -15.399249)
			(xy 147.782829 -15.450202) (xy 147.710922 -15.49471) (xy 147.635215 -15.532392) (xy 147.556354 -15.562926)
			(xy 147.475011 -15.586054) (xy 147.391881 -15.601576) (xy 147.307673 -15.60936) (xy 147.26539 -15.609824)
			(xy 147.265136 -15.609824) (xy 147.222711 -15.60927) (xy 147.138269 -15.600956) (xy 147.055049 -15.584406)
			(xy 146.973852 -15.559779) (xy 146.895459 -15.527311) (xy 146.820627 -15.487315) (xy 146.750075 -15.440177)
			(xy 146.684483 -15.386351) (xy 146.624484 -15.326355) (xy 146.570654 -15.260767) (xy 146.523511 -15.190218)
			(xy 146.483512 -15.115388) (xy 146.451039 -15.036997) (xy 146.426406 -14.955802) (xy 146.409851 -14.872582)
			(xy 146.401533 -14.788141) (xy 146.401028 -14.745716) (xy 138.856503 -14.745716) (xy 138.830737 -14.822896)
			(xy 138.792212 -14.913317) (xy 138.746537 -15.000345) (xy 138.694006 -15.083415) (xy 138.634962 -15.161988)
			(xy 138.569787 -15.235556) (xy 138.498903 -15.303641) (xy 138.42277 -15.365802) (xy 138.341883 -15.421634)
			(xy 138.256765 -15.470777) (xy 138.167968 -15.512911) (xy 138.07607 -15.547764) (xy 137.981664 -15.575109)
			(xy 137.885365 -15.594768) (xy 137.787796 -15.606615) (xy 137.68959 -15.610573) (xy 137.591384 -15.606615)
			(xy 137.493815 -15.594768) (xy 137.397516 -15.575109) (xy 137.30311 -15.547764) (xy 137.211212 -15.512911)
			(xy 137.122415 -15.470777) (xy 137.037297 -15.421634) (xy 136.95641 -15.365802) (xy 136.880277 -15.303641)
			(xy 136.809393 -15.235556) (xy 136.744218 -15.161988) (xy 136.685174 -15.083415) (xy 136.632643 -15.000345)
			(xy 136.586968 -14.913317) (xy 136.548443 -14.822896) (xy 136.517319 -14.729668) (xy 136.493798 -14.634239)
			(xy 136.478032 -14.537226) (xy 136.470123 -14.439259) (xy 110.260384 -14.439259) (xy 110.260384 -14.694662)
			(xy 110.259852 -14.736949) (xy 110.252052 -14.821164) (xy 110.236515 -14.904299) (xy 110.213373 -14.985646)
			(xy 110.182824 -15.06451) (xy 110.145129 -15.14022) (xy 110.100608 -15.212128) (xy 110.049643 -15.279622)
			(xy 109.992668 -15.342125) (xy 109.930168 -15.399105) (xy 109.862678 -15.450074) (xy 109.790772 -15.494599)
			(xy 109.715065 -15.5323) (xy 109.636203 -15.562854) (xy 109.554857 -15.586001) (xy 109.471723 -15.601544)
			(xy 109.387509 -15.609349) (xy 109.345222 -15.609824) (xy 109.302783 -15.609337) (xy 109.218312 -15.601019)
			(xy 109.135064 -15.584462) (xy 109.05384 -15.559824) (xy 108.975422 -15.527343) (xy 108.900565 -15.487331)
			(xy 108.829991 -15.440175) (xy 108.764379 -15.386328) (xy 108.704361 -15.326309) (xy 108.650515 -15.260696)
			(xy 108.60336 -15.190121) (xy 108.563351 -15.115264) (xy 108.530871 -15.036845) (xy 108.506234 -14.95562)
			(xy 108.489678 -14.872372) (xy 108.481362 -14.787901) (xy 108.48086 -14.745462) (xy 100.936335 -14.745462)
			(xy 100.910569 -14.822642) (xy 100.872044 -14.913063) (xy 100.826369 -15.000091) (xy 100.773838 -15.083161)
			(xy 100.714794 -15.161734) (xy 100.649619 -15.235302) (xy 100.578735 -15.303387) (xy 100.502602 -15.365548)
			(xy 100.421715 -15.42138) (xy 100.336597 -15.470523) (xy 100.2478 -15.512657) (xy 100.155902 -15.54751)
			(xy 100.061496 -15.574855) (xy 99.965197 -15.594514) (xy 99.867628 -15.606361) (xy 99.769422 -15.610319)
			(xy 99.671216 -15.606361) (xy 99.573647 -15.594514) (xy 99.477348 -15.574855) (xy 99.382942 -15.54751)
			(xy 99.291044 -15.512657) (xy 99.202247 -15.470523) (xy 99.117129 -15.42138) (xy 99.036242 -15.365548)
			(xy 98.960109 -15.303387) (xy 98.889225 -15.235302) (xy 98.82405 -15.161734) (xy 98.765006 -15.083161)
			(xy 98.712475 -15.000091) (xy 98.6668 -14.913063) (xy 98.628275 -14.822642) (xy 98.597151 -14.729414)
			(xy 98.57363 -14.633985) (xy 98.557864 -14.536972) (xy 98.549955 -14.439005) (xy 0.509016 -14.439005)
			(xy 0.509016 -18.545219) (xy 20.872007 -18.545219) (xy 20.87205 -18.453908) (xy 20.880966 -18.363033)
			(xy 20.898671 -18.273454) (xy 20.911312 -18.22958) (xy 21.129752 -18.22958) (xy 21.146337 -18.229101)
			(xy 21.178386 -18.220556) (xy 21.207146 -18.204033) (xy 21.23067 -18.180649) (xy 21.23948 -18.166588)
			(xy 21.257783 -18.136238) (xy 21.299908 -18.079238) (xy 21.347887 -18.02707) (xy 21.401171 -17.980332)
			(xy 21.459147 -17.939561) (xy 21.489924 -17.921986) (xy 21.504471 -17.913263) (xy 21.528754 -17.889601)
			(xy 21.545969 -17.860391) (xy 21.554909 -17.827686) (xy 21.555456 -17.810734) (xy 21.555456 -17.596866)
			(xy 21.596941 -17.585678) (xy 21.681432 -17.570032) (xy 21.767 -17.562177) (xy 21.852928 -17.562177)
			(xy 21.938496 -17.570032) (xy 22.022987 -17.585678) (xy 22.064472 -17.596866) (xy 22.064472 -17.810734)
			(xy 22.064965 -17.827699) (xy 22.073856 -17.860443) (xy 22.091078 -17.889676) (xy 22.115409 -17.913323)
			(xy 22.130004 -17.921986) (xy 22.160779 -17.939567) (xy 22.21877 -17.98032) (xy 22.272063 -18.02705)
			(xy 22.320044 -18.079219) (xy 22.362161 -18.136227) (xy 22.380448 -18.166588) (xy 22.389279 -18.180628)
			(xy 22.412809 -18.203988) (xy 22.441563 -18.220498) (xy 22.473598 -18.229044) (xy 22.490176 -18.22958)
			(xy 22.708616 -18.22958) (xy 22.72124 -18.273545) (xy 22.738897 -18.363302) (xy 22.747728 -18.454351)
			(xy 22.74824 -18.50009) (xy 22.747731 -18.545211) (xy 22.739127 -18.635041) (xy 22.730464 -18.679668)
			(xy 167.07104 -18.679668) (xy 167.07104 -18.353532) (xy 167.301672 -18.1229) (xy 168.897808 -18.1229)
			(xy 169.12844 -18.353532) (xy 169.12844 -18.679668) (xy 191.866266 -18.679668) (xy 191.866266 -18.353532)
			(xy 192.096898 -18.1229) (xy 193.693034 -18.1229) (xy 193.923666 -18.353532) (xy 193.923666 -18.679668)
			(xy 388.071106 -18.679668) (xy 388.071106 -18.353532) (xy 388.301738 -18.1229) (xy 389.897874 -18.1229)
			(xy 390.128506 -18.353532) (xy 390.128506 -18.679668) (xy 412.866332 -18.679668) (xy 412.866332 -18.353532)
			(xy 413.096964 -18.1229) (xy 414.6931 -18.1229) (xy 414.923732 -18.353532) (xy 414.923732 -18.679668)
			(xy 414.6931 -18.9103) (xy 413.096964 -18.9103) (xy 412.866332 -18.679668) (xy 390.128506 -18.679668)
			(xy 389.897874 -18.9103) (xy 388.301738 -18.9103) (xy 388.071106 -18.679668) (xy 193.923666 -18.679668)
			(xy 193.693034 -18.9103) (xy 192.096898 -18.9103) (xy 191.866266 -18.679668) (xy 169.12844 -18.679668)
			(xy 168.897808 -18.9103) (xy 167.301672 -18.9103) (xy 167.07104 -18.679668) (xy 22.730464 -18.679668)
			(xy 22.721931 -18.723629) (xy 22.709632 -18.767044) (xy 22.492208 -18.767044) (xy 22.475563 -18.767623)
			(xy 22.443406 -18.776234) (xy 22.414572 -18.792872) (xy 22.391024 -18.816404) (xy 22.382226 -18.830544)
			(xy 22.363929 -18.861244) (xy 22.321713 -18.918915) (xy 22.273522 -18.971695) (xy 22.219918 -19.018968)
			(xy 22.161527 -19.060183) (xy 22.130512 -19.07794) (xy 22.115939 -19.086623) (xy 22.091663 -19.110301)
			(xy 22.074455 -19.139522) (xy 22.065523 -19.172237) (xy 22.06498 -19.189192) (xy 22.06498 -19.40306)
			(xy 22.023416 -19.414293) (xy 21.938758 -19.430004) (xy 21.853016 -19.437893) (xy 21.766912 -19.437893)
			(xy 21.68117 -19.430004) (xy 21.596512 -19.414293) (xy 21.554948 -19.40306) (xy 21.554948 -19.189192)
			(xy 21.554425 -19.172229) (xy 21.545543 -19.139488) (xy 21.528329 -19.110255) (xy 21.504007 -19.086606)
			(xy 21.489416 -19.07794) (xy 21.458589 -19.060303) (xy 21.40052 -19.019407) (xy 21.347167 -18.972525)
			(xy 21.299145 -18.920195) (xy 21.257007 -18.863021) (xy 21.238718 -18.832576) (xy 21.229921 -18.818513)
			(xy 21.206378 -18.795158) (xy 21.177615 -18.778654) (xy 21.145571 -18.770116) (xy 21.12899 -18.769584)
			(xy 20.911058 -18.769584) (xy 20.89846 -18.725697) (xy 20.880839 -18.636102) (xy 20.872007 -18.545219)
			(xy 0.509016 -18.545219) (xy 0.509016 -24.826468) (xy 165.8239 -24.826468) (xy 165.8239 -23.230332)
			(xy 166.054532 -22.9997) (xy 166.380668 -22.9997) (xy 166.6113 -23.230332) (xy 166.6113 -23.858728)
			(xy 170.456352 -23.858728) (xy 170.456352 -23.532592) (xy 170.686984 -23.30196) (xy 172.28312 -23.30196)
			(xy 172.513752 -23.532592) (xy 172.513752 -23.858728) (xy 172.28312 -24.08936) (xy 170.686984 -24.08936)
			(xy 170.456352 -23.858728) (xy 166.6113 -23.858728) (xy 166.6113 -24.826468) (xy 177.83048 -24.826468)
			(xy 177.83048 -23.230332) (xy 178.061112 -22.9997) (xy 178.387248 -22.9997) (xy 178.61788 -23.230332)
			(xy 178.61788 -23.741888) (xy 189.46622 -23.741888) (xy 189.46622 -23.415752) (xy 189.696852 -23.18512)
			(xy 191.292988 -23.18512) (xy 191.52362 -23.415752) (xy 191.52362 -23.741888) (xy 191.292988 -23.97252)
			(xy 189.696852 -23.97252) (xy 189.46622 -23.741888) (xy 178.61788 -23.741888) (xy 178.61788 -24.826468)
			(xy 178.61026 -24.834088) (xy 197.2691 -24.834088) (xy 197.2691 -23.237952) (xy 197.499732 -23.00732)
			(xy 197.825868 -23.00732) (xy 198.0565 -23.237952) (xy 198.0565 -24.826468) (xy 386.823966 -24.826468)
			(xy 386.823966 -23.230332) (xy 387.054598 -22.9997) (xy 387.380734 -22.9997) (xy 387.611366 -23.230332)
			(xy 387.611366 -23.858728) (xy 391.456418 -23.858728) (xy 391.456418 -23.532592) (xy 391.68705 -23.30196)
			(xy 393.283186 -23.30196) (xy 393.513818 -23.532592) (xy 393.513818 -23.858728) (xy 393.283186 -24.08936)
			(xy 391.68705 -24.08936) (xy 391.456418 -23.858728) (xy 387.611366 -23.858728) (xy 387.611366 -24.826468)
			(xy 398.830546 -24.826468) (xy 398.830546 -23.230332) (xy 399.061178 -22.9997) (xy 399.387314 -22.9997)
			(xy 399.617946 -23.230332) (xy 399.617946 -23.741888) (xy 410.466286 -23.741888) (xy 410.466286 -23.415752)
			(xy 410.696918 -23.18512) (xy 412.293054 -23.18512) (xy 412.523686 -23.415752) (xy 412.523686 -23.741888)
			(xy 412.293054 -23.97252) (xy 410.696918 -23.97252) (xy 410.466286 -23.741888) (xy 399.617946 -23.741888)
			(xy 399.617946 -24.826468) (xy 399.610326 -24.834088) (xy 418.269166 -24.834088) (xy 418.269166 -23.237952)
			(xy 418.499798 -23.00732) (xy 418.825934 -23.00732) (xy 419.056566 -23.237952) (xy 419.056566 -24.834088)
			(xy 418.825934 -25.06472) (xy 418.499798 -25.06472) (xy 418.269166 -24.834088) (xy 399.610326 -24.834088)
			(xy 399.387314 -25.0571) (xy 399.061178 -25.0571) (xy 398.830546 -24.826468) (xy 387.611366 -24.826468)
			(xy 387.380734 -25.0571) (xy 387.054598 -25.0571) (xy 386.823966 -24.826468) (xy 198.0565 -24.826468)
			(xy 198.0565 -24.834088) (xy 197.825868 -25.06472) (xy 197.499732 -25.06472) (xy 197.2691 -24.834088)
			(xy 178.61026 -24.834088) (xy 178.387248 -25.0571) (xy 178.061112 -25.0571) (xy 177.83048 -24.826468)
			(xy 166.6113 -24.826468) (xy 166.380668 -25.0571) (xy 166.054532 -25.0571) (xy 165.8239 -24.826468)
			(xy 0.509016 -24.826468) (xy 0.509016 -26.545204) (xy 20.872002 -26.545204) (xy 20.872046 -26.453892)
			(xy 20.880963 -26.363017) (xy 20.89867 -26.273438) (xy 20.911312 -26.229564) (xy 21.129752 -26.229564)
			(xy 21.146337 -26.229093) (xy 21.178388 -26.220547) (xy 21.207148 -26.204021) (xy 21.230671 -26.180634)
			(xy 21.23948 -26.166572) (xy 21.257779 -26.13622) (xy 21.299905 -26.07922) (xy 21.347885 -26.027052)
			(xy 21.40117 -25.980315) (xy 21.459146 -25.939544) (xy 21.489924 -25.92197) (xy 21.504479 -25.913258)
			(xy 21.528761 -25.889592) (xy 21.545974 -25.86038) (xy 21.554911 -25.827671) (xy 21.555456 -25.810718)
			(xy 21.555456 -25.59685) (xy 21.596941 -25.585662) (xy 21.681432 -25.570016) (xy 21.767 -25.562161)
			(xy 21.852928 -25.562161) (xy 21.938496 -25.570016) (xy 22.022987 -25.585662) (xy 22.064472 -25.59685)
			(xy 22.064472 -25.810718) (xy 22.064977 -25.827683) (xy 22.073864 -25.860425) (xy 22.091083 -25.889658)
			(xy 22.11541 -25.913306) (xy 22.130004 -25.92197) (xy 22.160776 -25.939556) (xy 22.218768 -25.980308)
			(xy 22.272061 -26.027037) (xy 22.320043 -26.079205) (xy 22.362161 -26.136212) (xy 22.380448 -26.166572)
			(xy 22.389252 -26.18063) (xy 22.412795 -26.203982) (xy 22.441556 -26.220486) (xy 22.473596 -26.229029)
			(xy 22.490176 -26.229564) (xy 22.708616 -26.229564) (xy 22.721236 -26.27353) (xy 22.738894 -26.363286)
			(xy 22.747728 -26.454335) (xy 22.74824 -26.500074) (xy 22.747727 -26.545195) (xy 22.739125 -26.635025)
			(xy 22.72193 -26.723613) (xy 22.709632 -26.767028) (xy 22.492208 -26.767028) (xy 22.475553 -26.767518)
			(xy 22.443378 -26.776138) (xy 22.414531 -26.792795) (xy 22.39098 -26.816351) (xy 22.382226 -26.830528)
			(xy 22.363925 -26.861225) (xy 22.32171 -26.918897) (xy 22.27352 -26.971677) (xy 22.257883 -26.985468)
			(xy 183.6039 -26.985468) (xy 183.6039 -26.659332) (xy 183.834532 -26.4287) (xy 185.430668 -26.4287)
			(xy 185.6613 -26.659332) (xy 185.6613 -26.985468) (xy 404.603712 -26.985468) (xy 404.603712 -26.659332)
			(xy 404.834344 -26.4287) (xy 406.43048 -26.4287) (xy 406.661112 -26.659332) (xy 406.661112 -26.985468)
			(xy 406.43048 -27.2161) (xy 404.834344 -27.2161) (xy 404.603712 -26.985468) (xy 185.6613 -26.985468)
			(xy 185.430668 -27.2161) (xy 183.834532 -27.2161) (xy 183.6039 -26.985468) (xy 22.257883 -26.985468)
			(xy 22.219917 -27.018951) (xy 22.161527 -27.060166) (xy 22.130512 -27.077924) (xy 22.115946 -27.086618)
			(xy 22.091669 -27.110292) (xy 22.07446 -27.13951) (xy 22.065525 -27.172222) (xy 22.06498 -27.189176)
			(xy 22.06498 -27.403044) (xy 22.023416 -27.414277) (xy 21.938758 -27.429988) (xy 21.853016 -27.437877)
			(xy 21.766912 -27.437877) (xy 21.68117 -27.429988) (xy 21.596512 -27.414277) (xy 21.554948 -27.403044)
			(xy 21.554948 -27.189176) (xy 21.554438 -27.172212) (xy 21.545551 -27.139471) (xy 21.528334 -27.110238)
			(xy 21.504009 -27.086589) (xy 21.489416 -27.077924) (xy 21.458587 -27.060291) (xy 21.400517 -27.019395)
			(xy 21.347165 -26.972511) (xy 21.299143 -26.92018) (xy 21.257006 -26.863005) (xy 21.238718 -26.83256)
			(xy 21.229926 -26.818493) (xy 21.206381 -26.79514) (xy 21.177616 -26.778637) (xy 21.145571 -26.770099)
			(xy 21.12899 -26.769568) (xy 20.911058 -26.769568) (xy 20.898452 -26.725683) (xy 20.880832 -26.636088)
			(xy 20.872002 -26.545204) (xy 0.509016 -26.545204) (xy 0.509016 -35.084824) (xy 0.991888 -35.084824)
			(xy 0.991888 -34.915036) (xy 1.000101 -34.745446) (xy 1.016507 -34.576452) (xy 1.04107 -34.40845)
			(xy 1.07373 -34.241833) (xy 1.114412 -34.07699) (xy 1.16302 -33.914308) (xy 1.190752 -33.83407) (xy 1.197864 -33.813496)
			(xy 1.197864 -33.63214) (xy 1.326134 -33.50387) (xy 1.335532 -33.484312) (xy 1.370617 -33.412109)
			(xy 1.446515 -33.270632) (xy 1.528804 -33.132774) (xy 1.617313 -32.998825) (xy 1.711856 -32.869064)
			(xy 1.812235 -32.743763) (xy 1.91824 -32.623185) (xy 2.02965 -32.507581) (xy 2.087626 -32.452056)
			(xy 2.111452 -32.428781) (xy 2.153219 -32.376896) (xy 2.187589 -32.319842) (xy 2.21393 -32.258664)
			(xy 2.231759 -32.194487) (xy 2.240748 -32.12849) (xy 2.241296 -32.095186) (xy 2.241296 -28.999942)
			(xy 2.241792 -28.932998) (xy 2.249724 -28.799346) (xy 2.265559 -28.666399) (xy 2.289242 -28.534623)
			(xy 2.32069 -28.404482) (xy 2.359793 -28.276432) (xy 2.406413 -28.150923) (xy 2.460386 -28.028397)
			(xy 2.521523 -27.909284) (xy 2.589609 -27.794001) (xy 2.664404 -27.682954) (xy 2.745647 -27.576533)
			(xy 2.833051 -27.475112) (xy 2.926311 -27.379047) (xy 3.025097 -27.288676) (xy 3.129064 -27.204315)
			(xy 3.237845 -27.126261) (xy 3.35106 -27.054789) (xy 3.468309 -26.99015) (xy 3.589182 -26.932569)
			(xy 3.713254 -26.882251) (xy 3.840089 -26.839371) (xy 3.969241 -26.80408) (xy 4.100258 -26.776502)
			(xy 4.232677 -26.756734) (xy 4.366036 -26.744846) (xy 4.499864 -26.740878) (xy 4.633692 -26.744846)
			(xy 4.767051 -26.756734) (xy 4.89947 -26.776502) (xy 5.030487 -26.80408) (xy 5.159639 -26.839371)
			(xy 5.286474 -26.882251) (xy 5.410546 -26.932569) (xy 5.531419 -26.99015) (xy 5.648668 -27.054789)
			(xy 5.761883 -27.126261) (xy 5.870664 -27.204315) (xy 5.974631 -27.288676) (xy 6.073417 -27.379047)
			(xy 6.166677 -27.475112) (xy 6.254081 -27.576533) (xy 6.335324 -27.682954) (xy 6.410119 -27.794001)
			(xy 6.478205 -27.909284) (xy 6.539342 -28.028397) (xy 6.593315 -28.150923) (xy 6.639935 -28.276432)
			(xy 6.679038 -28.404482) (xy 6.710486 -28.534623) (xy 6.734169 -28.666399) (xy 6.750004 -28.799346)
			(xy 6.757936 -28.932998) (xy 6.758432 -28.999942) (xy 6.758432 -29.472128) (xy 183.83504 -29.472128)
			(xy 183.83504 -29.145992) (xy 184.065672 -28.91536) (xy 185.661808 -28.91536) (xy 185.89244 -29.145992)
			(xy 185.89244 -29.472128) (xy 404.834852 -29.472128) (xy 404.834852 -29.145992) (xy 405.065484 -28.91536)
			(xy 406.66162 -28.91536) (xy 406.892252 -29.145992) (xy 406.892252 -29.472128) (xy 406.66162 -29.70276)
			(xy 405.065484 -29.70276) (xy 404.834852 -29.472128) (xy 185.89244 -29.472128) (xy 185.661808 -29.70276)
			(xy 184.065672 -29.70276) (xy 183.83504 -29.472128) (xy 6.758432 -29.472128) (xy 6.758432 -30.897068)
			(xy 167.656256 -30.897068) (xy 167.656256 -30.570932) (xy 167.886888 -30.3403) (xy 169.483024 -30.3403)
			(xy 169.713656 -30.570932) (xy 169.713656 -30.897068) (xy 169.483024 -31.1277) (xy 167.886888 -31.1277)
			(xy 167.656256 -30.897068) (xy 6.758432 -30.897068) (xy 6.758432 -31.158688) (xy 174.856394 -31.158688)
			(xy 174.856394 -30.832552) (xy 175.087026 -30.60192) (xy 176.683162 -30.60192) (xy 176.839118 -30.757876)
			(xy 189.06617 -30.757876) (xy 189.06617 -30.43174) (xy 189.296802 -30.201108) (xy 190.892938 -30.201108)
			(xy 191.12357 -30.43174) (xy 191.12357 -30.726888) (xy 193.866262 -30.726888) (xy 193.866262 -30.400752)
			(xy 194.096894 -30.17012) (xy 195.69303 -30.17012) (xy 195.923662 -30.400752) (xy 195.923662 -30.726888)
			(xy 195.753482 -30.897068) (xy 388.656068 -30.897068) (xy 388.656068 -30.570932) (xy 388.8867 -30.3403)
			(xy 390.482836 -30.3403) (xy 390.713468 -30.570932) (xy 390.713468 -30.897068) (xy 390.482836 -31.1277)
			(xy 388.8867 -31.1277) (xy 388.656068 -30.897068) (xy 195.753482 -30.897068) (xy 195.69303 -30.95752)
			(xy 194.096894 -30.95752) (xy 193.866262 -30.726888) (xy 191.12357 -30.726888) (xy 191.12357 -30.757876)
			(xy 190.892938 -30.988508) (xy 189.296802 -30.988508) (xy 189.06617 -30.757876) (xy 176.839118 -30.757876)
			(xy 176.913794 -30.832552) (xy 176.913794 -31.158688) (xy 395.856206 -31.158688) (xy 395.856206 -30.832552)
			(xy 396.086838 -30.60192) (xy 397.682974 -30.60192) (xy 397.83893 -30.757876) (xy 410.065982 -30.757876)
			(xy 410.065982 -30.43174) (xy 410.296614 -30.201108) (xy 411.89275 -30.201108) (xy 412.123382 -30.43174)
			(xy 412.123382 -30.726888) (xy 414.866074 -30.726888) (xy 414.866074 -30.400752) (xy 415.096706 -30.17012)
			(xy 416.692842 -30.17012) (xy 416.923474 -30.400752) (xy 416.923474 -30.726888) (xy 416.692842 -30.95752)
			(xy 415.096706 -30.95752) (xy 414.866074 -30.726888) (xy 412.123382 -30.726888) (xy 412.123382 -30.757876)
			(xy 411.89275 -30.988508) (xy 410.296614 -30.988508) (xy 410.065982 -30.757876) (xy 397.83893 -30.757876)
			(xy 397.913606 -30.832552) (xy 397.913606 -31.158688) (xy 397.682974 -31.38932) (xy 396.086838 -31.38932)
			(xy 395.856206 -31.158688) (xy 176.913794 -31.158688) (xy 176.683162 -31.38932) (xy 175.087026 -31.38932)
			(xy 174.856394 -31.158688) (xy 6.758432 -31.158688) (xy 6.758432 -32.095186) (xy 6.75903 -32.128484)
			(xy 6.761875 -32.149288) (xy 170.056302 -32.149288) (xy 170.056302 -31.823152) (xy 170.286934 -31.59252)
			(xy 171.88307 -31.59252) (xy 172.113702 -31.823152) (xy 172.113702 -31.844488) (xy 191.48044 -31.844488)
			(xy 191.48044 -31.518352) (xy 191.711072 -31.28772) (xy 193.307208 -31.28772) (xy 193.53784 -31.518352)
			(xy 193.53784 -31.844488) (xy 193.307208 -32.07512) (xy 191.711072 -32.07512) (xy 191.48044 -31.844488)
			(xy 172.113702 -31.844488) (xy 172.113702 -32.149288) (xy 391.056114 -32.149288) (xy 391.056114 -31.823152)
			(xy 391.286746 -31.59252) (xy 392.882882 -31.59252) (xy 393.113514 -31.823152) (xy 393.113514 -31.844488)
			(xy 412.480252 -31.844488) (xy 412.480252 -31.518352) (xy 412.710884 -31.28772) (xy 414.30702 -31.28772)
			(xy 414.537652 -31.518352) (xy 414.537652 -31.844488) (xy 414.30702 -32.07512) (xy 412.710884 -32.07512)
			(xy 412.480252 -31.844488) (xy 393.113514 -31.844488) (xy 393.113514 -32.149288) (xy 392.882882 -32.37992)
			(xy 391.286746 -32.37992) (xy 391.056114 -32.149288) (xy 172.113702 -32.149288) (xy 171.88307 -32.37992)
			(xy 170.286934 -32.37992) (xy 170.056302 -32.149288) (xy 6.761875 -32.149288) (xy 6.768053 -32.194467)
			(xy 6.785895 -32.258629) (xy 6.81223 -32.319798) (xy 6.846577 -32.376855) (xy 6.888306 -32.428757)
			(xy 6.912102 -32.452056) (xy 6.970087 -32.507573) (xy 7.081498 -32.623175) (xy 7.187504 -32.743753)
			(xy 7.287884 -32.869054) (xy 7.382426 -32.998816) (xy 7.470933 -33.132768) (xy 7.553219 -33.270628)
			(xy 7.629113 -33.412108) (xy 7.664196 -33.484312) (xy 7.673594 -33.50387) (xy 7.801864 -33.63214)
			(xy 7.801864 -33.639119) (xy 165.265595 -33.639119) (xy 165.265595 -33.540833) (xy 165.273504 -33.442866)
			(xy 165.28927 -33.345853) (xy 165.312791 -33.250424) (xy 165.343915 -33.157196) (xy 165.38244 -33.066775)
			(xy 165.428115 -32.979748) (xy 165.480646 -32.896677) (xy 165.53969 -32.818104) (xy 165.604865 -32.744536)
			(xy 165.675749 -32.676451) (xy 165.751882 -32.61429) (xy 165.832769 -32.558458) (xy 165.917887 -32.509315)
			(xy 166.006684 -32.467181) (xy 166.098582 -32.432328) (xy 166.192988 -32.404983) (xy 166.289287 -32.385324)
			(xy 166.386856 -32.373477) (xy 166.485062 -32.369519) (xy 166.583268 -32.373477) (xy 166.680837 -32.385324)
			(xy 166.777136 -32.404983) (xy 166.871542 -32.432328) (xy 166.96344 -32.467181) (xy 167.052237 -32.509315)
			(xy 167.137355 -32.558458) (xy 167.218242 -32.61429) (xy 167.294375 -32.676451) (xy 167.365259 -32.744536)
			(xy 167.430434 -32.818104) (xy 167.489478 -32.896677) (xy 167.542009 -32.979748) (xy 167.587684 -33.066775)
			(xy 167.593944 -33.081468) (xy 172.481748 -33.081468) (xy 172.481748 -32.755332) (xy 172.71238 -32.5247)
			(xy 174.308516 -32.5247) (xy 174.539148 -32.755332) (xy 174.539148 -33.081468) (xy 174.308516 -33.3121)
			(xy 172.71238 -33.3121) (xy 172.481748 -33.081468) (xy 167.593944 -33.081468) (xy 167.626209 -33.157196)
			(xy 167.657333 -33.250424) (xy 167.680854 -33.345853) (xy 167.69662 -33.442866) (xy 167.704529 -33.540833)
			(xy 167.705024 -33.589976) (xy 167.704529 -33.639119) (xy 167.704526 -33.63915) (xy 177.264809 -33.63915)
			(xy 177.264809 -33.540802) (xy 177.272723 -33.442774) (xy 177.288499 -33.345701) (xy 177.312035 -33.250211)
			(xy 177.343178 -33.156926) (xy 177.381727 -33.066448) (xy 177.427431 -32.979366) (xy 177.479994 -32.896244)
			(xy 177.539075 -32.817621) (xy 177.604292 -32.744008) (xy 177.67522 -32.67588) (xy 177.7514 -32.613681)
			(xy 177.832338 -32.557813) (xy 177.917509 -32.50864) (xy 178.006361 -32.466479) (xy 178.098317 -32.431605)
			(xy 178.192781 -32.404243) (xy 178.289141 -32.384571) (xy 178.386771 -32.372717) (xy 178.485038 -32.368757)
			(xy 178.583305 -32.372717) (xy 178.680935 -32.384571) (xy 178.777295 -32.404243) (xy 178.871759 -32.431605)
			(xy 178.963715 -32.466479) (xy 179.052567 -32.50864) (xy 179.137738 -32.557813) (xy 179.218676 -32.613681)
			(xy 179.294856 -32.67588) (xy 179.365784 -32.744008) (xy 179.431001 -32.817621) (xy 179.490082 -32.896244)
			(xy 179.542645 -32.979366) (xy 179.588349 -33.066448) (xy 179.626898 -33.156926) (xy 179.658041 -33.250211)
			(xy 179.681577 -33.345701) (xy 179.697353 -33.442774) (xy 179.705267 -33.540802) (xy 179.705762 -33.589976)
			(xy 179.705267 -33.639119) (xy 184.275463 -33.639119) (xy 184.275463 -33.540833) (xy 184.283372 -33.442866)
			(xy 184.299138 -33.345853) (xy 184.322659 -33.250424) (xy 184.353783 -33.157196) (xy 184.392308 -33.066775)
			(xy 184.437983 -32.979748) (xy 184.490514 -32.896677) (xy 184.549558 -32.818104) (xy 184.614733 -32.744536)
			(xy 184.685617 -32.676451) (xy 184.76175 -32.61429) (xy 184.842637 -32.558458) (xy 184.927755 -32.509315)
			(xy 185.016552 -32.467181) (xy 185.10845 -32.432328) (xy 185.202856 -32.404983) (xy 185.299155 -32.385324)
			(xy 185.396724 -32.373477) (xy 185.49493 -32.369519) (xy 185.593136 -32.373477) (xy 185.690705 -32.385324)
			(xy 185.787004 -32.404983) (xy 185.88141 -32.432328) (xy 185.973308 -32.467181) (xy 186.062105 -32.509315)
			(xy 186.147223 -32.558458) (xy 186.22811 -32.61429) (xy 186.304243 -32.676451) (xy 186.375127 -32.744536)
			(xy 186.440302 -32.818104) (xy 186.499346 -32.896677) (xy 186.551877 -32.979748) (xy 186.597552 -33.066775)
			(xy 186.636077 -33.157196) (xy 186.667201 -33.250424) (xy 186.690722 -33.345853) (xy 186.706488 -33.442866)
			(xy 186.714397 -33.540833) (xy 186.714892 -33.589976) (xy 186.714397 -33.639119) (xy 186.714394 -33.63915)
			(xy 196.274677 -33.63915) (xy 196.274677 -33.540802) (xy 196.282591 -33.442774) (xy 196.298367 -33.345701)
			(xy 196.321903 -33.250211) (xy 196.353046 -33.156926) (xy 196.391595 -33.066448) (xy 196.437299 -32.979366)
			(xy 196.489862 -32.896244) (xy 196.548943 -32.817621) (xy 196.61416 -32.744008) (xy 196.685088 -32.67588)
			(xy 196.761268 -32.613681) (xy 196.842206 -32.557813) (xy 196.927377 -32.50864) (xy 197.016229 -32.466479)
			(xy 197.108185 -32.431605) (xy 197.202649 -32.404243) (xy 197.299009 -32.384571) (xy 197.396639 -32.372717)
			(xy 197.494906 -32.368757) (xy 197.593173 -32.372717) (xy 197.690803 -32.384571) (xy 197.787163 -32.404243)
			(xy 197.881627 -32.431605) (xy 197.973583 -32.466479) (xy 198.062435 -32.50864) (xy 198.147606 -32.557813)
			(xy 198.228544 -32.613681) (xy 198.304724 -32.67588) (xy 198.375652 -32.744008) (xy 198.440869 -32.817621)
			(xy 198.49995 -32.896244) (xy 198.552513 -32.979366) (xy 198.598217 -33.066448) (xy 198.636766 -33.156926)
			(xy 198.667909 -33.250211) (xy 198.691445 -33.345701) (xy 198.707221 -33.442774) (xy 198.715135 -33.540802)
			(xy 198.71563 -33.589976) (xy 198.715135 -33.639119) (xy 386.265407 -33.639119) (xy 386.265407 -33.540833)
			(xy 386.273316 -33.442866) (xy 386.289082 -33.345853) (xy 386.312603 -33.250424) (xy 386.343727 -33.157196)
			(xy 386.382252 -33.066775) (xy 386.427927 -32.979748) (xy 386.480458 -32.896677) (xy 386.539502 -32.818104)
			(xy 386.604677 -32.744536) (xy 386.675561 -32.676451) (xy 386.751694 -32.61429) (xy 386.832581 -32.558458)
			(xy 386.917699 -32.509315) (xy 387.006496 -32.467181) (xy 387.098394 -32.432328) (xy 387.1928 -32.404983)
			(xy 387.289099 -32.385324) (xy 387.386668 -32.373477) (xy 387.484874 -32.369519) (xy 387.58308 -32.373477)
			(xy 387.680649 -32.385324) (xy 387.776948 -32.404983) (xy 387.871354 -32.432328) (xy 387.963252 -32.467181)
			(xy 388.052049 -32.509315) (xy 388.137167 -32.558458) (xy 388.218054 -32.61429) (xy 388.294187 -32.676451)
			(xy 388.365071 -32.744536) (xy 388.430246 -32.818104) (xy 388.48929 -32.896677) (xy 388.541821 -32.979748)
			(xy 388.587496 -33.066775) (xy 388.593756 -33.081468) (xy 393.48156 -33.081468) (xy 393.48156 -32.755332)
			(xy 393.712192 -32.5247) (xy 395.308328 -32.5247) (xy 395.53896 -32.755332) (xy 395.53896 -33.081468)
			(xy 395.308328 -33.3121) (xy 393.712192 -33.3121) (xy 393.48156 -33.081468) (xy 388.593756 -33.081468)
			(xy 388.626021 -33.157196) (xy 388.657145 -33.250424) (xy 388.680666 -33.345853) (xy 388.696432 -33.442866)
			(xy 388.704341 -33.540833) (xy 388.704836 -33.589976) (xy 388.704341 -33.639119) (xy 388.704338 -33.63915)
			(xy 398.264621 -33.63915) (xy 398.264621 -33.540802) (xy 398.272535 -33.442774) (xy 398.288311 -33.345701)
			(xy 398.311847 -33.250211) (xy 398.34299 -33.156926) (xy 398.381539 -33.066448) (xy 398.427243 -32.979366)
			(xy 398.479806 -32.896244) (xy 398.538887 -32.817621) (xy 398.604104 -32.744008) (xy 398.675032 -32.67588)
			(xy 398.751212 -32.613681) (xy 398.83215 -32.557813) (xy 398.917321 -32.50864) (xy 399.006173 -32.466479)
			(xy 399.098129 -32.431605) (xy 399.192593 -32.404243) (xy 399.288953 -32.384571) (xy 399.386583 -32.372717)
			(xy 399.48485 -32.368757) (xy 399.583117 -32.372717) (xy 399.680747 -32.384571) (xy 399.777107 -32.404243)
			(xy 399.871571 -32.431605) (xy 399.963527 -32.466479) (xy 400.052379 -32.50864) (xy 400.13755 -32.557813)
			(xy 400.218488 -32.613681) (xy 400.294668 -32.67588) (xy 400.365596 -32.744008) (xy 400.430813 -32.817621)
			(xy 400.489894 -32.896244) (xy 400.542457 -32.979366) (xy 400.588161 -33.066448) (xy 400.62671 -33.156926)
			(xy 400.657853 -33.250211) (xy 400.681389 -33.345701) (xy 400.697165 -33.442774) (xy 400.705079 -33.540802)
			(xy 400.705574 -33.589976) (xy 400.705079 -33.639119) (xy 405.275529 -33.639119) (xy 405.275529 -33.540833)
			(xy 405.283438 -33.442866) (xy 405.299204 -33.345853) (xy 405.322725 -33.250424) (xy 405.353849 -33.157196)
			(xy 405.392374 -33.066775) (xy 405.438049 -32.979748) (xy 405.49058 -32.896677) (xy 405.549624 -32.818104)
			(xy 405.614799 -32.744536) (xy 405.685683 -32.676451) (xy 405.761816 -32.61429) (xy 405.842703 -32.558458)
			(xy 405.927821 -32.509315) (xy 406.016618 -32.467181) (xy 406.108516 -32.432328) (xy 406.202922 -32.404983)
			(xy 406.299221 -32.385324) (xy 406.39679 -32.373477) (xy 406.494996 -32.369519) (xy 406.593202 -32.373477)
			(xy 406.690771 -32.385324) (xy 406.78707 -32.404983) (xy 406.881476 -32.432328) (xy 406.973374 -32.467181)
			(xy 407.062171 -32.509315) (xy 407.147289 -32.558458) (xy 407.228176 -32.61429) (xy 407.304309 -32.676451)
			(xy 407.375193 -32.744536) (xy 407.440368 -32.818104) (xy 407.499412 -32.896677) (xy 407.551943 -32.979748)
			(xy 407.597618 -33.066775) (xy 407.636143 -33.157196) (xy 407.667267 -33.250424) (xy 407.690788 -33.345853)
			(xy 407.706554 -33.442866) (xy 407.714463 -33.540833) (xy 407.714958 -33.589976) (xy 407.714463 -33.639119)
			(xy 407.71446 -33.63915) (xy 417.274743 -33.63915) (xy 417.274743 -33.540802) (xy 417.282657 -33.442774)
			(xy 417.298433 -33.345701) (xy 417.321969 -33.250211) (xy 417.353112 -33.156926) (xy 417.391661 -33.066448)
			(xy 417.437365 -32.979366) (xy 417.489928 -32.896244) (xy 417.549009 -32.817621) (xy 417.614226 -32.744008)
			(xy 417.685154 -32.67588) (xy 417.761334 -32.613681) (xy 417.842272 -32.557813) (xy 417.927443 -32.50864)
			(xy 418.016295 -32.466479) (xy 418.108251 -32.431605) (xy 418.202715 -32.404243) (xy 418.299075 -32.384571)
			(xy 418.396705 -32.372717) (xy 418.494972 -32.368757) (xy 418.593239 -32.372717) (xy 418.690869 -32.384571)
			(xy 418.787229 -32.404243) (xy 418.881693 -32.431605) (xy 418.973649 -32.466479) (xy 419.062501 -32.50864)
			(xy 419.147672 -32.557813) (xy 419.22861 -32.613681) (xy 419.30479 -32.67588) (xy 419.375718 -32.744008)
			(xy 419.440935 -32.817621) (xy 419.500016 -32.896244) (xy 419.552579 -32.979366) (xy 419.598283 -33.066448)
			(xy 419.636832 -33.156926) (xy 419.667975 -33.250211) (xy 419.691511 -33.345701) (xy 419.707287 -33.442774)
			(xy 419.715201 -33.540802) (xy 419.715696 -33.589976) (xy 419.715201 -33.63915) (xy 419.707287 -33.737178)
			(xy 419.691511 -33.834251) (xy 419.667975 -33.929741) (xy 419.636832 -34.023026) (xy 419.598283 -34.113504)
			(xy 419.552579 -34.200586) (xy 419.500016 -34.283708) (xy 419.440935 -34.362331) (xy 419.375718 -34.435944)
			(xy 419.30479 -34.504072) (xy 419.22861 -34.566271) (xy 419.147672 -34.622139) (xy 419.062501 -34.671312)
			(xy 418.973649 -34.713473) (xy 418.881693 -34.748347) (xy 418.787229 -34.775709) (xy 418.690869 -34.795381)
			(xy 418.593239 -34.807235) (xy 418.494972 -34.811196) (xy 418.396705 -34.807235) (xy 418.299075 -34.795381)
			(xy 418.202715 -34.775709) (xy 418.108251 -34.748347) (xy 418.016295 -34.713473) (xy 417.927443 -34.671312)
			(xy 417.842272 -34.622139) (xy 417.761334 -34.566271) (xy 417.685154 -34.504072) (xy 417.614226 -34.435944)
			(xy 417.549009 -34.362331) (xy 417.489928 -34.283708) (xy 417.437365 -34.200586) (xy 417.391661 -34.113504)
			(xy 417.353112 -34.023026) (xy 417.321969 -33.929741) (xy 417.298433 -33.834251) (xy 417.282657 -33.737178)
			(xy 417.274743 -33.63915) (xy 407.71446 -33.63915) (xy 407.706554 -33.737086) (xy 407.690788 -33.834099)
			(xy 407.667267 -33.929528) (xy 407.636143 -34.022756) (xy 407.597618 -34.113177) (xy 407.551943 -34.200205)
			(xy 407.499412 -34.283275) (xy 407.440368 -34.361848) (xy 407.375193 -34.435416) (xy 407.304309 -34.503501)
			(xy 407.228176 -34.565662) (xy 407.147289 -34.621494) (xy 407.062171 -34.670637) (xy 406.973374 -34.712771)
			(xy 406.881476 -34.747624) (xy 406.78707 -34.774969) (xy 406.690771 -34.794628) (xy 406.593202 -34.806475)
			(xy 406.494996 -34.810433) (xy 406.39679 -34.806475) (xy 406.299221 -34.794628) (xy 406.202922 -34.774969)
			(xy 406.108516 -34.747624) (xy 406.016618 -34.712771) (xy 405.927821 -34.670637) (xy 405.842703 -34.621494)
			(xy 405.761816 -34.565662) (xy 405.685683 -34.503501) (xy 405.614799 -34.435416) (xy 405.549624 -34.361848)
			(xy 405.49058 -34.283275) (xy 405.438049 -34.200205) (xy 405.392374 -34.113177) (xy 405.353849 -34.022756)
			(xy 405.322725 -33.929528) (xy 405.299204 -33.834099) (xy 405.283438 -33.737086) (xy 405.275529 -33.639119)
			(xy 400.705079 -33.639119) (xy 400.705079 -33.63915) (xy 400.697165 -33.737178) (xy 400.681389 -33.834251)
			(xy 400.657853 -33.929741) (xy 400.62671 -34.023026) (xy 400.588161 -34.113504) (xy 400.542457 -34.200586)
			(xy 400.489894 -34.283708) (xy 400.430813 -34.362331) (xy 400.365596 -34.435944) (xy 400.294668 -34.504072)
			(xy 400.218488 -34.566271) (xy 400.13755 -34.622139) (xy 400.052379 -34.671312) (xy 399.963527 -34.713473)
			(xy 399.871571 -34.748347) (xy 399.777107 -34.775709) (xy 399.680747 -34.795381) (xy 399.583117 -34.807235)
			(xy 399.48485 -34.811196) (xy 399.386583 -34.807235) (xy 399.288953 -34.795381) (xy 399.192593 -34.775709)
			(xy 399.098129 -34.748347) (xy 399.006173 -34.713473) (xy 398.917321 -34.671312) (xy 398.83215 -34.622139)
			(xy 398.751212 -34.566271) (xy 398.675032 -34.504072) (xy 398.604104 -34.435944) (xy 398.538887 -34.362331)
			(xy 398.479806 -34.283708) (xy 398.427243 -34.200586) (xy 398.381539 -34.113504) (xy 398.34299 -34.023026)
			(xy 398.311847 -33.929741) (xy 398.288311 -33.834251) (xy 398.272535 -33.737178) (xy 398.264621 -33.63915)
			(xy 388.704338 -33.63915) (xy 388.696432 -33.737086) (xy 388.680666 -33.834099) (xy 388.657145 -33.929528)
			(xy 388.626021 -34.022756) (xy 388.587496 -34.113177) (xy 388.541821 -34.200205) (xy 388.48929 -34.283275)
			(xy 388.430246 -34.361848) (xy 388.365071 -34.435416) (xy 388.294187 -34.503501) (xy 388.218054 -34.565662)
			(xy 388.137167 -34.621494) (xy 388.052049 -34.670637) (xy 387.963252 -34.712771) (xy 387.871354 -34.747624)
			(xy 387.776948 -34.774969) (xy 387.680649 -34.794628) (xy 387.58308 -34.806475) (xy 387.484874 -34.810433)
			(xy 387.386668 -34.806475) (xy 387.289099 -34.794628) (xy 387.1928 -34.774969) (xy 387.098394 -34.747624)
			(xy 387.006496 -34.712771) (xy 386.917699 -34.670637) (xy 386.832581 -34.621494) (xy 386.751694 -34.565662)
			(xy 386.675561 -34.503501) (xy 386.604677 -34.435416) (xy 386.539502 -34.361848) (xy 386.480458 -34.283275)
			(xy 386.427927 -34.200205) (xy 386.382252 -34.113177) (xy 386.343727 -34.022756) (xy 386.312603 -33.929528)
			(xy 386.289082 -33.834099) (xy 386.273316 -33.737086) (xy 386.265407 -33.639119) (xy 198.715135 -33.639119)
			(xy 198.715135 -33.63915) (xy 198.707221 -33.737178) (xy 198.691445 -33.834251) (xy 198.667909 -33.929741)
			(xy 198.636766 -34.023026) (xy 198.598217 -34.113504) (xy 198.552513 -34.200586) (xy 198.49995 -34.283708)
			(xy 198.440869 -34.362331) (xy 198.375652 -34.435944) (xy 198.304724 -34.504072) (xy 198.228544 -34.566271)
			(xy 198.147606 -34.622139) (xy 198.062435 -34.671312) (xy 197.973583 -34.713473) (xy 197.881627 -34.748347)
			(xy 197.787163 -34.775709) (xy 197.690803 -34.795381) (xy 197.593173 -34.807235) (xy 197.494906 -34.811196)
			(xy 197.396639 -34.807235) (xy 197.299009 -34.795381) (xy 197.202649 -34.775709) (xy 197.108185 -34.748347)
			(xy 197.016229 -34.713473) (xy 196.927377 -34.671312) (xy 196.842206 -34.622139) (xy 196.761268 -34.566271)
			(xy 196.685088 -34.504072) (xy 196.61416 -34.435944) (xy 196.548943 -34.362331) (xy 196.489862 -34.283708)
			(xy 196.437299 -34.200586) (xy 196.391595 -34.113504) (xy 196.353046 -34.023026) (xy 196.321903 -33.929741)
			(xy 196.298367 -33.834251) (xy 196.282591 -33.737178) (xy 196.274677 -33.63915) (xy 186.714394 -33.63915)
			(xy 186.706488 -33.737086) (xy 186.690722 -33.834099) (xy 186.667201 -33.929528) (xy 186.636077 -34.022756)
			(xy 186.597552 -34.113177) (xy 186.551877 -34.200205) (xy 186.499346 -34.283275) (xy 186.440302 -34.361848)
			(xy 186.375127 -34.435416) (xy 186.304243 -34.503501) (xy 186.22811 -34.565662) (xy 186.147223 -34.621494)
			(xy 186.062105 -34.670637) (xy 185.973308 -34.712771) (xy 185.88141 -34.747624) (xy 185.787004 -34.774969)
			(xy 185.690705 -34.794628) (xy 185.593136 -34.806475) (xy 185.49493 -34.810433) (xy 185.396724 -34.806475)
			(xy 185.299155 -34.794628) (xy 185.202856 -34.774969) (xy 185.10845 -34.747624) (xy 185.016552 -34.712771)
			(xy 184.927755 -34.670637) (xy 184.842637 -34.621494) (xy 184.76175 -34.565662) (xy 184.685617 -34.503501)
			(xy 184.614733 -34.435416) (xy 184.549558 -34.361848) (xy 184.490514 -34.283275) (xy 184.437983 -34.200205)
			(xy 184.392308 -34.113177) (xy 184.353783 -34.022756) (xy 184.322659 -33.929528) (xy 184.299138 -33.834099)
			(xy 184.283372 -33.737086) (xy 184.275463 -33.639119) (xy 179.705267 -33.639119) (xy 179.705267 -33.63915)
			(xy 179.697353 -33.737178) (xy 179.681577 -33.834251) (xy 179.658041 -33.929741) (xy 179.626898 -34.023026)
			(xy 179.588349 -34.113504) (xy 179.542645 -34.200586) (xy 179.490082 -34.283708) (xy 179.431001 -34.362331)
			(xy 179.365784 -34.435944) (xy 179.294856 -34.504072) (xy 179.218676 -34.566271) (xy 179.137738 -34.622139)
			(xy 179.052567 -34.671312) (xy 178.963715 -34.713473) (xy 178.871759 -34.748347) (xy 178.777295 -34.775709)
			(xy 178.680935 -34.795381) (xy 178.583305 -34.807235) (xy 178.485038 -34.811196) (xy 178.386771 -34.807235)
			(xy 178.289141 -34.795381) (xy 178.192781 -34.775709) (xy 178.098317 -34.748347) (xy 178.006361 -34.713473)
			(xy 177.917509 -34.671312) (xy 177.832338 -34.622139) (xy 177.7514 -34.566271) (xy 177.67522 -34.504072)
			(xy 177.604292 -34.435944) (xy 177.539075 -34.362331) (xy 177.479994 -34.283708) (xy 177.427431 -34.200586)
			(xy 177.381727 -34.113504) (xy 177.343178 -34.023026) (xy 177.312035 -33.929741) (xy 177.288499 -33.834251)
			(xy 177.272723 -33.737178) (xy 177.264809 -33.63915) (xy 167.704526 -33.63915) (xy 167.69662 -33.737086)
			(xy 167.680854 -33.834099) (xy 167.657333 -33.929528) (xy 167.626209 -34.022756) (xy 167.587684 -34.113177)
			(xy 167.542009 -34.200205) (xy 167.489478 -34.283275) (xy 167.430434 -34.361848) (xy 167.365259 -34.435416)
			(xy 167.294375 -34.503501) (xy 167.218242 -34.565662) (xy 167.137355 -34.621494) (xy 167.052237 -34.670637)
			(xy 166.96344 -34.712771) (xy 166.871542 -34.747624) (xy 166.777136 -34.774969) (xy 166.680837 -34.794628)
			(xy 166.583268 -34.806475) (xy 166.485062 -34.810433) (xy 166.386856 -34.806475) (xy 166.289287 -34.794628)
			(xy 166.192988 -34.774969) (xy 166.098582 -34.747624) (xy 166.006684 -34.712771) (xy 165.917887 -34.670637)
			(xy 165.832769 -34.621494) (xy 165.751882 -34.565662) (xy 165.675749 -34.503501) (xy 165.604865 -34.435416)
			(xy 165.53969 -34.361848) (xy 165.480646 -34.283275) (xy 165.428115 -34.200205) (xy 165.38244 -34.113177)
			(xy 165.343915 -34.022756) (xy 165.312791 -33.929528) (xy 165.28927 -33.834099) (xy 165.273504 -33.737086)
			(xy 165.265595 -33.639119) (xy 7.801864 -33.639119) (xy 7.801864 -33.813496) (xy 7.808976 -33.83407)
			(xy 7.836708 -33.914308) (xy 7.885316 -34.07699) (xy 7.925998 -34.241833) (xy 7.958658 -34.40845)
			(xy 7.983221 -34.576452) (xy 7.999628 -34.745446) (xy 8.007841 -34.915036) (xy 8.007841 -35.084824)
			(xy 7.999628 -35.254414) (xy 7.983221 -35.423408) (xy 7.958658 -35.59141) (xy 7.925998 -35.758027)
			(xy 7.885316 -35.92287) (xy 7.836708 -36.085552) (xy 7.808976 -36.16579) (xy 7.801864 -36.186364)
			(xy 7.801864 -36.367974) (xy 7.67334 -36.496498) (xy 7.663942 -36.516056) (xy 7.626819 -36.592356)
			(xy 7.546175 -36.74167) (xy 7.458407 -36.88691) (xy 7.363719 -37.027738) (xy 7.262334 -37.163823)
			(xy 7.154488 -37.294847) (xy 7.040434 -37.420504) (xy 6.960886 -37.500052) (xy 9.403341 -37.500052)
			(xy 9.407346 -37.412144) (xy 9.419329 -37.324964) (xy 9.439189 -37.239235) (xy 9.466764 -37.155667)
			(xy 9.501823 -37.074953) (xy 9.544076 -36.997761) (xy 9.593174 -36.924732) (xy 9.64871 -36.85647)
			(xy 9.710222 -36.79354) (xy 9.777203 -36.736466) (xy 9.849096 -36.685718) (xy 9.925305 -36.641718)
			(xy 10.0052 -36.604831) (xy 10.088119 -36.575362) (xy 10.173374 -36.553555) (xy 10.260258 -36.539591)
			(xy 10.348052 -36.533585) (xy 10.436029 -36.535589) (xy 10.523459 -36.545584) (xy 10.609618 -36.563488)
			(xy 10.693792 -36.589152) (xy 10.775283 -36.622365) (xy 10.853417 -36.662851) (xy 10.927545 -36.710273)
			(xy 10.997053 -36.76424) (xy 11.061367 -36.824305) (xy 11.119951 -36.889969) (xy 11.172322 -36.960688)
			(xy 11.218045 -37.035876) (xy 11.256742 -37.114911) (xy 11.288091 -37.197137) (xy 11.311833 -37.281873)
			(xy 11.327771 -37.368417) (xy 11.335773 -37.456052) (xy 11.336274 -37.500052) (xy 11.335773 -37.544052)
			(xy 11.327771 -37.631687) (xy 11.311833 -37.718231) (xy 11.288091 -37.802967) (xy 11.256742 -37.885193)
			(xy 11.218045 -37.964228) (xy 11.172322 -38.039416) (xy 11.119951 -38.110135) (xy 11.061367 -38.175799)
			(xy 10.997053 -38.235864) (xy 10.927545 -38.289831) (xy 10.853417 -38.337253) (xy 10.775283 -38.377739)
			(xy 10.693792 -38.410952) (xy 10.609618 -38.436616) (xy 10.523459 -38.45452) (xy 10.436029 -38.464515)
			(xy 10.348052 -38.466519) (xy 10.260258 -38.460513) (xy 10.173374 -38.446549) (xy 10.088119 -38.424742)
			(xy 10.0052 -38.395273) (xy 9.925305 -38.358386) (xy 9.849096 -38.314386) (xy 9.777203 -38.263638)
			(xy 9.710222 -38.206564) (xy 9.64871 -38.143634) (xy 9.593174 -38.075372) (xy 9.544076 -38.002343)
			(xy 9.501823 -37.925151) (xy 9.466764 -37.844437) (xy 9.439189 -37.760869) (xy 9.419329 -37.67514)
			(xy 9.407346 -37.58796) (xy 9.403341 -37.500052) (xy 6.960886 -37.500052) (xy 6.920438 -37.5405)
			(xy 6.794781 -37.654554) (xy 6.663757 -37.762401) (xy 6.527672 -37.863786) (xy 6.386845 -37.958474)
			(xy 6.241604 -38.046242) (xy 6.092291 -38.126887) (xy 6.01599 -38.164008) (xy 5.996432 -38.173406)
			(xy 5.867654 -38.302184) (xy 5.685536 -38.302184) (xy 5.665216 -38.309296) (xy 5.58501 -38.337004)
			(xy 5.422395 -38.385567) (xy 5.257623 -38.426211) (xy 5.091078 -38.458842) (xy 4.92315 -38.483381)
			(xy 4.754232 -38.499773) (xy 4.58472 -38.507978) (xy 4.415008 -38.507978) (xy 4.245496 -38.499773)
			(xy 4.076578 -38.483381) (xy 3.90865 -38.458842) (xy 3.742105 -38.426211) (xy 3.577333 -38.385567)
			(xy 3.414718 -38.337004) (xy 3.334512 -38.309296) (xy 3.314192 -38.302184) (xy 3.132074 -38.302184)
			(xy 3.003296 -38.173406) (xy 2.983738 -38.164008) (xy 2.907438 -38.126885) (xy 2.758124 -38.046241)
			(xy 2.612884 -37.958473) (xy 2.472056 -37.863785) (xy 2.335971 -37.7624) (xy 2.204947 -37.654554)
			(xy 2.07929 -37.5405) (xy 1.959294 -37.420504) (xy 1.845239 -37.294847) (xy 1.737393 -37.163823)
			(xy 1.636008 -37.027738) (xy 1.54132 -36.886911) (xy 1.453552 -36.74167) (xy 1.372907 -36.592357)
			(xy 1.335786 -36.516056) (xy 1.326388 -36.496498) (xy 1.197864 -36.367974) (xy 1.197864 -36.186364)
			(xy 1.190752 -36.16579) (xy 1.16302 -36.085552) (xy 1.114412 -35.92287) (xy 1.07373 -35.758027) (xy 1.04107 -35.59141)
			(xy 1.016507 -35.423408) (xy 1.000101 -35.254414) (xy 0.991888 -35.084824) (xy 0.509016 -35.084824)
			(xy 0.509016 -46.4566) (xy 0.509511 -46.473254) (xy 0.518132 -46.505427) (xy 0.534787 -46.534272)
			(xy 0.558341 -46.557823) (xy 0.587188 -46.574474) (xy 0.619362 -46.583091) (xy 0.636016 -46.5836)
			(xy 9.814052 -46.5836) (xy 9.830711 -46.583111) (xy 9.862896 -46.574498) (xy 9.891754 -46.557847)
			(xy 9.915317 -46.534292) (xy 9.93198 -46.50544) (xy 9.940605 -46.473259) (xy 9.941052 -46.4566) (xy 9.941052 -42.649902)
			(xy 9.941539 -42.609005) (xy 9.949314 -42.52758) (xy 9.964793 -42.447264) (xy 9.987838 -42.368782)
			(xy 10.018238 -42.292847) (xy 10.055718 -42.220145) (xy 10.09994 -42.151334) (xy 10.150502 -42.087039)
			(xy 10.206947 -42.027842) (xy 10.268763 -41.974278) (xy 10.335391 -41.926832) (xy 10.406227 -41.885935)
			(xy 10.480631 -41.851956) (xy 10.557927 -41.825203) (xy 10.637416 -41.80592) (xy 10.718378 -41.794279)
			(xy 10.80008 -41.790387) (xy 10.881782 -41.794279) (xy 10.962744 -41.80592) (xy 11.042233 -41.825203)
			(xy 11.119529 -41.851956) (xy 11.193933 -41.885935) (xy 11.264769 -41.926832) (xy 11.331397 -41.974278)
			(xy 11.393213 -42.027842) (xy 11.449658 -42.087039) (xy 11.50022 -42.151334) (xy 11.544442 -42.220145)
			(xy 11.581922 -42.292847) (xy 11.612322 -42.368782) (xy 11.635367 -42.447264) (xy 11.650846 -42.52758)
			(xy 11.658621 -42.609005) (xy 11.659108 -42.649902) (xy 11.659108 -45.085) (xy 11.659603 -45.101654)
			(xy 11.668224 -45.133828) (xy 11.684879 -45.162674) (xy 11.708432 -45.186226) (xy 11.737279 -45.202879)
			(xy 11.769454 -45.211498) (xy 11.786108 -45.212) (xy 12.032234 -45.212) (xy 12.057634 -45.2374) (xy 18.284698 -45.2374)
			(xy 18.310098 -45.212) (xy 50.320702 -45.212) (xy 50.346102 -45.2374) (xy 51.44389 -45.2374) (xy 51.460546 -45.236907)
			(xy 51.492722 -45.228287) (xy 51.521571 -45.211633) (xy 51.545127 -45.188079) (xy 51.561783 -45.159232)
			(xy 51.570405 -45.127056) (xy 51.57089 -45.1104) (xy 51.57089 -43.319954) (xy 51.571372 -43.266078)
			(xy 51.579063 -43.1586) (xy 51.5944 -43.051944) (xy 51.617308 -42.946655) (xy 51.647668 -42.843268)
			(xy 51.685326 -42.74231) (xy 51.73009 -42.644296) (xy 51.781732 -42.549725) (xy 51.83999 -42.459079)
			(xy 51.904565 -42.372819) (xy 51.975129 -42.291387) (xy 52.051323 -42.215195) (xy 52.132758 -42.144634)
			(xy 52.21902 -42.080061) (xy 52.309668 -42.021807) (xy 52.404241 -41.970168) (xy 52.502256 -41.925407)
			(xy 52.603215 -41.887752) (xy 52.706603 -41.857395) (xy 52.811894 -41.834491) (xy 52.91855 -41.819157)
			(xy 53.026028 -41.811471) (xy 53.079904 -41.81094) (xy 55.0799 -41.81094) (xy 55.133778 -41.811421)
			(xy 55.241259 -41.819108) (xy 55.347919 -41.834443) (xy 55.453212 -41.857348) (xy 55.556603 -41.887705)
			(xy 55.657566 -41.925362) (xy 55.755584 -41.970124) (xy 55.85016 -42.021765) (xy 55.940811 -42.080022)
			(xy 56.027075 -42.144596) (xy 56.108512 -42.21516) (xy 56.184708 -42.291354) (xy 56.255275 -42.372789)
			(xy 56.319852 -42.459051) (xy 56.378111 -42.5497) (xy 56.429755 -42.644274) (xy 56.474521 -42.742292)
			(xy 56.51218 -42.843253) (xy 56.542541 -42.946643) (xy 56.565449 -43.051936) (xy 56.580787 -43.158595)
			(xy 56.588478 -43.266076) (xy 56.588914 -43.319954) (xy 56.588914 -47.585006) (xy 76.302054 -47.585006)
			(xy 76.302054 -47.415312) (xy 76.310259 -47.245817) (xy 76.326651 -47.076917) (xy 76.351191 -46.909008)
			(xy 76.383821 -46.742481) (xy 76.424465 -46.577727) (xy 76.473029 -46.415131) (xy 76.500736 -46.334934)
			(xy 76.507848 -46.31436) (xy 76.507848 -46.132496) (xy 76.636372 -46.003972) (xy 76.64577 -45.984414)
			(xy 76.680844 -45.912205) (xy 76.756744 -45.770729) (xy 76.839035 -45.632872) (xy 76.927545 -45.498923)
			(xy 77.022089 -45.369163) (xy 77.12247 -45.243863) (xy 77.228476 -45.123285) (xy 77.339887 -45.007683)
			(xy 77.397864 -44.952158) (xy 77.421682 -44.928888) (xy 77.463394 -44.876982) (xy 77.497712 -44.819916)
			(xy 77.524005 -44.758738) (xy 77.541792 -44.694568) (xy 77.550747 -44.628583) (xy 77.55128 -44.595288)
			(xy 77.55128 -41.500044) (xy 77.551776 -41.433093) (xy 77.559709 -41.299426) (xy 77.575546 -41.166463)
			(xy 77.599232 -41.034673) (xy 77.630683 -40.904517) (xy 77.669791 -40.776453) (xy 77.716415 -40.65093)
			(xy 77.770395 -40.52839) (xy 77.831538 -40.409263) (xy 77.899632 -40.293967) (xy 77.974436 -40.182908)
			(xy 78.055688 -40.076475) (xy 78.143102 -39.975043) (xy 78.236372 -39.878967) (xy 78.335169 -39.788585)
			(xy 78.439148 -39.704215) (xy 78.547941 -39.626153) (xy 78.661168 -39.554673) (xy 78.778431 -39.490026)
			(xy 78.899318 -39.432439) (xy 79.023404 -39.382115) (xy 79.150253 -39.33923) (xy 79.27942 -39.303935)
			(xy 79.410451 -39.276354) (xy 79.542885 -39.256584) (xy 79.676259 -39.244694) (xy 79.810102 -39.240726)
			(xy 79.943945 -39.244694) (xy 80.077319 -39.256584) (xy 80.209753 -39.276354) (xy 80.340784 -39.303935)
			(xy 80.469951 -39.33923) (xy 80.5968 -39.382115) (xy 80.720886 -39.432439) (xy 80.841773 -39.490026)
			(xy 80.959036 -39.554673) (xy 81.072263 -39.626153) (xy 81.181056 -39.704215) (xy 81.285035 -39.788585)
			(xy 81.383832 -39.878967) (xy 81.477102 -39.975043) (xy 81.564516 -40.076475) (xy 81.645768 -40.182908)
			(xy 81.720572 -40.293967) (xy 81.788666 -40.409263) (xy 81.849809 -40.52839) (xy 81.903789 -40.65093)
			(xy 81.950413 -40.776453) (xy 81.989521 -40.904517) (xy 82.020972 -41.034673) (xy 82.044658 -41.166463)
			(xy 82.060495 -41.299426) (xy 82.068428 -41.433093) (xy 82.068924 -41.500044) (xy 82.068924 -44.595288)
			(xy 82.069462 -44.628581) (xy 82.078427 -44.694561) (xy 82.096221 -44.758725) (xy 82.122519 -44.819898)
			(xy 82.156839 -44.876958) (xy 82.198551 -44.92886) (xy 82.202817 -44.933038) (xy 115.78564 -44.933038)
			(xy 115.78564 -44.805162) (xy 115.793669 -44.677538) (xy 115.809697 -44.55067) (xy 115.833658 -44.425058)
			(xy 115.86546 -44.3012) (xy 115.904976 -44.179582) (xy 115.95205 -44.060685) (xy 116.006497 -43.944979)
			(xy 116.068102 -43.83292) (xy 116.136622 -43.724951) (xy 116.211786 -43.621497) (xy 116.293297 -43.522966)
			(xy 116.380834 -43.429748) (xy 116.474052 -43.342211) (xy 116.572583 -43.2607) (xy 116.676037 -43.185536)
			(xy 116.784006 -43.117016) (xy 116.896065 -43.055411) (xy 117.011771 -43.000964) (xy 117.130668 -42.95389)
			(xy 117.252286 -42.914374) (xy 117.376144 -42.882572) (xy 117.501756 -42.858611) (xy 117.628624 -42.842583)
			(xy 117.756248 -42.834554) (xy 117.884124 -42.834554) (xy 118.011748 -42.842583) (xy 118.138616 -42.858611)
			(xy 118.264228 -42.882572) (xy 118.388086 -42.914374) (xy 118.509704 -42.95389) (xy 118.628601 -43.000964)
			(xy 118.744307 -43.055411) (xy 118.856366 -43.117016) (xy 118.964335 -43.185536) (xy 119.067789 -43.2607)
			(xy 119.16632 -43.342211) (xy 119.259538 -43.429748) (xy 119.347075 -43.522966) (xy 119.428586 -43.621497)
			(xy 119.50375 -43.724951) (xy 119.57227 -43.83292) (xy 119.633875 -43.944979) (xy 119.688322 -44.060685)
			(xy 119.735396 -44.179582) (xy 119.774912 -44.3012) (xy 119.806714 -44.425058) (xy 119.830675 -44.55067)
			(xy 119.846703 -44.677538) (xy 119.854732 -44.805162) (xy 119.855234 -44.8691) (xy 119.854732 -44.932982)
			(xy 127.217418 -44.932982) (xy 127.217418 -44.805218) (xy 127.22544 -44.677705) (xy 127.241453 -44.550948)
			(xy 127.265394 -44.425446) (xy 127.297168 -44.301696) (xy 127.336649 -44.180184) (xy 127.383682 -44.061392)
			(xy 127.438082 -43.945787) (xy 127.499633 -43.833826) (xy 127.568093 -43.725951) (xy 127.643191 -43.622587)
			(xy 127.724631 -43.524142) (xy 127.812092 -43.431006) (xy 127.905228 -43.343545) (xy 128.003673 -43.262105)
			(xy 128.107037 -43.187007) (xy 128.214912 -43.118547) (xy 128.326873 -43.056996) (xy 128.442478 -43.002596)
			(xy 128.56127 -42.955563) (xy 128.682782 -42.916082) (xy 128.806532 -42.884308) (xy 128.932034 -42.860367)
			(xy 129.058791 -42.844354) (xy 129.186304 -42.836332) (xy 129.314068 -42.836332) (xy 129.441581 -42.844354)
			(xy 129.568338 -42.860367) (xy 129.69384 -42.884308) (xy 129.81759 -42.916082) (xy 129.939102 -42.955563)
			(xy 130.057894 -43.002596) (xy 130.173499 -43.056996) (xy 130.28546 -43.118547) (xy 130.393335 -43.187007)
			(xy 130.496699 -43.262105) (xy 130.595144 -43.343545) (xy 130.68828 -43.431006) (xy 130.775741 -43.524142)
			(xy 130.857181 -43.622587) (xy 130.932279 -43.725951) (xy 131.000739 -43.833826) (xy 131.06229 -43.945787)
			(xy 131.11669 -44.061392) (xy 131.163723 -44.180184) (xy 131.203204 -44.301696) (xy 131.234978 -44.425446)
			(xy 131.258919 -44.550948) (xy 131.274932 -44.677705) (xy 131.282954 -44.805218) (xy 131.283456 -44.8691)
			(xy 131.282954 -44.932982) (xy 131.274932 -45.060495) (xy 131.258919 -45.187252) (xy 131.234978 -45.312754)
			(xy 131.203204 -45.436504) (xy 131.163723 -45.558016) (xy 131.11669 -45.676808) (xy 131.06229 -45.792413)
			(xy 131.000739 -45.904374) (xy 130.932279 -46.012249) (xy 130.857181 -46.115613) (xy 130.775741 -46.214058)
			(xy 130.68828 -46.307194) (xy 130.595144 -46.394655) (xy 130.496699 -46.476095) (xy 130.393335 -46.551193)
			(xy 130.28546 -46.619653) (xy 130.173499 -46.681204) (xy 130.057894 -46.735604) (xy 129.939102 -46.782637)
			(xy 129.81759 -46.822118) (xy 129.69384 -46.853892) (xy 129.568338 -46.877833) (xy 129.441581 -46.893846)
			(xy 129.314068 -46.901868) (xy 129.186304 -46.901868) (xy 129.058791 -46.893846) (xy 128.932034 -46.877833)
			(xy 128.806532 -46.853892) (xy 128.682782 -46.822118) (xy 128.56127 -46.782637) (xy 128.442478 -46.735604)
			(xy 128.326873 -46.681204) (xy 128.214912 -46.619653) (xy 128.107037 -46.551193) (xy 128.003673 -46.476095)
			(xy 127.905228 -46.394655) (xy 127.812092 -46.307194) (xy 127.724631 -46.214058) (xy 127.643191 -46.115613)
			(xy 127.568093 -46.012249) (xy 127.499633 -45.904374) (xy 127.438082 -45.792413) (xy 127.383682 -45.676808)
			(xy 127.336649 -45.558016) (xy 127.297168 -45.436504) (xy 127.265394 -45.312754) (xy 127.241453 -45.187252)
			(xy 127.22544 -45.060495) (xy 127.217418 -44.932982) (xy 119.854732 -44.932982) (xy 119.854732 -44.933038)
			(xy 119.846703 -45.060662) (xy 119.830675 -45.18753) (xy 119.806714 -45.313142) (xy 119.774912 -45.437)
			(xy 119.735396 -45.558618) (xy 119.688322 -45.677515) (xy 119.633875 -45.793221) (xy 119.57227 -45.90528)
			(xy 119.50375 -46.013249) (xy 119.428586 -46.116703) (xy 119.347075 -46.215234) (xy 119.259538 -46.308452)
			(xy 119.16632 -46.395989) (xy 119.067789 -46.4775) (xy 118.964335 -46.552664) (xy 118.856366 -46.621184)
			(xy 118.744307 -46.682789) (xy 118.628601 -46.737236) (xy 118.509704 -46.78431) (xy 118.388086 -46.823826)
			(xy 118.264228 -46.855628) (xy 118.138616 -46.879589) (xy 118.011748 -46.895617) (xy 117.884124 -46.903646)
			(xy 117.756248 -46.903646) (xy 117.628624 -46.895617) (xy 117.501756 -46.879589) (xy 117.376144 -46.855628)
			(xy 117.252286 -46.823826) (xy 117.130668 -46.78431) (xy 117.011771 -46.737236) (xy 116.896065 -46.682789)
			(xy 116.784006 -46.621184) (xy 116.676037 -46.552664) (xy 116.572583 -46.4775) (xy 116.474052 -46.395989)
			(xy 116.380834 -46.308452) (xy 116.293297 -46.215234) (xy 116.211786 -46.116703) (xy 116.136622 -46.013249)
			(xy 116.068102 -45.90528) (xy 116.006497 -45.793221) (xy 115.95205 -45.677515) (xy 115.904976 -45.558618)
			(xy 115.86546 -45.437) (xy 115.833658 -45.313142) (xy 115.809697 -45.18753) (xy 115.793669 -45.060662)
			(xy 115.78564 -44.933038) (xy 82.202817 -44.933038) (xy 82.22234 -44.952158) (xy 82.280356 -45.007726)
			(xy 82.391852 -45.123406) (xy 82.497938 -45.244068) (xy 82.59839 -45.369459) (xy 82.692998 -45.499316)
			(xy 82.781564 -45.633366) (xy 82.863902 -45.77133) (xy 82.93984 -45.912917) (xy 82.974942 -45.985176)
			(xy 82.98434 -46.004988) (xy 83.111848 -46.132496) (xy 83.111848 -46.31309) (xy 83.11896 -46.33341)
			(xy 83.146748 -46.41369) (xy 83.19542 -46.576474) (xy 83.236154 -46.741423) (xy 83.268857 -46.90815)
			(xy 83.293451 -47.076265) (xy 83.309879 -47.245373) (xy 83.318102 -47.415078) (xy 83.3181 -47.584982)
			(xy 83.318099 -47.585008) (xy 206.302031 -47.585008) (xy 206.302033 -47.415314) (xy 206.31024 -47.245819)
			(xy 206.326634 -47.076918) (xy 206.351176 -46.909008) (xy 206.383809 -46.742481) (xy 206.424456 -46.577727)
			(xy 206.473022 -46.415131) (xy 206.50073 -46.334934) (xy 206.507842 -46.31436) (xy 206.507842 -46.132242)
			(xy 206.63662 -46.003464) (xy 206.646018 -45.983906) (xy 206.681097 -45.91174) (xy 206.75699 -45.770341)
			(xy 206.839265 -45.632559) (xy 206.92775 -45.49868) (xy 207.022261 -45.368985) (xy 207.1226 -45.243744)
			(xy 207.228557 -45.123219) (xy 207.339912 -45.007662) (xy 207.397858 -44.952158) (xy 207.421671 -44.928869)
			(xy 207.463442 -44.876989) (xy 207.497815 -44.819938) (xy 207.524158 -44.758763) (xy 207.541989 -44.694588)
			(xy 207.55098 -44.628591) (xy 207.551528 -44.595288) (xy 207.551274 -41.500044) (xy 207.551774 -41.433099)
			(xy 207.559713 -41.299445) (xy 207.575555 -41.166495) (xy 207.599246 -41.034718) (xy 207.630701 -40.904576)
			(xy 207.66981 -40.776525) (xy 207.716436 -40.651016) (xy 207.770415 -40.528489) (xy 207.831558 -40.409376)
			(xy 207.89965 -40.294093) (xy 207.974451 -40.183047) (xy 208.055699 -40.076626) (xy 208.143108 -39.975206)
			(xy 208.236372 -39.879142) (xy 208.335163 -39.788771) (xy 208.439133 -39.704411) (xy 208.547919 -39.626358)
			(xy 208.661137 -39.554887) (xy 208.77839 -39.490248) (xy 208.899267 -39.432669) (xy 209.023342 -39.382351)
			(xy 209.15018 -39.339472) (xy 209.279335 -39.304181) (xy 209.410354 -39.276604) (xy 209.542777 -39.256836)
			(xy 209.676138 -39.244947) (xy 209.809969 -39.24098) (xy 209.9438 -39.244947) (xy 210.077161 -39.256836)
			(xy 210.209584 -39.276604) (xy 210.340603 -39.304181) (xy 210.469758 -39.339472) (xy 210.596596 -39.382351)
			(xy 210.720671 -39.432669) (xy 210.841548 -39.490248) (xy 210.958801 -39.554887) (xy 211.072019 -39.626358)
			(xy 211.180805 -39.704411) (xy 211.284775 -39.788771) (xy 211.383566 -39.879142) (xy 211.47683 -39.975206)
			(xy 211.564239 -40.076626) (xy 211.645487 -40.183047) (xy 211.720288 -40.294093) (xy 211.78838 -40.409376)
			(xy 211.849523 -40.528489) (xy 211.903502 -40.651016) (xy 211.950128 -40.776525) (xy 211.989237 -40.904576)
			(xy 212.020692 -41.034718) (xy 212.044383 -41.166495) (xy 212.060225 -41.299445) (xy 212.068164 -41.433099)
			(xy 212.068664 -41.500044) (xy 212.068664 -44.595288) (xy 212.069252 -44.628587) (xy 212.078275 -44.69457)
			(xy 212.096119 -44.758733) (xy 212.122456 -44.819902) (xy 212.156805 -44.876959) (xy 212.198537 -44.928859)
			(xy 212.222334 -44.952158) (xy 212.280334 -45.007691) (xy 212.391793 -45.123311) (xy 212.497842 -45.243912)
			(xy 212.59826 -45.36924) (xy 212.692836 -45.499034) (xy 212.781371 -45.633021) (xy 212.863681 -45.77092)
			(xy 212.939592 -45.912442) (xy 212.974682 -45.984668) (xy 212.98408 -46.00448) (xy 213.111842 -46.132242)
			(xy 213.111842 -46.31309) (xy 213.118954 -46.33341) (xy 213.146742 -46.41369) (xy 213.195414 -46.576474)
			(xy 213.236149 -46.741423) (xy 213.268852 -46.90815) (xy 213.293446 -47.076265) (xy 213.309873 -47.245373)
			(xy 213.318096 -47.415078) (xy 213.318095 -47.584982) (xy 213.318094 -47.585008) (xy 297.302105 -47.585008)
			(xy 297.302106 -47.415314) (xy 297.310314 -47.245819) (xy 297.326708 -47.076918) (xy 297.351249 -46.909008)
			(xy 297.383882 -46.742481) (xy 297.424528 -46.577727) (xy 297.473094 -46.415131) (xy 297.500802 -46.334934)
			(xy 297.507914 -46.31436) (xy 297.507914 -46.132242) (xy 297.636692 -46.003464) (xy 297.64609 -45.983906)
			(xy 297.681156 -45.911733) (xy 297.75705 -45.770335) (xy 297.839327 -45.632553) (xy 297.927814 -45.498675)
			(xy 298.022326 -45.368981) (xy 298.122667 -45.243741) (xy 298.228626 -45.123217) (xy 298.339983 -45.007662)
			(xy 298.39793 -44.952158) (xy 298.421756 -44.928883) (xy 298.463523 -44.876998) (xy 298.497893 -44.819943)
			(xy 298.524234 -44.758766) (xy 298.542062 -44.694589) (xy 298.551052 -44.628592) (xy 298.5516 -44.595288)
			(xy 298.5516 -41.500044) (xy 298.552096 -41.4331) (xy 298.560028 -41.299448) (xy 298.575863 -41.166501)
			(xy 298.599546 -41.034725) (xy 298.630994 -40.904584) (xy 298.670097 -40.776534) (xy 298.716717 -40.651025)
			(xy 298.77069 -40.528499) (xy 298.831827 -40.409386) (xy 298.899913 -40.294103) (xy 298.974708 -40.183056)
			(xy 299.055951 -40.076635) (xy 299.143355 -39.975214) (xy 299.236615 -39.879149) (xy 299.335401 -39.788778)
			(xy 299.439368 -39.704417) (xy 299.548149 -39.626363) (xy 299.661364 -39.554891) (xy 299.778613 -39.490252)
			(xy 299.899486 -39.432671) (xy 300.023558 -39.382353) (xy 300.150393 -39.339473) (xy 300.279545 -39.304182)
			(xy 300.410562 -39.276604) (xy 300.542981 -39.256836) (xy 300.67634 -39.244948) (xy 300.810168 -39.24098)
			(xy 300.943996 -39.244948) (xy 301.077355 -39.256836) (xy 301.209774 -39.276604) (xy 301.340791 -39.304182)
			(xy 301.469943 -39.339473) (xy 301.596778 -39.382353) (xy 301.72085 -39.432671) (xy 301.841723 -39.490252)
			(xy 301.958972 -39.554891) (xy 302.072187 -39.626363) (xy 302.180968 -39.704417) (xy 302.284935 -39.788778)
			(xy 302.383721 -39.879149) (xy 302.476981 -39.975214) (xy 302.564385 -40.076635) (xy 302.645628 -40.183056)
			(xy 302.720423 -40.294103) (xy 302.788509 -40.409386) (xy 302.849646 -40.528499) (xy 302.903619 -40.651025)
			(xy 302.950239 -40.776534) (xy 302.989342 -40.904584) (xy 303.02079 -41.034725) (xy 303.044473 -41.166501)
			(xy 303.060308 -41.299448) (xy 303.06824 -41.4331) (xy 303.068736 -41.500044) (xy 303.068736 -44.595288)
			(xy 303.069332 -44.628586) (xy 303.078355 -44.694569) (xy 303.096197 -44.758732) (xy 303.122533 -44.819901)
			(xy 303.15688 -44.876957) (xy 303.19861 -44.928859) (xy 303.202878 -44.933038) (xy 336.785706 -44.933038)
			(xy 336.785706 -44.805162) (xy 336.793735 -44.677538) (xy 336.809763 -44.55067) (xy 336.833724 -44.425058)
			(xy 336.865526 -44.3012) (xy 336.905042 -44.179582) (xy 336.952116 -44.060685) (xy 337.006563 -43.944979)
			(xy 337.068168 -43.83292) (xy 337.136688 -43.724951) (xy 337.211852 -43.621497) (xy 337.293363 -43.522966)
			(xy 337.3809 -43.429748) (xy 337.474118 -43.342211) (xy 337.572649 -43.2607) (xy 337.676103 -43.185536)
			(xy 337.784072 -43.117016) (xy 337.896131 -43.055411) (xy 338.011837 -43.000964) (xy 338.130734 -42.95389)
			(xy 338.252352 -42.914374) (xy 338.37621 -42.882572) (xy 338.501822 -42.858611) (xy 338.62869 -42.842583)
			(xy 338.756314 -42.834554) (xy 338.88419 -42.834554) (xy 339.011814 -42.842583) (xy 339.138682 -42.858611)
			(xy 339.264294 -42.882572) (xy 339.388152 -42.914374) (xy 339.50977 -42.95389) (xy 339.628667 -43.000964)
			(xy 339.744373 -43.055411) (xy 339.856432 -43.117016) (xy 339.964401 -43.185536) (xy 340.067855 -43.2607)
			(xy 340.166386 -43.342211) (xy 340.259604 -43.429748) (xy 340.347141 -43.522966) (xy 340.428652 -43.621497)
			(xy 340.503816 -43.724951) (xy 340.572336 -43.83292) (xy 340.633941 -43.944979) (xy 340.688388 -44.060685)
			(xy 340.735462 -44.179582) (xy 340.774978 -44.3012) (xy 340.80678 -44.425058) (xy 340.830741 -44.55067)
			(xy 340.846769 -44.677538) (xy 340.854798 -44.805162) (xy 340.8553 -44.8691) (xy 340.854798 -44.932982)
			(xy 348.217484 -44.932982) (xy 348.217484 -44.805218) (xy 348.225506 -44.677705) (xy 348.241519 -44.550948)
			(xy 348.26546 -44.425446) (xy 348.297234 -44.301696) (xy 348.336715 -44.180184) (xy 348.383748 -44.061392)
			(xy 348.438148 -43.945787) (xy 348.499699 -43.833826) (xy 348.568159 -43.725951) (xy 348.643257 -43.622587)
			(xy 348.724697 -43.524142) (xy 348.812158 -43.431006) (xy 348.905294 -43.343545) (xy 349.003739 -43.262105)
			(xy 349.107103 -43.187007) (xy 349.214978 -43.118547) (xy 349.326939 -43.056996) (xy 349.442544 -43.002596)
			(xy 349.561336 -42.955563) (xy 349.682848 -42.916082) (xy 349.806598 -42.884308) (xy 349.9321 -42.860367)
			(xy 350.058857 -42.844354) (xy 350.18637 -42.836332) (xy 350.314134 -42.836332) (xy 350.441647 -42.844354)
			(xy 350.568404 -42.860367) (xy 350.693906 -42.884308) (xy 350.817656 -42.916082) (xy 350.939168 -42.955563)
			(xy 351.05796 -43.002596) (xy 351.173565 -43.056996) (xy 351.285526 -43.118547) (xy 351.393401 -43.187007)
			(xy 351.496765 -43.262105) (xy 351.59521 -43.343545) (xy 351.688346 -43.431006) (xy 351.775807 -43.524142)
			(xy 351.857247 -43.622587) (xy 351.932345 -43.725951) (xy 352.000805 -43.833826) (xy 352.062356 -43.945787)
			(xy 352.116756 -44.061392) (xy 352.163789 -44.180184) (xy 352.20327 -44.301696) (xy 352.235044 -44.425446)
			(xy 352.258985 -44.550948) (xy 352.274998 -44.677705) (xy 352.28302 -44.805218) (xy 352.283522 -44.8691)
			(xy 352.28302 -44.932982) (xy 352.274998 -45.060495) (xy 352.258985 -45.187252) (xy 352.235044 -45.312754)
			(xy 352.20327 -45.436504) (xy 352.163789 -45.558016) (xy 352.116756 -45.676808) (xy 352.062356 -45.792413)
			(xy 352.000805 -45.904374) (xy 351.932345 -46.012249) (xy 351.857247 -46.115613) (xy 351.775807 -46.214058)
			(xy 351.688346 -46.307194) (xy 351.59521 -46.394655) (xy 351.496765 -46.476095) (xy 351.393401 -46.551193)
			(xy 351.285526 -46.619653) (xy 351.173565 -46.681204) (xy 351.05796 -46.735604) (xy 350.939168 -46.782637)
			(xy 350.817656 -46.822118) (xy 350.693906 -46.853892) (xy 350.568404 -46.877833) (xy 350.441647 -46.893846)
			(xy 350.314134 -46.901868) (xy 350.18637 -46.901868) (xy 350.058857 -46.893846) (xy 349.9321 -46.877833)
			(xy 349.806598 -46.853892) (xy 349.682848 -46.822118) (xy 349.561336 -46.782637) (xy 349.442544 -46.735604)
			(xy 349.326939 -46.681204) (xy 349.214978 -46.619653) (xy 349.107103 -46.551193) (xy 349.003739 -46.476095)
			(xy 348.905294 -46.394655) (xy 348.812158 -46.307194) (xy 348.724697 -46.214058) (xy 348.643257 -46.115613)
			(xy 348.568159 -46.012249) (xy 348.499699 -45.904374) (xy 348.438148 -45.792413) (xy 348.383748 -45.676808)
			(xy 348.336715 -45.558016) (xy 348.297234 -45.436504) (xy 348.26546 -45.312754) (xy 348.241519 -45.187252)
			(xy 348.225506 -45.060495) (xy 348.217484 -44.932982) (xy 340.854798 -44.932982) (xy 340.854798 -44.933038)
			(xy 340.846769 -45.060662) (xy 340.830741 -45.18753) (xy 340.80678 -45.313142) (xy 340.774978 -45.437)
			(xy 340.735462 -45.558618) (xy 340.688388 -45.677515) (xy 340.633941 -45.793221) (xy 340.572336 -45.90528)
			(xy 340.503816 -46.013249) (xy 340.428652 -46.116703) (xy 340.347141 -46.215234) (xy 340.259604 -46.308452)
			(xy 340.166386 -46.395989) (xy 340.067855 -46.4775) (xy 339.964401 -46.552664) (xy 339.856432 -46.621184)
			(xy 339.744373 -46.682789) (xy 339.628667 -46.737236) (xy 339.50977 -46.78431) (xy 339.388152 -46.823826)
			(xy 339.264294 -46.855628) (xy 339.138682 -46.879589) (xy 339.011814 -46.895617) (xy 338.88419 -46.903646)
			(xy 338.756314 -46.903646) (xy 338.62869 -46.895617) (xy 338.501822 -46.879589) (xy 338.37621 -46.855628)
			(xy 338.252352 -46.823826) (xy 338.130734 -46.78431) (xy 338.011837 -46.737236) (xy 337.896131 -46.682789)
			(xy 337.784072 -46.621184) (xy 337.676103 -46.552664) (xy 337.572649 -46.4775) (xy 337.474118 -46.395989)
			(xy 337.3809 -46.308452) (xy 337.293363 -46.215234) (xy 337.211852 -46.116703) (xy 337.136688 -46.013249)
			(xy 337.068168 -45.90528) (xy 337.006563 -45.793221) (xy 336.952116 -45.677515) (xy 336.905042 -45.558618)
			(xy 336.865526 -45.437) (xy 336.833724 -45.313142) (xy 336.809763 -45.18753) (xy 336.793735 -45.060662)
			(xy 336.785706 -44.933038) (xy 303.202878 -44.933038) (xy 303.222406 -44.952158) (xy 303.280403 -45.007695)
			(xy 303.391862 -45.123314) (xy 303.497912 -45.243914) (xy 303.59833 -45.369242) (xy 303.692906 -45.499035)
			(xy 303.781442 -45.633022) (xy 303.863752 -45.77092) (xy 303.939664 -45.912442) (xy 303.974754 -45.984668)
			(xy 303.984152 -46.00448) (xy 304.111914 -46.132242) (xy 304.111914 -46.31309) (xy 304.119026 -46.33341)
			(xy 304.146814 -46.41369) (xy 304.195486 -46.576474) (xy 304.236222 -46.741423) (xy 304.268925 -46.90815)
			(xy 304.293519 -47.076265) (xy 304.309947 -47.245373) (xy 304.31817 -47.415078) (xy 304.318168 -47.584982)
			(xy 304.309943 -47.754687) (xy 304.293512 -47.923795) (xy 304.268915 -48.09191) (xy 304.236209 -48.258636)
			(xy 304.19547 -48.423584) (xy 304.146796 -48.586367) (xy 304.119026 -48.666654) (xy 304.111914 -48.687228)
			(xy 304.111914 -48.868076) (xy 303.983898 -48.996092) (xy 303.9745 -49.01565) (xy 303.937399 -49.092006)
			(xy 303.856734 -49.241402) (xy 303.768938 -49.386722) (xy 303.674216 -49.527626) (xy 303.572789 -49.663782)
			(xy 303.464895 -49.794874) (xy 303.350787 -49.920593) (xy 303.230731 -50.040646) (xy 303.105009 -50.154751)
			(xy 302.973915 -50.262642) (xy 302.837756 -50.364065) (xy 302.69685 -50.458784) (xy 302.551528 -50.546577)
			(xy 302.40213 -50.627237) (xy 302.325786 -50.664364) (xy 302.306228 -50.673762) (xy 302.177704 -50.802286)
			(xy 301.99584 -50.802286) (xy 301.97552 -50.809398) (xy 301.895314 -50.837106) (xy 301.732699 -50.885669)
			(xy 301.567927 -50.926313) (xy 301.401382 -50.958944) (xy 301.233454 -50.983483) (xy 301.064536 -50.999875)
			(xy 300.895024 -51.00808) (xy 300.725312 -51.00808) (xy 300.5558 -50.999875) (xy 300.386882 -50.983483)
			(xy 300.218954 -50.958944) (xy 300.052409 -50.926313) (xy 299.887637 -50.885669) (xy 299.725022 -50.837106)
			(xy 299.644816 -50.809398) (xy 299.624496 -50.802286) (xy 299.442124 -50.802286) (xy 299.313092 -50.673254)
			(xy 299.293534 -50.663856) (xy 299.217276 -50.626741) (xy 299.068045 -50.546114) (xy 298.922885 -50.458371)
			(xy 298.782135 -50.363715) (xy 298.646122 -50.262369) (xy 298.515166 -50.154568) (xy 298.389572 -50.040566)
			(xy 298.269634 -49.920628) (xy 298.155632 -49.795034) (xy 298.047831 -49.664078) (xy 297.946485 -49.528065)
			(xy 297.851829 -49.387315) (xy 297.764086 -49.242155) (xy 297.683459 -49.092924) (xy 297.646344 -49.016666)
			(xy 297.636946 -48.997108) (xy 297.507914 -48.868076) (xy 297.507914 -48.685704) (xy 297.500802 -48.665384)
			(xy 297.47307 -48.585196) (xy 297.424508 -48.422598) (xy 297.383865 -48.257843) (xy 297.351236 -48.091316)
			(xy 297.326698 -47.923405) (xy 297.310308 -47.754504) (xy 297.302105 -47.585008) (xy 213.318094 -47.585008)
			(xy 213.309869 -47.754687) (xy 213.293438 -47.923795) (xy 213.268841 -48.09191) (xy 213.236136 -48.258636)
			(xy 213.195398 -48.423584) (xy 213.146723 -48.586367) (xy 213.118954 -48.666654) (xy 213.111842 -48.687228)
			(xy 213.111842 -48.868076) (xy 212.983826 -48.996092) (xy 212.974428 -49.01565) (xy 212.937315 -49.092)
			(xy 212.856651 -49.241397) (xy 212.768856 -49.386717) (xy 212.674135 -49.52762) (xy 212.572709 -49.663777)
			(xy 212.464816 -49.794869) (xy 212.350708 -49.920588) (xy 212.230653 -50.040641) (xy 212.104932 -50.154747)
			(xy 211.973839 -50.262638) (xy 211.837681 -50.364062) (xy 211.696776 -50.458782) (xy 211.551455 -50.546575)
			(xy 211.402057 -50.627237) (xy 211.325714 -50.664364) (xy 211.306156 -50.673762) (xy 211.177632 -50.802286)
			(xy 210.995768 -50.802286) (xy 210.975448 -50.809398) (xy 210.895242 -50.837106) (xy 210.732627 -50.885669)
			(xy 210.567855 -50.926313) (xy 210.40131 -50.958944) (xy 210.233382 -50.983483) (xy 210.064464 -50.999875)
			(xy 209.894952 -51.00808) (xy 209.72524 -51.00808) (xy 209.555728 -50.999875) (xy 209.38681 -50.983483)
			(xy 209.218882 -50.958944) (xy 209.052337 -50.926313) (xy 208.887565 -50.885669) (xy 208.72495 -50.837106)
			(xy 208.644744 -50.809398) (xy 208.624424 -50.802286) (xy 208.442052 -50.802286) (xy 208.31302 -50.673254)
			(xy 208.293462 -50.663856) (xy 208.217209 -50.626729) (xy 208.067979 -50.546104) (xy 207.922818 -50.458362)
			(xy 207.782067 -50.363707) (xy 207.646054 -50.262362) (xy 207.515098 -50.154562) (xy 207.389504 -50.040561)
			(xy 207.269565 -49.920623) (xy 207.155562 -49.79503) (xy 207.047761 -49.664075) (xy 206.946414 -49.528063)
			(xy 206.851759 -49.387313) (xy 206.764015 -49.242154) (xy 206.683388 -49.092924) (xy 206.646272 -49.016666)
			(xy 206.636874 -48.997108) (xy 206.507842 -48.868076) (xy 206.507842 -48.685704) (xy 206.50073 -48.665384)
			(xy 206.472998 -48.585196) (xy 206.424435 -48.422599) (xy 206.383792 -48.257843) (xy 206.351163 -48.091316)
			(xy 206.326625 -47.923405) (xy 206.310235 -47.754504) (xy 206.302031 -47.585008) (xy 83.318099 -47.585008)
			(xy 83.309875 -47.754687) (xy 83.293444 -47.923795) (xy 83.268847 -48.09191) (xy 83.236141 -48.258636)
			(xy 83.195404 -48.423584) (xy 83.146729 -48.586367) (xy 83.11896 -48.666654) (xy 83.111848 -48.687228)
			(xy 83.111848 -48.86833) (xy 82.983578 -48.9966) (xy 82.97418 -49.016158) (xy 82.937071 -49.092465)
			(xy 82.856425 -49.241778) (xy 82.768656 -49.387018) (xy 82.673967 -49.527845) (xy 82.57258 -49.66393)
			(xy 82.464733 -49.794953) (xy 82.350678 -49.92061) (xy 82.230681 -50.040606) (xy 82.105023 -50.154659)
			(xy 81.973998 -50.262505) (xy 81.837912 -50.36389) (xy 81.697084 -50.458577) (xy 81.551843 -50.546345)
			(xy 81.402529 -50.626989) (xy 81.326228 -50.66411) (xy 81.30667 -50.673508) (xy 81.177638 -50.80254)
			(xy 80.995266 -50.80254) (xy 80.974692 -50.809652) (xy 80.894534 -50.837323) (xy 80.732021 -50.885822)
			(xy 80.567354 -50.926411) (xy 80.400918 -50.958998) (xy 80.233102 -50.983504) (xy 80.064298 -50.999873)
			(xy 79.8949 -51.008068) (xy 79.725304 -51.008068) (xy 79.555906 -50.999873) (xy 79.387102 -50.983504)
			(xy 79.219286 -50.958998) (xy 79.05285 -50.926411) (xy 78.888183 -50.885822) (xy 78.72567 -50.837323)
			(xy 78.645512 -50.809652) (xy 78.624938 -50.80254) (xy 78.442058 -50.80254) (xy 78.312772 -50.673254)
			(xy 78.293214 -50.663856) (xy 78.216985 -50.626744) (xy 78.067808 -50.546131) (xy 77.922701 -50.458406)
			(xy 77.782 -50.363773) (xy 77.646036 -50.262453) (xy 77.515125 -50.154684) (xy 77.389573 -50.040716)
			(xy 77.269673 -49.920816) (xy 77.155706 -49.795263) (xy 77.047937 -49.664352) (xy 76.946618 -49.528387)
			(xy 76.851986 -49.387686) (xy 76.764261 -49.242578) (xy 76.683649 -49.093401) (xy 76.646532 -49.017174)
			(xy 76.637134 -48.997616) (xy 76.507848 -48.86833) (xy 76.507848 -48.685704) (xy 76.500736 -48.665384)
			(xy 76.473028 -48.585187) (xy 76.424465 -48.422591) (xy 76.383821 -48.257837) (xy 76.35119 -48.09131)
			(xy 76.326651 -47.923401) (xy 76.310259 -47.754501) (xy 76.302054 -47.585006) (xy 56.588914 -47.585006)
			(xy 56.588914 -50.31994) (xy 56.589437 -50.375708) (xy 56.597775 -50.486932) (xy 56.614401 -50.597222)
			(xy 56.639223 -50.705962) (xy 56.672101 -50.812542) (xy 56.712852 -50.916368) (xy 56.761247 -51.016857)
			(xy 56.817017 -51.11345) (xy 56.879849 -51.205604) (xy 56.949392 -51.292806) (xy 57.025257 -51.374567)
			(xy 57.10702 -51.45043) (xy 57.194223 -51.519971) (xy 57.286379 -51.582801) (xy 57.382973 -51.638569)
			(xy 57.483464 -51.686962) (xy 57.58729 -51.72771) (xy 57.693871 -51.760586) (xy 57.802611 -51.785405)
			(xy 57.912901 -51.802029) (xy 58.024126 -51.810364) (xy 58.079894 -51.81092)
		)
		(stroke
			(width 0)
			(type solid)
		)
		(fill yes)
		(layer "In6.Cu")
		(net "GND")
	)
	(gr_line
		(start 0.1778 -46.8376)
		(end 10.541 -46.8376)
		(stroke
			(width 0.508)
			(type default)
		)
		(layer "In6.Cu")
	)
	(gr_line
		(start 0.7366 -49.1744)
		(end 9.271 -49.1744)
		(stroke
			(width 2.54)
			(type default)
		)
		(layer "In6.Cu")
	)
	(gr_line
		(start 0.762 -51.3334)
		(end 9.2964 -51.3334)
		(stroke
			(width 2.54)
			(type default)
		)
		(layer "In6.Cu")
	)
	(gr_line
		(start 0.762 -50.3174)
		(end 9.2964 -50.3174)
		(stroke
			(width 2.54)
			(type default)
		)
		(layer "In6.Cu")
	)
	(gr_line
		(start 0.762 -49.911)
		(end 9.2964 -49.911)
		(stroke
			(width 2.54)
			(type default)
		)
		(layer "In6.Cu")
	)
	(gr_line
		(start 0.7874 -50.8508)
		(end 9.3218 -50.8508)
		(stroke
			(width 2.54)
			(type default)
		)
		(layer "In6.Cu")
	)
	(gr_line
		(start 0.7874 -50.3682)
		(end 9.3218 -50.3682)
		(stroke
			(width 2.54)
			(type default)
		)
		(layer "In6.Cu")
	)
	(gr_line
		(start 0.7874 -49.5046)
		(end 9.3218 -49.5046)
		(stroke
			(width 2.54)
			(type default)
		)
		(layer "In6.Cu")
	)
	(gr_line
		(start 0.7874 -48.6156)
		(end 9.3218 -48.6156)
		(stroke
			(width 2.54)
			(type default)
		)
		(layer "In6.Cu")
	)
	(gr_line
		(start 0.7874 -48.0822)
		(end 9.3218 -48.0822)
		(stroke
			(width 2.54)
			(type default)
		)
		(layer "In6.Cu")
	)
	(gr_line
		(start 0.8128 -48.3108)
		(end 9.3472 -48.3108)
		(stroke
			(width 2.54)
			(type default)
		)
		(layer "In6.Cu")
	)
	(gr_line
		(start 0.8128 -48.26)
		(end 9.3472 -48.26)
		(stroke
			(width 2.54)
			(type default)
		)
		(layer "In6.Cu")
	)
	(gr_line
		(start 0.8128 -47.9044)
		(end 9.3472 -47.9044)
		(stroke
			(width 2.54)
			(type default)
		)
		(layer "In6.Cu")
	)
	(gr_line
		(start 0.8382 -48.8442)
		(end 9.3726 -48.8442)
		(stroke
			(width 2.54)
			(type default)
		)
		(layer "In6.Cu")
	)
	(gr_line
		(start 0.8382 -48.5394)
		(end 9.3726 -48.5394)
		(stroke
			(width 2.54)
			(type default)
		)
		(layer "In6.Cu")
	)
	(gr_line
		(start 0.8382 -48.4378)
		(end 9.3726 -48.4378)
		(stroke
			(width 2.54)
			(type default)
		)
		(layer "In6.Cu")
	)
	(gr_line
		(start 0.8382 -48.0822)
		(end 9.3726 -48.0822)
		(stroke
			(width 2.54)
			(type default)
		)
		(layer "In6.Cu")
	)
	(gr_line
		(start 0.8636 -49.0982)
		(end 9.398 -49.0982)
		(stroke
			(width 2.54)
			(type default)
		)
		(layer "In6.Cu")
	)
	(gr_line
		(start 0.8636 -48.9204)
		(end 9.398 -48.9204)
		(stroke
			(width 2.54)
			(type default)
		)
		(layer "In6.Cu")
	)
	(gr_line
		(start 0.8636 -48.7172)
		(end 9.398 -48.7172)
		(stroke
			(width 2.54)
			(type default)
		)
		(layer "In6.Cu")
	)
	(gr_line
		(start 0.8636 -48.641)
		(end 9.398 -48.641)
		(stroke
			(width 2.54)
			(type default)
		)
		(layer "In6.Cu")
	)
	(gr_line
		(start 0.889 -51.5366)
		(end 9.4234 -51.5366)
		(stroke
			(width 2.54)
			(type default)
		)
		(layer "In6.Cu")
	)
	(gr_line
		(start 0.9144 -49.8856)
		(end 9.4488 -49.8856)
		(stroke
			(width 2.54)
			(type default)
		)
		(layer "In6.Cu")
	)
	(gr_line
		(start 0.9144 -49.2506)
		(end 9.4488 -49.2506)
		(stroke
			(width 2.54)
			(type default)
		)
		(layer "In6.Cu")
	)
	(gr_line
		(start 0.9398 -51.2572)
		(end 9.4742 -51.2572)
		(stroke
			(width 2.54)
			(type default)
		)
		(layer "In6.Cu")
	)
	(gr_line
		(start 0.9398 -49.7332)
		(end 9.4742 -49.7332)
		(stroke
			(width 2.54)
			(type default)
		)
		(layer "In6.Cu")
	)
	(gr_line
		(start 0.9398 -49.5808)
		(end 9.4742 -49.5808)
		(stroke
			(width 2.54)
			(type default)
		)
		(layer "In6.Cu")
	)
	(gr_line
		(start 0.9398 -49.3522)
		(end 9.4742 -49.3522)
		(stroke
			(width 2.54)
			(type default)
		)
		(layer "In6.Cu")
	)
	(gr_line
		(start 0.9652 -51.3588)
		(end 9.4996 -51.3588)
		(stroke
			(width 2.54)
			(type default)
		)
		(layer "In6.Cu")
	)
	(gr_line
		(start 0.9652 -50.4698)
		(end 9.4996 -50.4698)
		(stroke
			(width 2.54)
			(type default)
		)
		(layer "In6.Cu")
	)
	(gr_line
		(start 0.9652 -50.3682)
		(end 9.4996 -50.3682)
		(stroke
			(width 2.54)
			(type default)
		)
		(layer "In6.Cu")
	)
	(gr_line
		(start 0.9652 -50.1142)
		(end 9.4996 -50.1142)
		(stroke
			(width 2.54)
			(type default)
		)
		(layer "In6.Cu")
	)
	(gr_line
		(start 0.9906 -51.435)
		(end 5.8674 -51.435)
		(stroke
			(width 2.54)
			(type default)
		)
		(layer "In6.Cu")
	)
	(gr_line
		(start 0.9906 -51.1048)
		(end 9.525 -51.1048)
		(stroke
			(width 2.54)
			(type default)
		)
		(layer "In6.Cu")
	)
	(gr_line
		(start 0.9906 -50.8)
		(end 9.525 -50.8)
		(stroke
			(width 2.54)
			(type default)
		)
		(layer "In6.Cu")
	)
	(gr_line
		(start 0.9906 -50.6476)
		(end 9.525 -50.6476)
		(stroke
			(width 2.54)
			(type default)
		)
		(layer "In6.Cu")
	)
	(gr_line
		(start 1.016 -50.9524)
		(end 9.5504 -50.9524)
		(stroke
			(width 2.54)
			(type default)
		)
		(layer "In6.Cu")
	)
	(gr_line
		(start 1.0414 -51.1556)
		(end 9.5758 -51.1556)
		(stroke
			(width 2.54)
			(type default)
		)
		(layer "In6.Cu")
	)
	(gr_line
		(start 1.0414 -50.9016)
		(end 9.5758 -50.9016)
		(stroke
			(width 2.54)
			(type default)
		)
		(layer "In6.Cu")
	)
	(gr_line
		(start 1.0414 -50.0888)
		(end 9.5758 -50.0888)
		(stroke
			(width 2.54)
			(type default)
		)
		(layer "In6.Cu")
	)
	(gr_line
		(start 1.0668 -50.6984)
		(end 9.6012 -50.6984)
		(stroke
			(width 2.54)
			(type default)
		)
		(layer "In6.Cu")
	)
	(gr_line
		(start 1.0668 -50.4952)
		(end 9.6012 -50.4952)
		(stroke
			(width 2.54)
			(type default)
		)
		(layer "In6.Cu")
	)
	(gr_line
		(start 1.0668 -50.2412)
		(end 9.6012 -50.2412)
		(stroke
			(width 2.54)
			(type default)
		)
		(layer "In6.Cu")
	)
	(gr_line
		(start 1.1938 -50.3682)
		(end 9.7282 -50.3682)
		(stroke
			(width 2.54)
			(type default)
		)
		(layer "In6.Cu")
	)
	(gr_line
		(start 1.2192 -50.3428)
		(end 9.7536 -50.3428)
		(stroke
			(width 2.54)
			(type default)
		)
		(layer "In6.Cu")
	)
	(gr_line
		(start 1.2192 -49.8602)
		(end 9.7536 -49.8602)
		(stroke
			(width 2.54)
			(type default)
		)
		(layer "In6.Cu")
	)
	(gr_line
		(start 1.2446 -48.7934)
		(end 9.779 -48.7934)
		(stroke
			(width 2.54)
			(type default)
		)
		(layer "In6.Cu")
	)
	(gr_line
		(start 1.4732 -52.1462)
		(end 6.35 -52.1462)
		(stroke
			(width 2.54)
			(type default)
		)
		(layer "In6.Cu")
	)
	(gr_line
		(start 1.49987 -53.299868)
		(end 0 -51.799998)
		(stroke
			(width 1.016)
			(type default)
		)
		(layer "In6.Cu")
	)
	(gr_line
		(start 1.8542 -52.5272)
		(end 6.731 -52.5272)
		(stroke
			(width 2.54)
			(type default)
		)
		(layer "In6.Cu")
	)
	(gr_arc
		(start 1.999996 0)
		(mid 0.585785 -0.585785)
		(end 0 -1.999996)
		(stroke
			(width 1.016)
			(type default)
		)
		(layer "In6.Cu")
	)
	(gr_line
		(start 1.999996 0)
		(end 426.809916 0)
		(stroke
			(width 1.016)
			(type default)
		)
		(layer "In6.Cu")
	)
	(gr_line
		(start 2.5654 -52.2478)
		(end 7.4422 -52.2478)
		(stroke
			(width 2.54)
			(type default)
		)
		(layer "In6.Cu")
	)
	(gr_arc
		(start 2.750058 -32.563308)
		(mid 4.372855 -37.997202)
		(end 6.45033 -32.720534)
		(stroke
			(width 1.016)
			(type default)
		)
		(layer "In6.Cu")
	)
	(gr_line
		(start 2.750058 -29.207714)
		(end 2.750058 -32.563308)
		(stroke
			(width 1.016)
			(type default)
		)
		(layer "In6.Cu")
	)
	(gr_line
		(start 2.760726 -29.197046)
		(end 2.750058 -29.207714)
		(stroke
			(width 1.016)
			(type default)
		)
		(layer "In6.Cu")
	)
	(gr_line
		(start 3.6576 -52.5018)
		(end 8.5344 -52.5018)
		(stroke
			(width 2.54)
			(type default)
		)
		(layer "In6.Cu")
	)
	(gr_line
		(start 4.2418 -49.5554)
		(end 12.7762 -49.5554)
		(stroke
			(width 2.54)
			(type default)
		)
		(layer "In6.Cu")
	)
	(gr_line
		(start 4.2672 -49.7586)
		(end 12.8016 -49.7586)
		(stroke
			(width 2.54)
			(type default)
		)
		(layer "In6.Cu")
	)
	(gr_line
		(start 4.2926 -49.2506)
		(end 12.827 -49.2506)
		(stroke
			(width 2.54)
			(type default)
		)
		(layer "In6.Cu")
	)
	(gr_line
		(start 4.318 -48.8188)
		(end 12.8524 -48.8188)
		(stroke
			(width 2.54)
			(type default)
		)
		(layer "In6.Cu")
	)
	(gr_line
		(start 4.3434 -50.8254)
		(end 12.8778 -50.8254)
		(stroke
			(width 2.54)
			(type default)
		)
		(layer "In6.Cu")
	)
	(gr_line
		(start 4.3434 -48.895)
		(end 12.8778 -48.895)
		(stroke
			(width 2.54)
			(type default)
		)
		(layer "In6.Cu")
	)
	(gr_line
		(start 4.3688 -50.6222)
		(end 12.9032 -50.6222)
		(stroke
			(width 2.54)
			(type default)
		)
		(layer "In6.Cu")
	)
	(gr_line
		(start 4.3688 -50.4444)
		(end 12.9032 -50.4444)
		(stroke
			(width 2.54)
			(type default)
		)
		(layer "In6.Cu")
	)
	(gr_line
		(start 4.3688 -50.1142)
		(end 12.9032 -50.1142)
		(stroke
			(width 2.54)
			(type default)
		)
		(layer "In6.Cu")
	)
	(gr_line
		(start 4.3942 -51.8668)
		(end 9.271 -51.8668)
		(stroke
			(width 2.54)
			(type default)
		)
		(layer "In6.Cu")
	)
	(gr_line
		(start 4.3942 -49.9364)
		(end 12.9286 -49.9364)
		(stroke
			(width 2.54)
			(type default)
		)
		(layer "In6.Cu")
	)
	(gr_line
		(start 4.3942 -48.4632)
		(end 12.9286 -48.4632)
		(stroke
			(width 2.54)
			(type default)
		)
		(layer "In6.Cu")
	)
	(gr_line
		(start 4.4196 -48.2092)
		(end 12.954 -48.2092)
		(stroke
			(width 2.54)
			(type default)
		)
		(layer "In6.Cu")
	)
	(gr_line
		(start 4.445 -48.5394)
		(end 12.9794 -48.5394)
		(stroke
			(width 2.54)
			(type default)
		)
		(layer "In6.Cu")
	)
	(gr_line
		(start 4.445 -48.4378)
		(end 12.9794 -48.4378)
		(stroke
			(width 2.54)
			(type default)
		)
		(layer "In6.Cu")
	)
	(gr_line
		(start 4.445 -48.0314)
		(end 12.9794 -48.0314)
		(stroke
			(width 2.54)
			(type default)
		)
		(layer "In6.Cu")
	)
	(gr_line
		(start 4.445 -47.9044)
		(end 12.9794 -47.9044)
		(stroke
			(width 2.54)
			(type default)
		)
		(layer "In6.Cu")
	)
	(gr_line
		(start 4.4704 -48.8442)
		(end 13.0048 -48.8442)
		(stroke
			(width 2.54)
			(type default)
		)
		(layer "In6.Cu")
	)
	(gr_line
		(start 4.49961 -34.99993)
		(end 4.499864 -35.000184)
		(stroke
			(width 4.064)
			(type default)
		)
		(layer "In6.Cu")
	)
	(gr_line
		(start 4.49961 -28.999688)
		(end 4.49961 -34.99993)
		(stroke
			(width 4.064)
			(type default)
		)
		(layer "In6.Cu")
	)
	(gr_line
		(start 4.499864 -35.000184)
		(end 4.499864 -34.99993)
		(stroke
			(width 6.604)
			(type default)
		)
		(layer "In6.Cu")
	)
	(gr_line
		(start 4.6736 -49.0728)
		(end 13.208 -49.0728)
		(stroke
			(width 2.54)
			(type default)
		)
		(layer "In6.Cu")
	)
	(gr_line
		(start 4.826 -49.4284)
		(end 13.3604 -49.4284)
		(stroke
			(width 2.54)
			(type default)
		)
		(layer "In6.Cu")
	)
	(gr_line
		(start 4.8514 -49.5808)
		(end 13.3858 -49.5808)
		(stroke
			(width 2.54)
			(type default)
		)
		(layer "In6.Cu")
	)
	(gr_line
		(start 4.8514 -48.7934)
		(end 13.3858 -48.7934)
		(stroke
			(width 2.54)
			(type default)
		)
		(layer "In6.Cu")
	)
	(gr_line
		(start 4.9022 -49.8856)
		(end 13.4366 -49.8856)
		(stroke
			(width 2.54)
			(type default)
		)
		(layer "In6.Cu")
	)
	(gr_line
		(start 4.9276 -50.2666)
		(end 13.462 -50.2666)
		(stroke
			(width 2.54)
			(type default)
		)
		(layer "In6.Cu")
	)
	(gr_line
		(start 4.953 -50.419)
		(end 13.4874 -50.419)
		(stroke
			(width 2.54)
			(type default)
		)
		(layer "In6.Cu")
	)
	(gr_line
		(start 4.953 -50.0634)
		(end 13.4874 -50.0634)
		(stroke
			(width 2.54)
			(type default)
		)
		(layer "In6.Cu")
	)
	(gr_line
		(start 5.0038 -50.7238)
		(end 13.5382 -50.7238)
		(stroke
			(width 2.54)
			(type default)
		)
		(layer "In6.Cu")
	)
	(gr_line
		(start 5.0546 -51.181)
		(end 9.9314 -51.181)
		(stroke
			(width 2.54)
			(type default)
		)
		(layer "In6.Cu")
	)
	(gr_line
		(start 6.249924 -32.520128)
		(end 6.249924 -28.999942)
		(stroke
			(width 1.016)
			(type default)
		)
		(layer "In6.Cu")
	)
	(gr_arc
		(start 6.249924 -28.999942)
		(mid 4.401168 -27.252413)
		(end 2.760726 -29.197046)
		(stroke
			(width 1.016)
			(type default)
		)
		(layer "In6.Cu")
	)
	(gr_line
		(start 6.45033 -32.720534)
		(end 6.249924 -32.520128)
		(stroke
			(width 1.016)
			(type default)
		)
		(layer "In6.Cu")
	)
	(gr_line
		(start 8.950198 -53.299868)
		(end 1.49987 -53.299868)
		(stroke
			(width 1.016)
			(type default)
		)
		(layer "In6.Cu")
	)
	(gr_line
		(start 10.450068 -51.799998)
		(end 8.950198 -53.299868)
		(stroke
			(width 1.016)
			(type default)
		)
		(layer "In6.Cu")
	)
	(gr_line
		(start 10.450068 -42.650664)
		(end 10.450068 -51.799998)
		(stroke
			(width 1.016)
			(type default)
		)
		(layer "In6.Cu")
	)
	(gr_arc
		(start 10.450068 -42.650664)
		(mid 11.047577 -42.898154)
		(end 10.80008 -42.300652)
		(stroke
			(width 1.016)
			(type default)
		)
		(layer "In6.Cu")
	)
	(gr_line
		(start 10.541 -46.8376)
		(end 10.9982 -46.3804)
		(stroke
			(width 0.508)
			(type default)
		)
		(layer "In6.Cu")
	)
	(gr_line
		(start 10.7188 -45.6692)
		(end 10.7696 -45.6184)
		(stroke
			(width 0.762)
			(type default)
		)
		(layer "In6.Cu")
	)
	(gr_line
		(start 10.7696 -45.72)
		(end 10.7188 -45.6692)
		(stroke
			(width 0.762)
			(type default)
		)
		(layer "In6.Cu")
	)
	(gr_line
		(start 10.7696 -45.6184)
		(end 51.9176 -45.6184)
		(stroke
			(width 0.762)
			(type default)
		)
		(layer "In6.Cu")
	)
	(gr_line
		(start 10.9982 -46.3804)
		(end 11.4554 -45.9232)
		(stroke
			(width 1.27)
			(type default)
		)
		(layer "In6.Cu")
	)
	(gr_line
		(start 11.150092 -51.799998)
		(end 12.649962 -53.299868)
		(stroke
			(width 1.016)
			(type default)
		)
		(layer "In6.Cu")
	)
	(gr_arc
		(start 11.150092 -42.650664)
		(mid 11.047562 -42.403198)
		(end 10.80008 -42.300652)
		(stroke
			(width 1.016)
			(type default)
		)
		(layer "In6.Cu")
	)
	(gr_line
		(start 11.150092 -42.650664)
		(end 11.150092 -51.799998)
		(stroke
			(width 1.016)
			(type default)
		)
		(layer "In6.Cu")
	)
	(gr_line
		(start 11.1506 -45.7962)
		(end 11.3284 -45.6184)
		(stroke
			(width 0.762)
			(type default)
		)
		(layer "In6.Cu")
	)
	(gr_line
		(start 11.303 -45.9486)
		(end 11.1506 -45.7962)
		(stroke
			(width 1.27)
			(type default)
		)
		(layer "In6.Cu")
	)
	(gr_line
		(start 11.3284 -45.6184)
		(end 51.9176 -45.6184)
		(stroke
			(width 0.762)
			(type default)
		)
		(layer "In6.Cu")
	)
	(gr_line
		(start 11.4554 -45.9232)
		(end 51.943 -45.9232)
		(stroke
			(width 1.27)
			(type default)
		)
		(layer "In6.Cu")
	)
	(gr_line
		(start 11.5062 -50.7238)
		(end 11.5062 -46.5836)
		(stroke
			(width 2.54)
			(type default)
		)
		(layer "In6.Cu")
	)
	(gr_line
		(start 11.5062 -50.6222)
		(end 11.5062 -46.482)
		(stroke
			(width 2.54)
			(type default)
		)
		(layer "In6.Cu")
	)
	(gr_line
		(start 12.192 -51.6382)
		(end 12.192 -47.498)
		(stroke
			(width 2.54)
			(type default)
		)
		(layer "In6.Cu")
	)
	(gr_line
		(start 12.3444 -51.5874)
		(end 12.3444 -47.4472)
		(stroke
			(width 2.54)
			(type default)
		)
		(layer "In6.Cu")
	)
	(gr_line
		(start 12.649962 -53.299868)
		(end 50.580036 -53.299868)
		(stroke
			(width 1.016)
			(type default)
		)
		(layer "In6.Cu")
	)
	(gr_line
		(start 13.0302 -52.578)
		(end 13.0302 -48.4378)
		(stroke
			(width 2.54)
			(type default)
		)
		(layer "In6.Cu")
	)
	(gr_line
		(start 13.6906 -49.3268)
		(end 42.545 -49.3268)
		(stroke
			(width 7.62)
			(type default)
		)
		(layer "In6.Cu")
	)
	(gr_line
		(start 13.716 -52.197)
		(end 13.716 -48.0568)
		(stroke
			(width 2.54)
			(type default)
		)
		(layer "In6.Cu")
	)
	(gr_line
		(start 13.843 -49.276)
		(end 42.6974 -49.276)
		(stroke
			(width 7.62)
			(type default)
		)
		(layer "In6.Cu")
	)
	(gr_line
		(start 14.1986 -49.9872)
		(end 43.053 -49.9872)
		(stroke
			(width 7.62)
			(type default)
		)
		(layer "In6.Cu")
	)
	(gr_line
		(start 14.6304 -52.4002)
		(end 14.6304 -48.26)
		(stroke
			(width 2.54)
			(type default)
		)
		(layer "In6.Cu")
	)
	(gr_line
		(start 15.5448 -49.276)
		(end 44.3992 -49.276)
		(stroke
			(width 7.62)
			(type default)
		)
		(layer "In6.Cu")
	)
	(gr_line
		(start 15.9258 -52.5272)
		(end 15.9258 -48.387)
		(stroke
			(width 2.54)
			(type default)
		)
		(layer "In6.Cu")
	)
	(gr_line
		(start 18.4912 -49.5808)
		(end 47.3456 -49.5808)
		(stroke
			(width 7.62)
			(type default)
		)
		(layer "In6.Cu")
	)
	(gr_line
		(start 18.6436 -49.4792)
		(end 47.498 -49.4792)
		(stroke
			(width 7.62)
			(type default)
		)
		(layer "In6.Cu")
	)
	(gr_line
		(start 18.9738 -49.3776)
		(end 47.8282 -49.3776)
		(stroke
			(width 7.62)
			(type default)
		)
		(layer "In6.Cu")
	)
	(gr_line
		(start 19.3294 -49.9872)
		(end 48.1838 -49.9872)
		(stroke
			(width 7.62)
			(type default)
		)
		(layer "In6.Cu")
	)
	(gr_line
		(start 19.7866 -49.8348)
		(end 48.641 -49.8348)
		(stroke
			(width 7.62)
			(type default)
		)
		(layer "In6.Cu")
	)
	(gr_line
		(start 19.7866 -49.276)
		(end 48.641 -49.276)
		(stroke
			(width 7.62)
			(type default)
		)
		(layer "In6.Cu")
	)
	(gr_line
		(start 19.8882 -49.022)
		(end 48.7426 -49.022)
		(stroke
			(width 7.62)
			(type default)
		)
		(layer "In6.Cu")
	)
	(gr_line
		(start 49.9872 -52.5272)
		(end 49.9872 -48.387)
		(stroke
			(width 2.54)
			(type default)
		)
		(layer "In6.Cu")
	)
	(gr_line
		(start 50.038 -51.1556)
		(end 50.038 -47.0154)
		(stroke
			(width 2.54)
			(type default)
		)
		(layer "In6.Cu")
	)
	(gr_line
		(start 50.3174 -52.451)
		(end 50.3174 -48.3108)
		(stroke
			(width 2.54)
			(type default)
		)
		(layer "In6.Cu")
	)
	(gr_line
		(start 50.546 -52.2224)
		(end 50.546 -48.0822)
		(stroke
			(width 2.54)
			(type default)
		)
		(layer "In6.Cu")
	)
	(gr_line
		(start 50.580036 -53.299868)
		(end 52.079906 -51.799998)
		(stroke
			(width 1.016)
			(type default)
		)
		(layer "In6.Cu")
	)
	(gr_line
		(start 50.8254 -51.8922)
		(end 50.8254 -47.752)
		(stroke
			(width 2.54)
			(type default)
		)
		(layer "In6.Cu")
	)
	(gr_line
		(start 50.927 -50.7746)
		(end 50.927 -46.6344)
		(stroke
			(width 2.54)
			(type default)
		)
		(layer "In6.Cu")
	)
	(gr_line
		(start 51.0286 -50.6984)
		(end 51.0286 -46.5582)
		(stroke
			(width 2.54)
			(type default)
		)
		(layer "In6.Cu")
	)
	(gr_line
		(start 51.2318 -51.4858)
		(end 51.2318 -47.3456)
		(stroke
			(width 2.54)
			(type default)
		)
		(layer "In6.Cu")
	)
	(gr_line
		(start 51.2826 -50.7238)
		(end 51.2826 -46.5836)
		(stroke
			(width 2.54)
			(type default)
		)
		(layer "In6.Cu")
	)
	(gr_line
		(start 51.816 -45.72)
		(end 10.7696 -45.72)
		(stroke
			(width 0.762)
			(type default)
		)
		(layer "In6.Cu")
	)
	(gr_line
		(start 51.9176 -45.9486)
		(end 11.303 -45.9486)
		(stroke
			(width 1.27)
			(type default)
		)
		(layer "In6.Cu")
	)
	(gr_line
		(start 51.9176 -45.6184)
		(end 51.816 -45.72)
		(stroke
			(width 0.762)
			(type default)
		)
		(layer "In6.Cu")
	)
	(gr_line
		(start 51.943 -45.9232)
		(end 51.9176 -45.9486)
		(stroke
			(width 1.27)
			(type default)
		)
		(layer "In6.Cu")
	)
	(gr_line
		(start 52.079906 -51.799998)
		(end 52.079906 -43.319954)
		(stroke
			(width 1.016)
			(type default)
		)
		(layer "In6.Cu")
	)
	(gr_arc
		(start 53.079904 -42.319956)
		(mid 52.37278 -42.612844)
		(end 52.079906 -43.319954)
		(stroke
			(width 1.016)
			(type default)
		)
		(layer "In6.Cu")
	)
	(gr_line
		(start 53.079904 -42.319956)
		(end 55.0799 -42.319956)
		(stroke
			(width 1.016)
			(type default)
		)
		(layer "In6.Cu")
	)
	(gr_arc
		(start 56.079898 -50.31994)
		(mid 56.665683 -51.734151)
		(end 58.079894 -52.319936)
		(stroke
			(width 1.016)
			(type default)
		)
		(layer "In6.Cu")
	)
	(gr_arc
		(start 56.079898 -43.319954)
		(mid 55.786989 -42.612878)
		(end 55.0799 -42.319956)
		(stroke
			(width 1.016)
			(type default)
		)
		(layer "In6.Cu")
	)
	(gr_line
		(start 56.079898 -43.319954)
		(end 56.079898 -50.31994)
		(stroke
			(width 1.016)
			(type default)
		)
		(layer "In6.Cu")
	)
	(gr_line
		(start 58.079894 -52.319936)
		(end 94.681802 -52.319936)
		(stroke
			(width 1.016)
			(type default)
		)
		(layer "In6.Cu")
	)
	(gr_arc
		(start 78.060042 -45.063664)
		(mid 79.682839 -50.497558)
		(end 81.760314 -45.22089)
		(stroke
			(width 1.016)
			(type default)
		)
		(layer "In6.Cu")
	)
	(gr_line
		(start 78.060042 -41.70807)
		(end 78.060042 -45.063664)
		(stroke
			(width 1.016)
			(type default)
		)
		(layer "In6.Cu")
	)
	(gr_line
		(start 78.07071 -41.697402)
		(end 78.060042 -41.70807)
		(stroke
			(width 1.016)
			(type default)
		)
		(layer "In6.Cu")
	)
	(gr_line
		(start 79.809594 -47.500286)
		(end 79.809848 -47.50054)
		(stroke
			(width 4.064)
			(type default)
		)
		(layer "In6.Cu")
	)
	(gr_line
		(start 79.809594 -41.500044)
		(end 79.809594 -47.500286)
		(stroke
			(width 4.064)
			(type default)
		)
		(layer "In6.Cu")
	)
	(gr_line
		(start 79.809848 -47.50054)
		(end 79.809848 -47.500286)
		(stroke
			(width 6.604)
			(type default)
		)
		(layer "In6.Cu")
	)
	(gr_line
		(start 81.559908 -45.020484)
		(end 81.559908 -41.500298)
		(stroke
			(width 1.016)
			(type default)
		)
		(layer "In6.Cu")
	)
	(gr_arc
		(start 81.559908 -41.500298)
		(mid 79.711152 -39.752769)
		(end 78.07071 -41.697402)
		(stroke
			(width 1.016)
			(type default)
		)
		(layer "In6.Cu")
	)
	(gr_line
		(start 81.760314 -45.22089)
		(end 81.559908 -45.020484)
		(stroke
			(width 1.016)
			(type default)
		)
		(layer "In6.Cu")
	)
	(gr_arc
		(start 94.681802 -52.319936)
		(mid 95.388907 -52.027043)
		(end 95.6818 -51.319938)
		(stroke
			(width 1.016)
			(type default)
		)
		(layer "In6.Cu")
	)
	(gr_line
		(start 95.6818 -51.319938)
		(end 95.6818 -50.8)
		(stroke
			(width 1.016)
			(type default)
		)
		(layer "In6.Cu")
	)
	(gr_arc
		(start 96.681798 -49.800002)
		(mid 95.974694 -50.092895)
		(end 95.6818 -50.8)
		(stroke
			(width 1.016)
			(type default)
		)
		(layer "In6.Cu")
	)
	(gr_line
		(start 96.681798 -49.800002)
		(end 112.06988 -49.800002)
		(stroke
			(width 1.016)
			(type default)
		)
		(layer "In6.Cu")
	)
	(gr_line
		(start 101.576632 -11.378946)
		(end 101.576632 -9.194546)
		(stroke
			(width 0.254)
			(type default)
		)
		(layer "In6.Cu")
	)
	(gr_line
		(start 101.576632 -9.194546)
		(end 103.151432 -9.194546)
		(stroke
			(width 0.254)
			(type default)
		)
		(layer "In6.Cu")
	)
	(gr_line
		(start 101.602032 -11.378946)
		(end 101.602032 -9.245346)
		(stroke
			(width 0.254)
			(type default)
		)
		(layer "In6.Cu")
	)
	(gr_line
		(start 101.602032 -9.245346)
		(end 103.126032 -9.245346)
		(stroke
			(width 0.254)
			(type default)
		)
		(layer "In6.Cu")
	)
	(gr_line
		(start 101.652832 -11.353546)
		(end 101.652832 -9.372346)
		(stroke
			(width 0.254)
			(type default)
		)
		(layer "In6.Cu")
	)
	(gr_line
		(start 101.652832 -9.372346)
		(end 103.100632 -9.372346)
		(stroke
			(width 0.254)
			(type default)
		)
		(layer "In6.Cu")
	)
	(gr_line
		(start 101.706934 -11.302746)
		(end 102.011734 -11.302746)
		(stroke
			(width 0.1016)
			(type default)
		)
		(layer "In6.Cu")
	)
	(gr_line
		(start 101.706934 -9.296146)
		(end 101.706934 -11.302746)
		(stroke
			(width 0.1016)
			(type default)
		)
		(layer "In6.Cu")
	)
	(gr_line
		(start 101.734874 -5.57784)
		(end 103.004874 -5.57784)
		(stroke
			(width 1.016)
			(type default)
		)
		(layer "In6.Cu")
	)
	(gr_line
		(start 101.757734 -11.226546)
		(end 102.849934 -11.226546)
		(stroke
			(width 0.2032)
			(type default)
		)
		(layer "In6.Cu")
	)
	(gr_line
		(start 101.757734 -9.372346)
		(end 101.757734 -11.226546)
		(stroke
			(width 0.2032)
			(type default)
		)
		(layer "In6.Cu")
	)
	(gr_line
		(start 101.783134 -11.226546)
		(end 102.951534 -11.226546)
		(stroke
			(width 0.2032)
			(type default)
		)
		(layer "In6.Cu")
	)
	(gr_line
		(start 101.783134 -9.423146)
		(end 101.783134 -11.226546)
		(stroke
			(width 0.2032)
			(type default)
		)
		(layer "In6.Cu")
	)
	(gr_line
		(start 101.830632 -11.124946)
		(end 101.830632 -9.575546)
		(stroke
			(width 0.762)
			(type default)
		)
		(layer "In6.Cu")
	)
	(gr_line
		(start 101.830632 -11.124946)
		(end 102.745032 -11.124946)
		(stroke
			(width 0.762)
			(type default)
		)
		(layer "In6.Cu")
	)
	(gr_line
		(start 101.830632 -11.099546)
		(end 101.830632 -9.550146)
		(stroke
			(width 0.762)
			(type default)
		)
		(layer "In6.Cu")
	)
	(gr_line
		(start 101.830632 -10.997946)
		(end 101.830632 -9.448546)
		(stroke
			(width 0.762)
			(type default)
		)
		(layer "In6.Cu")
	)
	(gr_line
		(start 101.830632 -9.448546)
		(end 102.745032 -9.448546)
		(stroke
			(width 0.762)
			(type default)
		)
		(layer "In6.Cu")
	)
	(gr_line
		(start 101.833934 -11.175746)
		(end 102.926134 -11.175746)
		(stroke
			(width 0.2032)
			(type default)
		)
		(layer "In6.Cu")
	)
	(gr_line
		(start 101.833934 -9.473946)
		(end 101.833934 -11.175746)
		(stroke
			(width 0.2032)
			(type default)
		)
		(layer "In6.Cu")
	)
	(gr_line
		(start 101.856032 -10.997946)
		(end 102.770432 -10.997946)
		(stroke
			(width 0.762)
			(type default)
		)
		(layer "In6.Cu")
	)
	(gr_line
		(start 101.856032 -9.575546)
		(end 102.770432 -9.575546)
		(stroke
			(width 0.762)
			(type default)
		)
		(layer "In6.Cu")
	)
	(gr_line
		(start 101.935534 -11.074146)
		(end 102.722934 -11.074146)
		(stroke
			(width 0.508)
			(type default)
		)
		(layer "In6.Cu")
	)
	(gr_line
		(start 101.935534 -11.048746)
		(end 101.935534 -9.524746)
		(stroke
			(width 0.508)
			(type default)
		)
		(layer "In6.Cu")
	)
	(gr_line
		(start 101.960934 -11.074146)
		(end 101.960934 -9.550146)
		(stroke
			(width 0.508)
			(type default)
		)
		(layer "In6.Cu")
	)
	(gr_line
		(start 101.983032 -11.124946)
		(end 102.897432 -11.124946)
		(stroke
			(width 0.762)
			(type default)
		)
		(layer "In6.Cu")
	)
	(gr_line
		(start 101.983032 -9.448546)
		(end 102.897432 -9.448546)
		(stroke
			(width 0.762)
			(type default)
		)
		(layer "In6.Cu")
	)
	(gr_line
		(start 101.986334 -9.524746)
		(end 102.722934 -9.524746)
		(stroke
			(width 0.508)
			(type default)
		)
		(layer "In6.Cu")
	)
	(gr_line
		(start 102.011734 -11.302746)
		(end 103.002334 -11.302746)
		(stroke
			(width 0.1016)
			(type default)
		)
		(layer "In6.Cu")
	)
	(gr_line
		(start 102.011734 -11.074146)
		(end 102.011734 -9.550146)
		(stroke
			(width 0.508)
			(type default)
		)
		(layer "In6.Cu")
	)
	(gr_line
		(start 102.037134 -11.074146)
		(end 102.037134 -9.550146)
		(stroke
			(width 0.508)
			(type default)
		)
		(layer "In6.Cu")
	)
	(gr_line
		(start 102.062534 -11.074146)
		(end 102.062534 -9.550146)
		(stroke
			(width 0.508)
			(type default)
		)
		(layer "In6.Cu")
	)
	(gr_line
		(start 102.087934 -11.074146)
		(end 102.087934 -9.550146)
		(stroke
			(width 0.508)
			(type default)
		)
		(layer "In6.Cu")
	)
	(gr_line
		(start 102.087934 -11.048746)
		(end 102.087934 -9.524746)
		(stroke
			(width 0.508)
			(type default)
		)
		(layer "In6.Cu")
	)
	(gr_line
		(start 102.113334 -11.074146)
		(end 102.113334 -9.550146)
		(stroke
			(width 0.508)
			(type default)
		)
		(layer "In6.Cu")
	)
	(gr_line
		(start 102.138734 -11.074146)
		(end 102.138734 -9.550146)
		(stroke
			(width 0.508)
			(type default)
		)
		(layer "In6.Cu")
	)
	(gr_line
		(start 102.189534 -11.074146)
		(end 102.189534 -9.550146)
		(stroke
			(width 0.508)
			(type default)
		)
		(layer "In6.Cu")
	)
	(gr_line
		(start 102.189534 -11.048746)
		(end 102.189534 -9.524746)
		(stroke
			(width 0.508)
			(type default)
		)
		(layer "In6.Cu")
	)
	(gr_line
		(start 102.214934 -11.074146)
		(end 102.214934 -9.550146)
		(stroke
			(width 0.508)
			(type default)
		)
		(layer "In6.Cu")
	)
	(gr_line
		(start 102.240334 -11.074146)
		(end 102.240334 -9.550146)
		(stroke
			(width 0.508)
			(type default)
		)
		(layer "In6.Cu")
	)
	(gr_line
		(start 102.265734 -11.074146)
		(end 102.265734 -9.550146)
		(stroke
			(width 0.508)
			(type default)
		)
		(layer "In6.Cu")
	)
	(gr_line
		(start 102.316534 -11.074146)
		(end 102.316534 -9.550146)
		(stroke
			(width 0.508)
			(type default)
		)
		(layer "In6.Cu")
	)
	(gr_line
		(start 102.341934 -11.074146)
		(end 102.341934 -9.550146)
		(stroke
			(width 0.508)
			(type default)
		)
		(layer "In6.Cu")
	)
	(gr_line
		(start 102.341934 -11.048746)
		(end 102.341934 -9.524746)
		(stroke
			(width 0.508)
			(type default)
		)
		(layer "In6.Cu")
	)
	(gr_line
		(start 102.367334 -11.074146)
		(end 102.367334 -9.550146)
		(stroke
			(width 0.508)
			(type default)
		)
		(layer "In6.Cu")
	)
	(gr_line
		(start 102.392734 -11.074146)
		(end 102.392734 -9.550146)
		(stroke
			(width 0.508)
			(type default)
		)
		(layer "In6.Cu")
	)
	(gr_line
		(start 102.418134 -11.074146)
		(end 102.418134 -9.550146)
		(stroke
			(width 0.508)
			(type default)
		)
		(layer "In6.Cu")
	)
	(gr_line
		(start 102.418134 -11.048746)
		(end 102.418134 -9.524746)
		(stroke
			(width 0.508)
			(type default)
		)
		(layer "In6.Cu")
	)
	(gr_line
		(start 102.443534 -11.074146)
		(end 102.443534 -9.550146)
		(stroke
			(width 0.508)
			(type default)
		)
		(layer "In6.Cu")
	)
	(gr_line
		(start 102.468934 -11.074146)
		(end 102.468934 -9.550146)
		(stroke
			(width 0.508)
			(type default)
		)
		(layer "In6.Cu")
	)
	(gr_line
		(start 102.468934 -11.048746)
		(end 102.468934 -9.524746)
		(stroke
			(width 0.508)
			(type default)
		)
		(layer "In6.Cu")
	)
	(gr_line
		(start 102.494334 -11.074146)
		(end 102.494334 -9.550146)
		(stroke
			(width 0.508)
			(type default)
		)
		(layer "In6.Cu")
	)
	(gr_line
		(start 102.494334 -11.048746)
		(end 102.494334 -9.524746)
		(stroke
			(width 0.508)
			(type default)
		)
		(layer "In6.Cu")
	)
	(gr_line
		(start 102.519734 -11.048746)
		(end 102.519734 -9.524746)
		(stroke
			(width 0.508)
			(type default)
		)
		(layer "In6.Cu")
	)
	(gr_line
		(start 102.545134 -11.074146)
		(end 102.545134 -9.550146)
		(stroke
			(width 0.508)
			(type default)
		)
		(layer "In6.Cu")
	)
	(gr_line
		(start 102.567232 -11.378946)
		(end 101.576632 -11.378946)
		(stroke
			(width 0.254)
			(type default)
		)
		(layer "In6.Cu")
	)
	(gr_line
		(start 102.570534 -11.048746)
		(end 102.570534 -9.524746)
		(stroke
			(width 0.508)
			(type default)
		)
		(layer "In6.Cu")
	)
	(gr_line
		(start 102.595934 -11.048746)
		(end 102.595934 -9.524746)
		(stroke
			(width 0.508)
			(type default)
		)
		(layer "In6.Cu")
	)
	(gr_line
		(start 102.621334 -11.074146)
		(end 102.621334 -9.550146)
		(stroke
			(width 0.508)
			(type default)
		)
		(layer "In6.Cu")
	)
	(gr_line
		(start 102.646734 -11.074146)
		(end 102.646734 -9.550146)
		(stroke
			(width 0.508)
			(type default)
		)
		(layer "In6.Cu")
	)
	(gr_line
		(start 102.646734 -11.048746)
		(end 102.646734 -9.524746)
		(stroke
			(width 0.508)
			(type default)
		)
		(layer "In6.Cu")
	)
	(gr_line
		(start 102.697534 -11.074146)
		(end 102.697534 -9.550146)
		(stroke
			(width 0.508)
			(type default)
		)
		(layer "In6.Cu")
	)
	(gr_line
		(start 102.697534 -11.048746)
		(end 102.697534 -9.524746)
		(stroke
			(width 0.508)
			(type default)
		)
		(layer "In6.Cu")
	)
	(gr_line
		(start 102.748334 -11.074146)
		(end 102.748334 -9.550146)
		(stroke
			(width 0.508)
			(type default)
		)
		(layer "In6.Cu")
	)
	(gr_line
		(start 102.748334 -11.048746)
		(end 102.748334 -9.524746)
		(stroke
			(width 0.508)
			(type default)
		)
		(layer "In6.Cu")
	)
	(gr_line
		(start 102.770432 -11.099546)
		(end 102.770432 -9.550146)
		(stroke
			(width 0.762)
			(type default)
		)
		(layer "In6.Cu")
	)
	(gr_line
		(start 102.773734 -11.074146)
		(end 102.773734 -9.550146)
		(stroke
			(width 0.508)
			(type default)
		)
		(layer "In6.Cu")
	)
	(gr_line
		(start 102.799134 -11.074146)
		(end 102.799134 -9.550146)
		(stroke
			(width 0.508)
			(type default)
		)
		(layer "In6.Cu")
	)
	(gr_line
		(start 102.849934 -11.226546)
		(end 102.875334 -11.226546)
		(stroke
			(width 0.2032)
			(type default)
		)
		(layer "In6.Cu")
	)
	(gr_line
		(start 102.875334 -11.226546)
		(end 102.875334 -9.473946)
		(stroke
			(width 0.2032)
			(type default)
		)
		(layer "In6.Cu")
	)
	(gr_line
		(start 102.875334 -9.473946)
		(end 101.833934 -9.473946)
		(stroke
			(width 0.2032)
			(type default)
		)
		(layer "In6.Cu")
	)
	(gr_line
		(start 102.897432 -11.124946)
		(end 102.897432 -9.575546)
		(stroke
			(width 0.762)
			(type default)
		)
		(layer "In6.Cu")
	)
	(gr_line
		(start 102.897432 -11.099546)
		(end 102.897432 -9.600946)
		(stroke
			(width 0.762)
			(type default)
		)
		(layer "In6.Cu")
	)
	(gr_line
		(start 102.897432 -10.997946)
		(end 102.897432 -9.448546)
		(stroke
			(width 0.762)
			(type default)
		)
		(layer "In6.Cu")
	)
	(gr_line
		(start 102.926134 -11.175746)
		(end 102.926134 -9.423146)
		(stroke
			(width 0.2032)
			(type default)
		)
		(layer "In6.Cu")
	)
	(gr_line
		(start 102.926134 -9.423146)
		(end 101.783134 -9.423146)
		(stroke
			(width 0.2032)
			(type default)
		)
		(layer "In6.Cu")
	)
	(gr_line
		(start 102.951534 -11.226546)
		(end 102.951534 -9.372346)
		(stroke
			(width 0.2032)
			(type default)
		)
		(layer "In6.Cu")
	)
	(gr_line
		(start 102.951534 -9.372346)
		(end 101.757734 -9.372346)
		(stroke
			(width 0.2032)
			(type default)
		)
		(layer "In6.Cu")
	)
	(gr_line
		(start 103.002334 -11.302746)
		(end 103.002334 -9.296146)
		(stroke
			(width 0.1016)
			(type default)
		)
		(layer "In6.Cu")
	)
	(gr_line
		(start 103.002334 -9.296146)
		(end 101.706934 -9.296146)
		(stroke
			(width 0.1016)
			(type default)
		)
		(layer "In6.Cu")
	)
	(gr_line
		(start 103.100632 -11.226546)
		(end 102.849934 -11.226546)
		(stroke
			(width 0.254)
			(type default)
		)
		(layer "In6.Cu")
	)
	(gr_line
		(start 103.100632 -9.372346)
		(end 103.100632 -11.226546)
		(stroke
			(width 0.254)
			(type default)
		)
		(layer "In6.Cu")
	)
	(gr_line
		(start 103.126032 -11.353546)
		(end 101.652832 -11.353546)
		(stroke
			(width 0.254)
			(type default)
		)
		(layer "In6.Cu")
	)
	(gr_line
		(start 103.126032 -9.245346)
		(end 103.126032 -11.353546)
		(stroke
			(width 0.254)
			(type default)
		)
		(layer "In6.Cu")
	)
	(gr_line
		(start 103.151432 -11.378946)
		(end 101.602032 -11.378946)
		(stroke
			(width 0.254)
			(type default)
		)
		(layer "In6.Cu")
	)
	(gr_line
		(start 103.151432 -9.194546)
		(end 103.151432 -11.378946)
		(stroke
			(width 0.254)
			(type default)
		)
		(layer "In6.Cu")
	)
	(gr_line
		(start 106.376724 -11.378946)
		(end 106.376724 -9.194546)
		(stroke
			(width 0.254)
			(type default)
		)
		(layer "In6.Cu")
	)
	(gr_line
		(start 106.376724 -9.194546)
		(end 107.951524 -9.194546)
		(stroke
			(width 0.254)
			(type default)
		)
		(layer "In6.Cu")
	)
	(gr_line
		(start 106.402124 -11.378946)
		(end 106.402124 -9.245346)
		(stroke
			(width 0.254)
			(type default)
		)
		(layer "In6.Cu")
	)
	(gr_line
		(start 106.402124 -9.245346)
		(end 107.926124 -9.245346)
		(stroke
			(width 0.254)
			(type default)
		)
		(layer "In6.Cu")
	)
	(gr_line
		(start 106.452924 -11.353546)
		(end 106.452924 -9.372346)
		(stroke
			(width 0.254)
			(type default)
		)
		(layer "In6.Cu")
	)
	(gr_line
		(start 106.452924 -9.372346)
		(end 107.900724 -9.372346)
		(stroke
			(width 0.254)
			(type default)
		)
		(layer "In6.Cu")
	)
	(gr_line
		(start 106.507026 -11.302746)
		(end 106.811826 -11.302746)
		(stroke
			(width 0.1016)
			(type default)
		)
		(layer "In6.Cu")
	)
	(gr_line
		(start 106.507026 -9.296146)
		(end 106.507026 -11.302746)
		(stroke
			(width 0.1016)
			(type default)
		)
		(layer "In6.Cu")
	)
	(gr_line
		(start 106.557826 -11.226546)
		(end 107.650026 -11.226546)
		(stroke
			(width 0.2032)
			(type default)
		)
		(layer "In6.Cu")
	)
	(gr_line
		(start 106.557826 -9.372346)
		(end 106.557826 -11.226546)
		(stroke
			(width 0.2032)
			(type default)
		)
		(layer "In6.Cu")
	)
	(gr_line
		(start 106.583226 -11.226546)
		(end 107.751626 -11.226546)
		(stroke
			(width 0.2032)
			(type default)
		)
		(layer "In6.Cu")
	)
	(gr_line
		(start 106.583226 -9.423146)
		(end 106.583226 -11.226546)
		(stroke
			(width 0.2032)
			(type default)
		)
		(layer "In6.Cu")
	)
	(gr_line
		(start 106.630724 -11.124946)
		(end 106.630724 -9.575546)
		(stroke
			(width 0.762)
			(type default)
		)
		(layer "In6.Cu")
	)
	(gr_line
		(start 106.630724 -11.124946)
		(end 107.545124 -11.124946)
		(stroke
			(width 0.762)
			(type default)
		)
		(layer "In6.Cu")
	)
	(gr_line
		(start 106.630724 -11.099546)
		(end 106.630724 -9.550146)
		(stroke
			(width 0.762)
			(type default)
		)
		(layer "In6.Cu")
	)
	(gr_line
		(start 106.630724 -10.997946)
		(end 106.630724 -9.448546)
		(stroke
			(width 0.762)
			(type default)
		)
		(layer "In6.Cu")
	)
	(gr_line
		(start 106.630724 -9.448546)
		(end 107.545124 -9.448546)
		(stroke
			(width 0.762)
			(type default)
		)
		(layer "In6.Cu")
	)
	(gr_line
		(start 106.634026 -11.175746)
		(end 107.726226 -11.175746)
		(stroke
			(width 0.2032)
			(type default)
		)
		(layer "In6.Cu")
	)
	(gr_line
		(start 106.634026 -9.473946)
		(end 106.634026 -11.175746)
		(stroke
			(width 0.2032)
			(type default)
		)
		(layer "In6.Cu")
	)
	(gr_line
		(start 106.656124 -10.997946)
		(end 107.570524 -10.997946)
		(stroke
			(width 0.762)
			(type default)
		)
		(layer "In6.Cu")
	)
	(gr_line
		(start 106.656124 -9.575546)
		(end 107.570524 -9.575546)
		(stroke
			(width 0.762)
			(type default)
		)
		(layer "In6.Cu")
	)
	(gr_line
		(start 106.735626 -11.074146)
		(end 107.523026 -11.074146)
		(stroke
			(width 0.508)
			(type default)
		)
		(layer "In6.Cu")
	)
	(gr_line
		(start 106.735626 -11.048746)
		(end 106.735626 -9.524746)
		(stroke
			(width 0.508)
			(type default)
		)
		(layer "In6.Cu")
	)
	(gr_line
		(start 106.761026 -11.074146)
		(end 106.761026 -9.550146)
		(stroke
			(width 0.508)
			(type default)
		)
		(layer "In6.Cu")
	)
	(gr_line
		(start 106.783124 -11.124946)
		(end 107.697524 -11.124946)
		(stroke
			(width 0.762)
			(type default)
		)
		(layer "In6.Cu")
	)
	(gr_line
		(start 106.783124 -9.448546)
		(end 107.697524 -9.448546)
		(stroke
			(width 0.762)
			(type default)
		)
		(layer "In6.Cu")
	)
	(gr_line
		(start 106.786426 -9.524746)
		(end 107.523026 -9.524746)
		(stroke
			(width 0.508)
			(type default)
		)
		(layer "In6.Cu")
	)
	(gr_line
		(start 106.811826 -11.302746)
		(end 107.802426 -11.302746)
		(stroke
			(width 0.1016)
			(type default)
		)
		(layer "In6.Cu")
	)
	(gr_line
		(start 106.811826 -11.074146)
		(end 106.811826 -9.550146)
		(stroke
			(width 0.508)
			(type default)
		)
		(layer "In6.Cu")
	)
	(gr_line
		(start 106.837226 -11.074146)
		(end 106.837226 -9.550146)
		(stroke
			(width 0.508)
			(type default)
		)
		(layer "In6.Cu")
	)
	(gr_line
		(start 106.862626 -11.074146)
		(end 106.862626 -9.550146)
		(stroke
			(width 0.508)
			(type default)
		)
		(layer "In6.Cu")
	)
	(gr_line
		(start 106.888026 -11.074146)
		(end 106.888026 -9.550146)
		(stroke
			(width 0.508)
			(type default)
		)
		(layer "In6.Cu")
	)
	(gr_line
		(start 106.888026 -11.048746)
		(end 106.888026 -9.524746)
		(stroke
			(width 0.508)
			(type default)
		)
		(layer "In6.Cu")
	)
	(gr_line
		(start 106.913426 -11.074146)
		(end 106.913426 -9.550146)
		(stroke
			(width 0.508)
			(type default)
		)
		(layer "In6.Cu")
	)
	(gr_line
		(start 106.938826 -11.074146)
		(end 106.938826 -9.550146)
		(stroke
			(width 0.508)
			(type default)
		)
		(layer "In6.Cu")
	)
	(gr_line
		(start 106.989626 -11.074146)
		(end 106.989626 -9.550146)
		(stroke
			(width 0.508)
			(type default)
		)
		(layer "In6.Cu")
	)
	(gr_line
		(start 106.989626 -11.048746)
		(end 106.989626 -9.524746)
		(stroke
			(width 0.508)
			(type default)
		)
		(layer "In6.Cu")
	)
	(gr_line
		(start 107.015026 -11.074146)
		(end 107.015026 -9.550146)
		(stroke
			(width 0.508)
			(type default)
		)
		(layer "In6.Cu")
	)
	(gr_line
		(start 107.040426 -11.074146)
		(end 107.040426 -9.550146)
		(stroke
			(width 0.508)
			(type default)
		)
		(layer "In6.Cu")
	)
	(gr_line
		(start 107.065826 -11.074146)
		(end 107.065826 -9.550146)
		(stroke
			(width 0.508)
			(type default)
		)
		(layer "In6.Cu")
	)
	(gr_line
		(start 107.116626 -11.074146)
		(end 107.116626 -9.550146)
		(stroke
			(width 0.508)
			(type default)
		)
		(layer "In6.Cu")
	)
	(gr_line
		(start 107.142026 -11.074146)
		(end 107.142026 -9.550146)
		(stroke
			(width 0.508)
			(type default)
		)
		(layer "In6.Cu")
	)
	(gr_line
		(start 107.142026 -11.048746)
		(end 107.142026 -9.524746)
		(stroke
			(width 0.508)
			(type default)
		)
		(layer "In6.Cu")
	)
	(gr_line
		(start 107.167426 -11.074146)
		(end 107.167426 -9.550146)
		(stroke
			(width 0.508)
			(type default)
		)
		(layer "In6.Cu")
	)
	(gr_line
		(start 107.192826 -11.074146)
		(end 107.192826 -9.550146)
		(stroke
			(width 0.508)
			(type default)
		)
		(layer "In6.Cu")
	)
	(gr_line
		(start 107.218226 -11.074146)
		(end 107.218226 -9.550146)
		(stroke
			(width 0.508)
			(type default)
		)
		(layer "In6.Cu")
	)
	(gr_line
		(start 107.218226 -11.048746)
		(end 107.218226 -9.524746)
		(stroke
			(width 0.508)
			(type default)
		)
		(layer "In6.Cu")
	)
	(gr_line
		(start 107.243626 -11.074146)
		(end 107.243626 -9.550146)
		(stroke
			(width 0.508)
			(type default)
		)
		(layer "In6.Cu")
	)
	(gr_line
		(start 107.269026 -11.074146)
		(end 107.269026 -9.550146)
		(stroke
			(width 0.508)
			(type default)
		)
		(layer "In6.Cu")
	)
	(gr_line
		(start 107.269026 -11.048746)
		(end 107.269026 -9.524746)
		(stroke
			(width 0.508)
			(type default)
		)
		(layer "In6.Cu")
	)
	(gr_line
		(start 107.294426 -11.074146)
		(end 107.294426 -9.550146)
		(stroke
			(width 0.508)
			(type default)
		)
		(layer "In6.Cu")
	)
	(gr_line
		(start 107.294426 -11.048746)
		(end 107.294426 -9.524746)
		(stroke
			(width 0.508)
			(type default)
		)
		(layer "In6.Cu")
	)
	(gr_line
		(start 107.319826 -11.048746)
		(end 107.319826 -9.524746)
		(stroke
			(width 0.508)
			(type default)
		)
		(layer "In6.Cu")
	)
	(gr_line
		(start 107.345226 -11.074146)
		(end 107.345226 -9.550146)
		(stroke
			(width 0.508)
			(type default)
		)
		(layer "In6.Cu")
	)
	(gr_line
		(start 107.367324 -11.378946)
		(end 106.376724 -11.378946)
		(stroke
			(width 0.254)
			(type default)
		)
		(layer "In6.Cu")
	)
	(gr_line
		(start 107.370626 -11.048746)
		(end 107.370626 -9.524746)
		(stroke
			(width 0.508)
			(type default)
		)
		(layer "In6.Cu")
	)
	(gr_line
		(start 107.396026 -11.048746)
		(end 107.396026 -9.524746)
		(stroke
			(width 0.508)
			(type default)
		)
		(layer "In6.Cu")
	)
	(gr_line
		(start 107.421426 -11.074146)
		(end 107.421426 -9.550146)
		(stroke
			(width 0.508)
			(type default)
		)
		(layer "In6.Cu")
	)
	(gr_line
		(start 107.446826 -11.074146)
		(end 107.446826 -9.550146)
		(stroke
			(width 0.508)
			(type default)
		)
		(layer "In6.Cu")
	)
	(gr_line
		(start 107.446826 -11.048746)
		(end 107.446826 -9.524746)
		(stroke
			(width 0.508)
			(type default)
		)
		(layer "In6.Cu")
	)
	(gr_line
		(start 107.497626 -11.074146)
		(end 107.497626 -9.550146)
		(stroke
			(width 0.508)
			(type default)
		)
		(layer "In6.Cu")
	)
	(gr_line
		(start 107.497626 -11.048746)
		(end 107.497626 -9.524746)
		(stroke
			(width 0.508)
			(type default)
		)
		(layer "In6.Cu")
	)
	(gr_line
		(start 107.548426 -11.074146)
		(end 107.548426 -9.550146)
		(stroke
			(width 0.508)
			(type default)
		)
		(layer "In6.Cu")
	)
	(gr_line
		(start 107.548426 -11.048746)
		(end 107.548426 -9.524746)
		(stroke
			(width 0.508)
			(type default)
		)
		(layer "In6.Cu")
	)
	(gr_line
		(start 107.570524 -11.099546)
		(end 107.570524 -9.550146)
		(stroke
			(width 0.762)
			(type default)
		)
		(layer "In6.Cu")
	)
	(gr_line
		(start 107.573826 -11.074146)
		(end 107.573826 -9.550146)
		(stroke
			(width 0.508)
			(type default)
		)
		(layer "In6.Cu")
	)
	(gr_line
		(start 107.599226 -11.074146)
		(end 107.599226 -9.550146)
		(stroke
			(width 0.508)
			(type default)
		)
		(layer "In6.Cu")
	)
	(gr_line
		(start 107.650026 -11.226546)
		(end 107.675426 -11.226546)
		(stroke
			(width 0.2032)
			(type default)
		)
		(layer "In6.Cu")
	)
	(gr_line
		(start 107.675426 -11.226546)
		(end 107.675426 -9.473946)
		(stroke
			(width 0.2032)
			(type default)
		)
		(layer "In6.Cu")
	)
	(gr_line
		(start 107.675426 -9.473946)
		(end 106.634026 -9.473946)
		(stroke
			(width 0.2032)
			(type default)
		)
		(layer "In6.Cu")
	)
	(gr_line
		(start 107.697524 -11.124946)
		(end 107.697524 -9.575546)
		(stroke
			(width 0.762)
			(type default)
		)
		(layer "In6.Cu")
	)
	(gr_line
		(start 107.697524 -11.099546)
		(end 107.697524 -9.600946)
		(stroke
			(width 0.762)
			(type default)
		)
		(layer "In6.Cu")
	)
	(gr_line
		(start 107.697524 -10.997946)
		(end 107.697524 -9.448546)
		(stroke
			(width 0.762)
			(type default)
		)
		(layer "In6.Cu")
	)
	(gr_line
		(start 107.726226 -11.175746)
		(end 107.726226 -9.423146)
		(stroke
			(width 0.2032)
			(type default)
		)
		(layer "In6.Cu")
	)
	(gr_line
		(start 107.726226 -9.423146)
		(end 106.583226 -9.423146)
		(stroke
			(width 0.2032)
			(type default)
		)
		(layer "In6.Cu")
	)
	(gr_line
		(start 107.751626 -11.226546)
		(end 107.751626 -9.372346)
		(stroke
			(width 0.2032)
			(type default)
		)
		(layer "In6.Cu")
	)
	(gr_line
		(start 107.751626 -9.372346)
		(end 106.557826 -9.372346)
		(stroke
			(width 0.2032)
			(type default)
		)
		(layer "In6.Cu")
	)
	(gr_line
		(start 107.802426 -11.302746)
		(end 107.802426 -9.296146)
		(stroke
			(width 0.1016)
			(type default)
		)
		(layer "In6.Cu")
	)
	(gr_line
		(start 107.802426 -9.296146)
		(end 106.507026 -9.296146)
		(stroke
			(width 0.1016)
			(type default)
		)
		(layer "In6.Cu")
	)
	(gr_line
		(start 107.900724 -11.226546)
		(end 107.650026 -11.226546)
		(stroke
			(width 0.254)
			(type default)
		)
		(layer "In6.Cu")
	)
	(gr_line
		(start 107.900724 -9.372346)
		(end 107.900724 -11.226546)
		(stroke
			(width 0.254)
			(type default)
		)
		(layer "In6.Cu")
	)
	(gr_line
		(start 107.926124 -11.353546)
		(end 106.452924 -11.353546)
		(stroke
			(width 0.254)
			(type default)
		)
		(layer "In6.Cu")
	)
	(gr_line
		(start 107.926124 -9.245346)
		(end 107.926124 -11.353546)
		(stroke
			(width 0.254)
			(type default)
		)
		(layer "In6.Cu")
	)
	(gr_line
		(start 107.951524 -11.378946)
		(end 106.402124 -11.378946)
		(stroke
			(width 0.254)
			(type default)
		)
		(layer "In6.Cu")
	)
	(gr_line
		(start 107.951524 -9.194546)
		(end 107.951524 -11.378946)
		(stroke
			(width 0.254)
			(type default)
		)
		(layer "In6.Cu")
	)
	(gr_arc
		(start 113.069878 -51.319938)
		(mid 113.362771 -52.027043)
		(end 114.069876 -52.319936)
		(stroke
			(width 1.016)
			(type default)
		)
		(layer "In6.Cu")
	)
	(gr_arc
		(start 113.069878 -50.8)
		(mid 112.776984 -50.092902)
		(end 112.06988 -49.800002)
		(stroke
			(width 1.016)
			(type default)
		)
		(layer "In6.Cu")
	)
	(gr_line
		(start 113.069878 -50.8)
		(end 113.069878 -51.319938)
		(stroke
			(width 1.016)
			(type default)
		)
		(layer "In6.Cu")
	)
	(gr_line
		(start 113.76152 -9.1948)
		(end 115.18392 -9.1948)
		(stroke
			(width 1.016)
			(type default)
		)
		(layer "In6.Cu")
	)
	(gr_line
		(start 114.069876 -52.319936)
		(end 132.990082 -52.319936)
		(stroke
			(width 1.016)
			(type default)
		)
		(layer "In6.Cu")
	)
	(gr_line
		(start 117.856 -13.843)
		(end 118.6942 -13.843)
		(stroke
			(width 0.1016)
			(type default)
		)
		(layer "In6.Cu")
	)
	(gr_line
		(start 117.856 -11.1252)
		(end 117.856 -13.843)
		(stroke
			(width 0.1016)
			(type default)
		)
		(layer "In6.Cu")
	)
	(gr_line
		(start 117.856 -9.64311)
		(end 118.6942 -9.64311)
		(stroke
			(width 0.1016)
			(type default)
		)
		(layer "In6.Cu")
	)
	(gr_line
		(start 117.856 -6.92531)
		(end 117.856 -9.64311)
		(stroke
			(width 0.1016)
			(type default)
		)
		(layer "In6.Cu")
	)
	(gr_line
		(start 117.8814 -13.8176)
		(end 117.8814 -11.1506)
		(stroke
			(width 0.127)
			(type default)
		)
		(layer "In6.Cu")
	)
	(gr_line
		(start 117.8814 -11.1506)
		(end 119.1768 -11.1506)
		(stroke
			(width 0.127)
			(type default)
		)
		(layer "In6.Cu")
	)
	(gr_line
		(start 117.8814 -9.61771)
		(end 117.8814 -6.95071)
		(stroke
			(width 0.127)
			(type default)
		)
		(layer "In6.Cu")
	)
	(gr_line
		(start 117.8814 -6.95071)
		(end 119.1768 -6.95071)
		(stroke
			(width 0.127)
			(type default)
		)
		(layer "In6.Cu")
	)
	(gr_line
		(start 117.9068 -13.8176)
		(end 117.9068 -11.176)
		(stroke
			(width 0.127)
			(type default)
		)
		(layer "In6.Cu")
	)
	(gr_line
		(start 117.9068 -13.7922)
		(end 117.9068 -11.176)
		(stroke
			(width 0.1778)
			(type default)
		)
		(layer "In6.Cu")
	)
	(gr_line
		(start 117.9068 -11.176)
		(end 119.1514 -11.176)
		(stroke
			(width 0.127)
			(type default)
		)
		(layer "In6.Cu")
	)
	(gr_line
		(start 117.9068 -11.176)
		(end 119.1514 -11.176)
		(stroke
			(width 0.1778)
			(type default)
		)
		(layer "In6.Cu")
	)
	(gr_line
		(start 117.9068 -9.61771)
		(end 117.9068 -6.97611)
		(stroke
			(width 0.127)
			(type default)
		)
		(layer "In6.Cu")
	)
	(gr_line
		(start 117.9068 -9.59231)
		(end 117.9068 -6.97611)
		(stroke
			(width 0.1778)
			(type default)
		)
		(layer "In6.Cu")
	)
	(gr_line
		(start 117.9068 -6.97611)
		(end 119.1514 -6.97611)
		(stroke
			(width 0.127)
			(type default)
		)
		(layer "In6.Cu")
	)
	(gr_line
		(start 117.9068 -6.97611)
		(end 119.1514 -6.97611)
		(stroke
			(width 0.1778)
			(type default)
		)
		(layer "In6.Cu")
	)
	(gr_line
		(start 117.9322 -13.7922)
		(end 117.9322 -11.2014)
		(stroke
			(width 0.1778)
			(type default)
		)
		(layer "In6.Cu")
	)
	(gr_line
		(start 117.9322 -11.2014)
		(end 119.126 -11.2014)
		(stroke
			(width 0.1778)
			(type default)
		)
		(layer "In6.Cu")
	)
	(gr_line
		(start 117.9322 -9.59231)
		(end 117.9322 -7.00151)
		(stroke
			(width 0.1778)
			(type default)
		)
		(layer "In6.Cu")
	)
	(gr_line
		(start 117.9322 -7.00151)
		(end 119.126 -7.00151)
		(stroke
			(width 0.1778)
			(type default)
		)
		(layer "In6.Cu")
	)
	(gr_line
		(start 117.9576 -13.7668)
		(end 117.9576 -11.2268)
		(stroke
			(width 0.254)
			(type default)
		)
		(layer "In6.Cu")
	)
	(gr_line
		(start 117.9576 -11.2268)
		(end 119.126 -11.2268)
		(stroke
			(width 0.254)
			(type default)
		)
		(layer "In6.Cu")
	)
	(gr_line
		(start 117.9576 -9.56691)
		(end 117.9576 -7.02691)
		(stroke
			(width 0.254)
			(type default)
		)
		(layer "In6.Cu")
	)
	(gr_line
		(start 117.9576 -7.02691)
		(end 119.126 -7.02691)
		(stroke
			(width 0.254)
			(type default)
		)
		(layer "In6.Cu")
	)
	(gr_line
		(start 117.983 -13.7668)
		(end 117.983 -11.2522)
		(stroke
			(width 0.254)
			(type default)
		)
		(layer "In6.Cu")
	)
	(gr_line
		(start 117.983 -11.2522)
		(end 119.1006 -11.2522)
		(stroke
			(width 0.254)
			(type default)
		)
		(layer "In6.Cu")
	)
	(gr_line
		(start 117.983 -9.56691)
		(end 117.983 -7.05231)
		(stroke
			(width 0.254)
			(type default)
		)
		(layer "In6.Cu")
	)
	(gr_line
		(start 117.983 -7.05231)
		(end 119.1006 -7.05231)
		(stroke
			(width 0.254)
			(type default)
		)
		(layer "In6.Cu")
	)
	(gr_line
		(start 118.0084 -13.716)
		(end 118.0084 -11.2776)
		(stroke
			(width 0.3556)
			(type default)
		)
		(layer "In6.Cu")
	)
	(gr_line
		(start 118.0084 -11.2776)
		(end 119.0498 -11.2776)
		(stroke
			(width 0.3556)
			(type default)
		)
		(layer "In6.Cu")
	)
	(gr_line
		(start 118.0084 -9.51611)
		(end 118.0084 -7.07771)
		(stroke
			(width 0.3556)
			(type default)
		)
		(layer "In6.Cu")
	)
	(gr_line
		(start 118.0084 -7.07771)
		(end 119.0498 -7.07771)
		(stroke
			(width 0.3556)
			(type default)
		)
		(layer "In6.Cu")
	)
	(gr_line
		(start 118.0592 -13.6906)
		(end 118.0592 -11.3284)
		(stroke
			(width 0.381)
			(type default)
		)
		(layer "In6.Cu")
	)
	(gr_line
		(start 118.0592 -11.3284)
		(end 118.999 -11.3284)
		(stroke
			(width 0.381)
			(type default)
		)
		(layer "In6.Cu")
	)
	(gr_line
		(start 118.0592 -9.49071)
		(end 118.0592 -7.12851)
		(stroke
			(width 0.381)
			(type default)
		)
		(layer "In6.Cu")
	)
	(gr_line
		(start 118.0592 -7.12851)
		(end 118.999 -7.12851)
		(stroke
			(width 0.381)
			(type default)
		)
		(layer "In6.Cu")
	)
	(gr_line
		(start 118.1354 -13.6398)
		(end 118.1354 -11.3792)
		(stroke
			(width 0.381)
			(type default)
		)
		(layer "In6.Cu")
	)
	(gr_line
		(start 118.1354 -11.3792)
		(end 118.9482 -11.3792)
		(stroke
			(width 0.381)
			(type default)
		)
		(layer "In6.Cu")
	)
	(gr_line
		(start 118.1354 -9.43991)
		(end 118.1354 -7.17931)
		(stroke
			(width 0.381)
			(type default)
		)
		(layer "In6.Cu")
	)
	(gr_line
		(start 118.1354 -7.17931)
		(end 118.9482 -7.17931)
		(stroke
			(width 0.381)
			(type default)
		)
		(layer "In6.Cu")
	)
	(gr_line
		(start 118.1608 -13.5636)
		(end 118.1608 -11.3792)
		(stroke
			(width 0.508)
			(type default)
		)
		(layer "In6.Cu")
	)
	(gr_line
		(start 118.1608 -11.3792)
		(end 118.9228 -11.3792)
		(stroke
			(width 0.508)
			(type default)
		)
		(layer "In6.Cu")
	)
	(gr_line
		(start 118.1608 -9.36371)
		(end 118.1608 -7.17931)
		(stroke
			(width 0.508)
			(type default)
		)
		(layer "In6.Cu")
	)
	(gr_line
		(start 118.1608 -7.17931)
		(end 118.9228 -7.17931)
		(stroke
			(width 0.508)
			(type default)
		)
		(layer "In6.Cu")
	)
	(gr_line
		(start 118.1862 -13.4112)
		(end 118.7704 -13.4112)
		(stroke
			(width 0.762)
			(type default)
		)
		(layer "In6.Cu")
	)
	(gr_line
		(start 118.1862 -11.5824)
		(end 118.7704 -11.5824)
		(stroke
			(width 0.762)
			(type default)
		)
		(layer "In6.Cu")
	)
	(gr_line
		(start 118.1862 -9.21131)
		(end 118.7704 -9.21131)
		(stroke
			(width 0.762)
			(type default)
		)
		(layer "In6.Cu")
	)
	(gr_line
		(start 118.1862 -7.38251)
		(end 118.7704 -7.38251)
		(stroke
			(width 0.762)
			(type default)
		)
		(layer "In6.Cu")
	)
	(gr_line
		(start 118.2116 -13.5636)
		(end 118.2116 -11.43)
		(stroke
			(width 0.635)
			(type default)
		)
		(layer "In6.Cu")
	)
	(gr_line
		(start 118.2116 -13.5128)
		(end 118.2116 -11.4808)
		(stroke
			(width 0.762)
			(type default)
		)
		(layer "In6.Cu")
	)
	(gr_line
		(start 118.2116 -11.43)
		(end 118.8974 -11.43)
		(stroke
			(width 0.635)
			(type default)
		)
		(layer "In6.Cu")
	)
	(gr_line
		(start 118.2116 -9.36371)
		(end 118.2116 -7.23011)
		(stroke
			(width 0.635)
			(type default)
		)
		(layer "In6.Cu")
	)
	(gr_line
		(start 118.2116 -9.31291)
		(end 118.2116 -7.28091)
		(stroke
			(width 0.762)
			(type default)
		)
		(layer "In6.Cu")
	)
	(gr_line
		(start 118.2116 -7.23011)
		(end 118.8974 -7.23011)
		(stroke
			(width 0.635)
			(type default)
		)
		(layer "In6.Cu")
	)
	(gr_line
		(start 118.237 -13.5128)
		(end 118.237 -11.4808)
		(stroke
			(width 0.762)
			(type default)
		)
		(layer "In6.Cu")
	)
	(gr_line
		(start 118.237 -11.4808)
		(end 118.8212 -11.4808)
		(stroke
			(width 0.762)
			(type default)
		)
		(layer "In6.Cu")
	)
	(gr_line
		(start 118.237 -9.31291)
		(end 118.237 -7.28091)
		(stroke
			(width 0.762)
			(type default)
		)
		(layer "In6.Cu")
	)
	(gr_line
		(start 118.237 -7.28091)
		(end 118.8212 -7.28091)
		(stroke
			(width 0.762)
			(type default)
		)
		(layer "In6.Cu")
	)
	(gr_line
		(start 118.2624 -13.5128)
		(end 118.2624 -11.4808)
		(stroke
			(width 0.762)
			(type default)
		)
		(layer "In6.Cu")
	)
	(gr_line
		(start 118.2624 -13.5128)
		(end 118.8466 -13.5128)
		(stroke
			(width 0.762)
			(type default)
		)
		(layer "In6.Cu")
	)
	(gr_line
		(start 118.2624 -13.4874)
		(end 118.2624 -11.4554)
		(stroke
			(width 0.762)
			(type default)
		)
		(layer "In6.Cu")
	)
	(gr_line
		(start 118.2624 -9.31291)
		(end 118.2624 -7.28091)
		(stroke
			(width 0.762)
			(type default)
		)
		(layer "In6.Cu")
	)
	(gr_line
		(start 118.2624 -9.31291)
		(end 118.8466 -9.31291)
		(stroke
			(width 0.762)
			(type default)
		)
		(layer "In6.Cu")
	)
	(gr_line
		(start 118.2624 -9.28751)
		(end 118.2624 -7.25551)
		(stroke
			(width 0.762)
			(type default)
		)
		(layer "In6.Cu")
	)
	(gr_line
		(start 118.2878 -13.5128)
		(end 118.2878 -11.4808)
		(stroke
			(width 0.762)
			(type default)
		)
		(layer "In6.Cu")
	)
	(gr_line
		(start 118.2878 -9.31291)
		(end 118.2878 -7.28091)
		(stroke
			(width 0.762)
			(type default)
		)
		(layer "In6.Cu")
	)
	(gr_line
		(start 118.3132 -13.5128)
		(end 118.3132 -11.4808)
		(stroke
			(width 0.762)
			(type default)
		)
		(layer "In6.Cu")
	)
	(gr_line
		(start 118.3132 -9.31291)
		(end 118.3132 -7.28091)
		(stroke
			(width 0.762)
			(type default)
		)
		(layer "In6.Cu")
	)
	(gr_line
		(start 118.3386 -13.5128)
		(end 118.3386 -11.4808)
		(stroke
			(width 0.762)
			(type default)
		)
		(layer "In6.Cu")
	)
	(gr_line
		(start 118.3386 -9.31291)
		(end 118.3386 -7.28091)
		(stroke
			(width 0.762)
			(type default)
		)
		(layer "In6.Cu")
	)
	(gr_line
		(start 118.3894 -13.5128)
		(end 118.3894 -11.4808)
		(stroke
			(width 0.762)
			(type default)
		)
		(layer "In6.Cu")
	)
	(gr_line
		(start 118.3894 -9.31291)
		(end 118.3894 -7.28091)
		(stroke
			(width 0.762)
			(type default)
		)
		(layer "In6.Cu")
	)
	(gr_line
		(start 118.4148 -13.5128)
		(end 118.4148 -11.4808)
		(stroke
			(width 0.762)
			(type default)
		)
		(layer "In6.Cu")
	)
	(gr_line
		(start 118.4148 -9.31291)
		(end 118.4148 -7.28091)
		(stroke
			(width 0.762)
			(type default)
		)
		(layer "In6.Cu")
	)
	(gr_line
		(start 118.4402 -13.5128)
		(end 118.4402 -11.7094)
		(stroke
			(width 0.635)
			(type default)
		)
		(layer "In6.Cu")
	)
	(gr_line
		(start 118.4402 -11.7094)
		(end 118.5418 -11.7094)
		(stroke
			(width 0.635)
			(type default)
		)
		(layer "In6.Cu")
	)
	(gr_line
		(start 118.4402 -9.31291)
		(end 118.4402 -7.50951)
		(stroke
			(width 0.635)
			(type default)
		)
		(layer "In6.Cu")
	)
	(gr_line
		(start 118.4402 -7.50951)
		(end 118.5418 -7.50951)
		(stroke
			(width 0.635)
			(type default)
		)
		(layer "In6.Cu")
	)
	(gr_line
		(start 118.4656 -13.5128)
		(end 118.4656 -11.4808)
		(stroke
			(width 0.762)
			(type default)
		)
		(layer "In6.Cu")
	)
	(gr_line
		(start 118.4656 -13.4874)
		(end 118.4656 -11.4554)
		(stroke
			(width 0.762)
			(type default)
		)
		(layer "In6.Cu")
	)
	(gr_line
		(start 118.4656 -13.4366)
		(end 118.4656 -11.6586)
		(stroke
			(width 0.635)
			(type default)
		)
		(layer "In6.Cu")
	)
	(gr_line
		(start 118.4656 -9.31291)
		(end 118.4656 -7.28091)
		(stroke
			(width 0.762)
			(type default)
		)
		(layer "In6.Cu")
	)
	(gr_line
		(start 118.4656 -9.28751)
		(end 118.4656 -7.25551)
		(stroke
			(width 0.762)
			(type default)
		)
		(layer "In6.Cu")
	)
	(gr_line
		(start 118.4656 -9.23671)
		(end 118.4656 -7.45871)
		(stroke
			(width 0.635)
			(type default)
		)
		(layer "In6.Cu")
	)
	(gr_line
		(start 118.5164 -13.5128)
		(end 118.5164 -11.4808)
		(stroke
			(width 0.762)
			(type default)
		)
		(layer "In6.Cu")
	)
	(gr_line
		(start 118.5164 -9.31291)
		(end 118.5164 -7.28091)
		(stroke
			(width 0.762)
			(type default)
		)
		(layer "In6.Cu")
	)
	(gr_line
		(start 118.5418 -13.5128)
		(end 118.5418 -11.4808)
		(stroke
			(width 0.762)
			(type default)
		)
		(layer "In6.Cu")
	)
	(gr_line
		(start 118.5418 -13.4874)
		(end 118.5418 -11.4554)
		(stroke
			(width 0.762)
			(type default)
		)
		(layer "In6.Cu")
	)
	(gr_line
		(start 118.5418 -13.4366)
		(end 118.4656 -13.4366)
		(stroke
			(width 0.635)
			(type default)
		)
		(layer "In6.Cu")
	)
	(gr_line
		(start 118.5418 -11.7094)
		(end 118.5418 -13.4366)
		(stroke
			(width 0.635)
			(type default)
		)
		(layer "In6.Cu")
	)
	(gr_line
		(start 118.5418 -9.31291)
		(end 118.5418 -7.28091)
		(stroke
			(width 0.762)
			(type default)
		)
		(layer "In6.Cu")
	)
	(gr_line
		(start 118.5418 -9.28751)
		(end 118.5418 -7.25551)
		(stroke
			(width 0.762)
			(type default)
		)
		(layer "In6.Cu")
	)
	(gr_line
		(start 118.5418 -9.23671)
		(end 118.4656 -9.23671)
		(stroke
			(width 0.635)
			(type default)
		)
		(layer "In6.Cu")
	)
	(gr_line
		(start 118.5418 -7.50951)
		(end 118.5418 -9.23671)
		(stroke
			(width 0.635)
			(type default)
		)
		(layer "In6.Cu")
	)
	(gr_line
		(start 118.5926 -13.4874)
		(end 118.5926 -11.4554)
		(stroke
			(width 0.762)
			(type default)
		)
		(layer "In6.Cu")
	)
	(gr_line
		(start 118.5926 -9.28751)
		(end 118.5926 -7.25551)
		(stroke
			(width 0.762)
			(type default)
		)
		(layer "In6.Cu")
	)
	(gr_line
		(start 118.618 -13.4874)
		(end 118.618 -11.4554)
		(stroke
			(width 0.762)
			(type default)
		)
		(layer "In6.Cu")
	)
	(gr_line
		(start 118.618 -9.28751)
		(end 118.618 -7.25551)
		(stroke
			(width 0.762)
			(type default)
		)
		(layer "In6.Cu")
	)
	(gr_line
		(start 118.6688 -13.5128)
		(end 118.6688 -11.4808)
		(stroke
			(width 0.762)
			(type default)
		)
		(layer "In6.Cu")
	)
	(gr_line
		(start 118.6688 -9.31291)
		(end 118.6688 -7.28091)
		(stroke
			(width 0.762)
			(type default)
		)
		(layer "In6.Cu")
	)
	(gr_line
		(start 118.6942 -13.843)
		(end 119.2022 -13.843)
		(stroke
			(width 0.1016)
			(type default)
		)
		(layer "In6.Cu")
	)
	(gr_line
		(start 118.6942 -13.4874)
		(end 118.6942 -11.4554)
		(stroke
			(width 0.762)
			(type default)
		)
		(layer "In6.Cu")
	)
	(gr_line
		(start 118.6942 -9.64311)
		(end 119.2022 -9.64311)
		(stroke
			(width 0.1016)
			(type default)
		)
		(layer "In6.Cu")
	)
	(gr_line
		(start 118.6942 -9.28751)
		(end 118.6942 -7.25551)
		(stroke
			(width 0.762)
			(type default)
		)
		(layer "In6.Cu")
	)
	(gr_line
		(start 118.745 -13.5128)
		(end 118.745 -11.4808)
		(stroke
			(width 0.762)
			(type default)
		)
		(layer "In6.Cu")
	)
	(gr_line
		(start 118.745 -13.4874)
		(end 118.745 -11.4554)
		(stroke
			(width 0.762)
			(type default)
		)
		(layer "In6.Cu")
	)
	(gr_line
		(start 118.745 -9.31291)
		(end 118.745 -7.28091)
		(stroke
			(width 0.762)
			(type default)
		)
		(layer "In6.Cu")
	)
	(gr_line
		(start 118.745 -9.28751)
		(end 118.745 -7.25551)
		(stroke
			(width 0.762)
			(type default)
		)
		(layer "In6.Cu")
	)
	(gr_line
		(start 118.7704 -13.4874)
		(end 118.7704 -11.4554)
		(stroke
			(width 0.762)
			(type default)
		)
		(layer "In6.Cu")
	)
	(gr_line
		(start 118.7704 -9.28751)
		(end 118.7704 -7.25551)
		(stroke
			(width 0.762)
			(type default)
		)
		(layer "In6.Cu")
	)
	(gr_line
		(start 118.7958 -13.5636)
		(end 118.1608 -13.5636)
		(stroke
			(width 0.508)
			(type default)
		)
		(layer "In6.Cu")
	)
	(gr_line
		(start 118.7958 -13.5636)
		(end 118.2116 -13.5636)
		(stroke
			(width 0.635)
			(type default)
		)
		(layer "In6.Cu")
	)
	(gr_line
		(start 118.7958 -9.36371)
		(end 118.1608 -9.36371)
		(stroke
			(width 0.508)
			(type default)
		)
		(layer "In6.Cu")
	)
	(gr_line
		(start 118.7958 -9.36371)
		(end 118.2116 -9.36371)
		(stroke
			(width 0.635)
			(type default)
		)
		(layer "In6.Cu")
	)
	(gr_line
		(start 118.8212 -13.4874)
		(end 118.8212 -11.4554)
		(stroke
			(width 0.762)
			(type default)
		)
		(layer "In6.Cu")
	)
	(gr_line
		(start 118.8212 -9.28751)
		(end 118.8212 -7.25551)
		(stroke
			(width 0.762)
			(type default)
		)
		(layer "In6.Cu")
	)
	(gr_line
		(start 118.8466 -13.716)
		(end 118.0084 -13.716)
		(stroke
			(width 0.3556)
			(type default)
		)
		(layer "In6.Cu")
	)
	(gr_line
		(start 118.8466 -13.6906)
		(end 118.0592 -13.6906)
		(stroke
			(width 0.381)
			(type default)
		)
		(layer "In6.Cu")
	)
	(gr_line
		(start 118.8466 -9.51611)
		(end 118.0084 -9.51611)
		(stroke
			(width 0.3556)
			(type default)
		)
		(layer "In6.Cu")
	)
	(gr_line
		(start 118.8466 -9.49071)
		(end 118.0592 -9.49071)
		(stroke
			(width 0.381)
			(type default)
		)
		(layer "In6.Cu")
	)
	(gr_line
		(start 118.872 -13.5128)
		(end 118.872 -11.4808)
		(stroke
			(width 0.762)
			(type default)
		)
		(layer "In6.Cu")
	)
	(gr_line
		(start 118.872 -9.31291)
		(end 118.872 -7.28091)
		(stroke
			(width 0.762)
			(type default)
		)
		(layer "In6.Cu")
	)
	(gr_line
		(start 118.8974 -13.7668)
		(end 117.9576 -13.7668)
		(stroke
			(width 0.254)
			(type default)
		)
		(layer "In6.Cu")
	)
	(gr_line
		(start 118.8974 -13.5128)
		(end 118.4402 -13.5128)
		(stroke
			(width 0.635)
			(type default)
		)
		(layer "In6.Cu")
	)
	(gr_line
		(start 118.8974 -11.43)
		(end 118.8974 -13.5128)
		(stroke
			(width 0.635)
			(type default)
		)
		(layer "In6.Cu")
	)
	(gr_line
		(start 118.8974 -9.56691)
		(end 117.9576 -9.56691)
		(stroke
			(width 0.254)
			(type default)
		)
		(layer "In6.Cu")
	)
	(gr_line
		(start 118.8974 -9.31291)
		(end 118.4402 -9.31291)
		(stroke
			(width 0.635)
			(type default)
		)
		(layer "In6.Cu")
	)
	(gr_line
		(start 118.8974 -7.23011)
		(end 118.8974 -9.31291)
		(stroke
			(width 0.635)
			(type default)
		)
		(layer "In6.Cu")
	)
	(gr_line
		(start 118.9228 -13.7922)
		(end 117.9068 -13.7922)
		(stroke
			(width 0.1778)
			(type default)
		)
		(layer "In6.Cu")
	)
	(gr_line
		(start 118.9228 -13.5636)
		(end 118.7958 -13.5636)
		(stroke
			(width 0.508)
			(type default)
		)
		(layer "In6.Cu")
	)
	(gr_line
		(start 118.9228 -11.3792)
		(end 118.9228 -13.5636)
		(stroke
			(width 0.508)
			(type default)
		)
		(layer "In6.Cu")
	)
	(gr_line
		(start 118.9228 -9.59231)
		(end 117.9068 -9.59231)
		(stroke
			(width 0.1778)
			(type default)
		)
		(layer "In6.Cu")
	)
	(gr_line
		(start 118.9228 -9.36371)
		(end 118.7958 -9.36371)
		(stroke
			(width 0.508)
			(type default)
		)
		(layer "In6.Cu")
	)
	(gr_line
		(start 118.9228 -7.17931)
		(end 118.9228 -9.36371)
		(stroke
			(width 0.508)
			(type default)
		)
		(layer "In6.Cu")
	)
	(gr_line
		(start 118.9482 -13.5636)
		(end 118.7958 -13.5636)
		(stroke
			(width 0.381)
			(type default)
		)
		(layer "In6.Cu")
	)
	(gr_line
		(start 118.9482 -11.3792)
		(end 118.9482 -13.5636)
		(stroke
			(width 0.381)
			(type default)
		)
		(layer "In6.Cu")
	)
	(gr_line
		(start 118.9482 -9.36371)
		(end 118.7958 -9.36371)
		(stroke
			(width 0.381)
			(type default)
		)
		(layer "In6.Cu")
	)
	(gr_line
		(start 118.9482 -7.17931)
		(end 118.9482 -9.36371)
		(stroke
			(width 0.381)
			(type default)
		)
		(layer "In6.Cu")
	)
	(gr_line
		(start 118.999 -13.6398)
		(end 118.1354 -13.6398)
		(stroke
			(width 0.381)
			(type default)
		)
		(layer "In6.Cu")
	)
	(gr_line
		(start 118.999 -11.3284)
		(end 118.999 -13.6398)
		(stroke
			(width 0.381)
			(type default)
		)
		(layer "In6.Cu")
	)
	(gr_line
		(start 118.999 -9.43991)
		(end 118.1354 -9.43991)
		(stroke
			(width 0.381)
			(type default)
		)
		(layer "In6.Cu")
	)
	(gr_line
		(start 118.999 -7.12851)
		(end 118.999 -9.43991)
		(stroke
			(width 0.381)
			(type default)
		)
		(layer "In6.Cu")
	)
	(gr_line
		(start 119.0498 -13.6906)
		(end 118.8466 -13.6906)
		(stroke
			(width 0.3556)
			(type default)
		)
		(layer "In6.Cu")
	)
	(gr_line
		(start 119.0498 -11.2776)
		(end 119.0498 -13.6906)
		(stroke
			(width 0.3556)
			(type default)
		)
		(layer "In6.Cu")
	)
	(gr_line
		(start 119.0498 -9.49071)
		(end 118.8466 -9.49071)
		(stroke
			(width 0.3556)
			(type default)
		)
		(layer "In6.Cu")
	)
	(gr_line
		(start 119.0498 -7.07771)
		(end 119.0498 -9.49071)
		(stroke
			(width 0.3556)
			(type default)
		)
		(layer "In6.Cu")
	)
	(gr_line
		(start 119.0752 -13.8176)
		(end 117.8814 -13.8176)
		(stroke
			(width 0.127)
			(type default)
		)
		(layer "In6.Cu")
	)
	(gr_line
		(start 119.0752 -9.61771)
		(end 117.8814 -9.61771)
		(stroke
			(width 0.127)
			(type default)
		)
		(layer "In6.Cu")
	)
	(gr_line
		(start 119.1006 -13.716)
		(end 118.8466 -13.716)
		(stroke
			(width 0.254)
			(type default)
		)
		(layer "In6.Cu")
	)
	(gr_line
		(start 119.1006 -11.2522)
		(end 119.1006 -13.716)
		(stroke
			(width 0.254)
			(type default)
		)
		(layer "In6.Cu")
	)
	(gr_line
		(start 119.1006 -9.51611)
		(end 118.8466 -9.51611)
		(stroke
			(width 0.254)
			(type default)
		)
		(layer "In6.Cu")
	)
	(gr_line
		(start 119.1006 -7.05231)
		(end 119.1006 -9.51611)
		(stroke
			(width 0.254)
			(type default)
		)
		(layer "In6.Cu")
	)
	(gr_line
		(start 119.126 -13.7668)
		(end 117.983 -13.7668)
		(stroke
			(width 0.254)
			(type default)
		)
		(layer "In6.Cu")
	)
	(gr_line
		(start 119.126 -13.7668)
		(end 118.8974 -13.7668)
		(stroke
			(width 0.1778)
			(type default)
		)
		(layer "In6.Cu")
	)
	(gr_line
		(start 119.126 -11.2268)
		(end 119.126 -13.7668)
		(stroke
			(width 0.254)
			(type default)
		)
		(layer "In6.Cu")
	)
	(gr_line
		(start 119.126 -11.2014)
		(end 119.126 -13.7668)
		(stroke
			(width 0.1778)
			(type default)
		)
		(layer "In6.Cu")
	)
	(gr_line
		(start 119.126 -9.56691)
		(end 117.983 -9.56691)
		(stroke
			(width 0.254)
			(type default)
		)
		(layer "In6.Cu")
	)
	(gr_line
		(start 119.126 -9.56691)
		(end 118.8974 -9.56691)
		(stroke
			(width 0.1778)
			(type default)
		)
		(layer "In6.Cu")
	)
	(gr_line
		(start 119.126 -7.02691)
		(end 119.126 -9.56691)
		(stroke
			(width 0.254)
			(type default)
		)
		(layer "In6.Cu")
	)
	(gr_line
		(start 119.126 -7.00151)
		(end 119.126 -9.56691)
		(stroke
			(width 0.1778)
			(type default)
		)
		(layer "In6.Cu")
	)
	(gr_line
		(start 119.1514 -13.7922)
		(end 117.9322 -13.7922)
		(stroke
			(width 0.1778)
			(type default)
		)
		(layer "In6.Cu")
	)
	(gr_line
		(start 119.1514 -13.7922)
		(end 118.9228 -13.7922)
		(stroke
			(width 0.127)
			(type default)
		)
		(layer "In6.Cu")
	)
	(gr_line
		(start 119.1514 -11.176)
		(end 119.1514 -13.7922)
		(stroke
			(width 0.127)
			(type default)
		)
		(layer "In6.Cu")
	)
	(gr_line
		(start 119.1514 -11.176)
		(end 119.1514 -13.7922)
		(stroke
			(width 0.1778)
			(type default)
		)
		(layer "In6.Cu")
	)
	(gr_line
		(start 119.1514 -9.59231)
		(end 117.9322 -9.59231)
		(stroke
			(width 0.1778)
			(type default)
		)
		(layer "In6.Cu")
	)
	(gr_line
		(start 119.1514 -9.59231)
		(end 118.9228 -9.59231)
		(stroke
			(width 0.127)
			(type default)
		)
		(layer "In6.Cu")
	)
	(gr_line
		(start 119.1514 -6.97611)
		(end 119.1514 -9.59231)
		(stroke
			(width 0.127)
			(type default)
		)
		(layer "In6.Cu")
	)
	(gr_line
		(start 119.1514 -6.97611)
		(end 119.1514 -9.59231)
		(stroke
			(width 0.1778)
			(type default)
		)
		(layer "In6.Cu")
	)
	(gr_line
		(start 119.1768 -13.8176)
		(end 117.9068 -13.8176)
		(stroke
			(width 0.127)
			(type default)
		)
		(layer "In6.Cu")
	)
	(gr_line
		(start 119.1768 -11.1506)
		(end 119.1768 -13.8176)
		(stroke
			(width 0.127)
			(type default)
		)
		(layer "In6.Cu")
	)
	(gr_line
		(start 119.1768 -9.61771)
		(end 117.9068 -9.61771)
		(stroke
			(width 0.127)
			(type default)
		)
		(layer "In6.Cu")
	)
	(gr_line
		(start 119.1768 -6.95071)
		(end 119.1768 -9.61771)
		(stroke
			(width 0.127)
			(type default)
		)
		(layer "In6.Cu")
	)
	(gr_line
		(start 119.2022 -13.843)
		(end 119.2022 -11.1252)
		(stroke
			(width 0.1016)
			(type default)
		)
		(layer "In6.Cu")
	)
	(gr_line
		(start 119.2022 -11.1252)
		(end 117.856 -11.1252)
		(stroke
			(width 0.1016)
			(type default)
		)
		(layer "In6.Cu")
	)
	(gr_line
		(start 119.2022 -9.64311)
		(end 119.2022 -6.92531)
		(stroke
			(width 0.1016)
			(type default)
		)
		(layer "In6.Cu")
	)
	(gr_line
		(start 119.2022 -6.92531)
		(end 117.856 -6.92531)
		(stroke
			(width 0.1016)
			(type default)
		)
		(layer "In6.Cu")
	)
	(gr_line
		(start 127.85598 -12.543028)
		(end 128.69418 -12.543028)
		(stroke
			(width 0.1016)
			(type default)
		)
		(layer "In6.Cu")
	)
	(gr_line
		(start 127.85598 -9.825228)
		(end 127.85598 -12.543028)
		(stroke
			(width 0.1016)
			(type default)
		)
		(layer "In6.Cu")
	)
	(gr_line
		(start 127.85598 -8.343138)
		(end 128.69418 -8.343138)
		(stroke
			(width 0.1016)
			(type default)
		)
		(layer "In6.Cu")
	)
	(gr_line
		(start 127.85598 -5.625338)
		(end 127.85598 -8.343138)
		(stroke
			(width 0.1016)
			(type default)
		)
		(layer "In6.Cu")
	)
	(gr_line
		(start 127.88138 -12.517628)
		(end 127.88138 -9.850628)
		(stroke
			(width 0.127)
			(type default)
		)
		(layer "In6.Cu")
	)
	(gr_line
		(start 127.88138 -9.850628)
		(end 129.17678 -9.850628)
		(stroke
			(width 0.127)
			(type default)
		)
		(layer "In6.Cu")
	)
	(gr_line
		(start 127.88138 -8.317738)
		(end 127.88138 -5.650738)
		(stroke
			(width 0.127)
			(type default)
		)
		(layer "In6.Cu")
	)
	(gr_line
		(start 127.88138 -5.650738)
		(end 129.17678 -5.650738)
		(stroke
			(width 0.127)
			(type default)
		)
		(layer "In6.Cu")
	)
	(gr_line
		(start 127.90678 -12.517628)
		(end 127.90678 -9.876028)
		(stroke
			(width 0.127)
			(type default)
		)
		(layer "In6.Cu")
	)
	(gr_line
		(start 127.90678 -12.492228)
		(end 127.90678 -9.876028)
		(stroke
			(width 0.1778)
			(type default)
		)
		(layer "In6.Cu")
	)
	(gr_line
		(start 127.90678 -9.876028)
		(end 129.15138 -9.876028)
		(stroke
			(width 0.127)
			(type default)
		)
		(layer "In6.Cu")
	)
	(gr_line
		(start 127.90678 -9.876028)
		(end 129.15138 -9.876028)
		(stroke
			(width 0.1778)
			(type default)
		)
		(layer "In6.Cu")
	)
	(gr_line
		(start 127.90678 -8.317738)
		(end 127.90678 -5.676138)
		(stroke
			(width 0.127)
			(type default)
		)
		(layer "In6.Cu")
	)
	(gr_line
		(start 127.90678 -8.292338)
		(end 127.90678 -5.676138)
		(stroke
			(width 0.1778)
			(type default)
		)
		(layer "In6.Cu")
	)
	(gr_line
		(start 127.90678 -5.676138)
		(end 129.15138 -5.676138)
		(stroke
			(width 0.127)
			(type default)
		)
		(layer "In6.Cu")
	)
	(gr_line
		(start 127.90678 -5.676138)
		(end 129.15138 -5.676138)
		(stroke
			(width 0.1778)
			(type default)
		)
		(layer "In6.Cu")
	)
	(gr_line
		(start 127.93218 -12.492228)
		(end 127.93218 -9.901428)
		(stroke
			(width 0.1778)
			(type default)
		)
		(layer "In6.Cu")
	)
	(gr_line
		(start 127.93218 -9.901428)
		(end 129.12598 -9.901428)
		(stroke
			(width 0.1778)
			(type default)
		)
		(layer "In6.Cu")
	)
	(gr_line
		(start 127.93218 -8.292338)
		(end 127.93218 -5.701538)
		(stroke
			(width 0.1778)
			(type default)
		)
		(layer "In6.Cu")
	)
	(gr_line
		(start 127.93218 -5.701538)
		(end 129.12598 -5.701538)
		(stroke
			(width 0.1778)
			(type default)
		)
		(layer "In6.Cu")
	)
	(gr_line
		(start 127.95758 -12.466828)
		(end 127.95758 -9.926828)
		(stroke
			(width 0.254)
			(type default)
		)
		(layer "In6.Cu")
	)
	(gr_line
		(start 127.95758 -9.926828)
		(end 129.12598 -9.926828)
		(stroke
			(width 0.254)
			(type default)
		)
		(layer "In6.Cu")
	)
	(gr_line
		(start 127.95758 -8.266938)
		(end 127.95758 -5.726938)
		(stroke
			(width 0.254)
			(type default)
		)
		(layer "In6.Cu")
	)
	(gr_line
		(start 127.95758 -5.726938)
		(end 129.12598 -5.726938)
		(stroke
			(width 0.254)
			(type default)
		)
		(layer "In6.Cu")
	)
	(gr_line
		(start 127.98298 -12.466828)
		(end 127.98298 -9.952228)
		(stroke
			(width 0.254)
			(type default)
		)
		(layer "In6.Cu")
	)
	(gr_line
		(start 127.98298 -9.952228)
		(end 129.10058 -9.952228)
		(stroke
			(width 0.254)
			(type default)
		)
		(layer "In6.Cu")
	)
	(gr_line
		(start 127.98298 -8.266938)
		(end 127.98298 -5.752338)
		(stroke
			(width 0.254)
			(type default)
		)
		(layer "In6.Cu")
	)
	(gr_line
		(start 127.98298 -5.752338)
		(end 129.10058 -5.752338)
		(stroke
			(width 0.254)
			(type default)
		)
		(layer "In6.Cu")
	)
	(gr_line
		(start 128.00838 -12.416028)
		(end 128.00838 -9.977628)
		(stroke
			(width 0.3556)
			(type default)
		)
		(layer "In6.Cu")
	)
	(gr_line
		(start 128.00838 -9.977628)
		(end 129.04978 -9.977628)
		(stroke
			(width 0.3556)
			(type default)
		)
		(layer "In6.Cu")
	)
	(gr_line
		(start 128.00838 -8.216138)
		(end 128.00838 -5.777738)
		(stroke
			(width 0.3556)
			(type default)
		)
		(layer "In6.Cu")
	)
	(gr_line
		(start 128.00838 -5.777738)
		(end 129.04978 -5.777738)
		(stroke
			(width 0.3556)
			(type default)
		)
		(layer "In6.Cu")
	)
	(gr_line
		(start 128.05918 -12.390628)
		(end 128.05918 -10.028428)
		(stroke
			(width 0.381)
			(type default)
		)
		(layer "In6.Cu")
	)
	(gr_line
		(start 128.05918 -10.028428)
		(end 128.99898 -10.028428)
		(stroke
			(width 0.381)
			(type default)
		)
		(layer "In6.Cu")
	)
	(gr_line
		(start 128.05918 -8.190738)
		(end 128.05918 -5.828538)
		(stroke
			(width 0.381)
			(type default)
		)
		(layer "In6.Cu")
	)
	(gr_line
		(start 128.05918 -5.828538)
		(end 128.99898 -5.828538)
		(stroke
			(width 0.381)
			(type default)
		)
		(layer "In6.Cu")
	)
	(gr_line
		(start 128.13538 -12.339828)
		(end 128.13538 -10.079228)
		(stroke
			(width 0.381)
			(type default)
		)
		(layer "In6.Cu")
	)
	(gr_line
		(start 128.13538 -10.079228)
		(end 128.94818 -10.079228)
		(stroke
			(width 0.381)
			(type default)
		)
		(layer "In6.Cu")
	)
	(gr_line
		(start 128.13538 -8.139938)
		(end 128.13538 -5.879338)
		(stroke
			(width 0.381)
			(type default)
		)
		(layer "In6.Cu")
	)
	(gr_line
		(start 128.13538 -5.879338)
		(end 128.94818 -5.879338)
		(stroke
			(width 0.381)
			(type default)
		)
		(layer "In6.Cu")
	)
	(gr_line
		(start 128.16078 -12.263628)
		(end 128.16078 -10.079228)
		(stroke
			(width 0.508)
			(type default)
		)
		(layer "In6.Cu")
	)
	(gr_line
		(start 128.16078 -10.079228)
		(end 128.92278 -10.079228)
		(stroke
			(width 0.508)
			(type default)
		)
		(layer "In6.Cu")
	)
	(gr_line
		(start 128.16078 -8.063738)
		(end 128.16078 -5.879338)
		(stroke
			(width 0.508)
			(type default)
		)
		(layer "In6.Cu")
	)
	(gr_line
		(start 128.16078 -5.879338)
		(end 128.92278 -5.879338)
		(stroke
			(width 0.508)
			(type default)
		)
		(layer "In6.Cu")
	)
	(gr_line
		(start 128.18618 -12.111228)
		(end 128.77038 -12.111228)
		(stroke
			(width 0.762)
			(type default)
		)
		(layer "In6.Cu")
	)
	(gr_line
		(start 128.18618 -10.282428)
		(end 128.77038 -10.282428)
		(stroke
			(width 0.762)
			(type default)
		)
		(layer "In6.Cu")
	)
	(gr_line
		(start 128.18618 -7.911338)
		(end 128.77038 -7.911338)
		(stroke
			(width 0.762)
			(type default)
		)
		(layer "In6.Cu")
	)
	(gr_line
		(start 128.18618 -6.082538)
		(end 128.77038 -6.082538)
		(stroke
			(width 0.762)
			(type default)
		)
		(layer "In6.Cu")
	)
	(gr_line
		(start 128.21158 -12.263628)
		(end 128.21158 -10.130028)
		(stroke
			(width 0.635)
			(type default)
		)
		(layer "In6.Cu")
	)
	(gr_line
		(start 128.21158 -12.212828)
		(end 128.21158 -10.180828)
		(stroke
			(width 0.762)
			(type default)
		)
		(layer "In6.Cu")
	)
	(gr_line
		(start 128.21158 -10.130028)
		(end 128.89738 -10.130028)
		(stroke
			(width 0.635)
			(type default)
		)
		(layer "In6.Cu")
	)
	(gr_line
		(start 128.21158 -8.063738)
		(end 128.21158 -5.930138)
		(stroke
			(width 0.635)
			(type default)
		)
		(layer "In6.Cu")
	)
	(gr_line
		(start 128.21158 -8.012938)
		(end 128.21158 -5.980938)
		(stroke
			(width 0.762)
			(type default)
		)
		(layer "In6.Cu")
	)
	(gr_line
		(start 128.21158 -5.930138)
		(end 128.89738 -5.930138)
		(stroke
			(width 0.635)
			(type default)
		)
		(layer "In6.Cu")
	)
	(gr_line
		(start 128.23698 -12.212828)
		(end 128.23698 -10.180828)
		(stroke
			(width 0.762)
			(type default)
		)
		(layer "In6.Cu")
	)
	(gr_line
		(start 128.23698 -10.180828)
		(end 128.82118 -10.180828)
		(stroke
			(width 0.762)
			(type default)
		)
		(layer "In6.Cu")
	)
	(gr_line
		(start 128.23698 -8.012938)
		(end 128.23698 -5.980938)
		(stroke
			(width 0.762)
			(type default)
		)
		(layer "In6.Cu")
	)
	(gr_line
		(start 128.23698 -5.980938)
		(end 128.82118 -5.980938)
		(stroke
			(width 0.762)
			(type default)
		)
		(layer "In6.Cu")
	)
	(gr_line
		(start 128.26238 -12.212828)
		(end 128.26238 -10.180828)
		(stroke
			(width 0.762)
			(type default)
		)
		(layer "In6.Cu")
	)
	(gr_line
		(start 128.26238 -12.212828)
		(end 128.84658 -12.212828)
		(stroke
			(width 0.762)
			(type default)
		)
		(layer "In6.Cu")
	)
	(gr_line
		(start 128.26238 -12.187428)
		(end 128.26238 -10.155428)
		(stroke
			(width 0.762)
			(type default)
		)
		(layer "In6.Cu")
	)
	(gr_line
		(start 128.26238 -8.012938)
		(end 128.26238 -5.980938)
		(stroke
			(width 0.762)
			(type default)
		)
		(layer "In6.Cu")
	)
	(gr_line
		(start 128.26238 -8.012938)
		(end 128.84658 -8.012938)
		(stroke
			(width 0.762)
			(type default)
		)
		(layer "In6.Cu")
	)
	(gr_line
		(start 128.26238 -7.987538)
		(end 128.26238 -5.955538)
		(stroke
			(width 0.762)
			(type default)
		)
		(layer "In6.Cu")
	)
	(gr_line
		(start 128.28778 -12.212828)
		(end 128.28778 -10.180828)
		(stroke
			(width 0.762)
			(type default)
		)
		(layer "In6.Cu")
	)
	(gr_line
		(start 128.28778 -8.012938)
		(end 128.28778 -5.980938)
		(stroke
			(width 0.762)
			(type default)
		)
		(layer "In6.Cu")
	)
	(gr_line
		(start 128.31318 -12.212828)
		(end 128.31318 -10.180828)
		(stroke
			(width 0.762)
			(type default)
		)
		(layer "In6.Cu")
	)
	(gr_line
		(start 128.31318 -8.012938)
		(end 128.31318 -5.980938)
		(stroke
			(width 0.762)
			(type default)
		)
		(layer "In6.Cu")
	)
	(gr_line
		(start 128.33858 -12.212828)
		(end 128.33858 -10.180828)
		(stroke
			(width 0.762)
			(type default)
		)
		(layer "In6.Cu")
	)
	(gr_line
		(start 128.33858 -8.012938)
		(end 128.33858 -5.980938)
		(stroke
			(width 0.762)
			(type default)
		)
		(layer "In6.Cu")
	)
	(gr_line
		(start 128.38938 -12.212828)
		(end 128.38938 -10.180828)
		(stroke
			(width 0.762)
			(type default)
		)
		(layer "In6.Cu")
	)
	(gr_line
		(start 128.38938 -8.012938)
		(end 128.38938 -5.980938)
		(stroke
			(width 0.762)
			(type default)
		)
		(layer "In6.Cu")
	)
	(gr_line
		(start 128.41478 -12.212828)
		(end 128.41478 -10.180828)
		(stroke
			(width 0.762)
			(type default)
		)
		(layer "In6.Cu")
	)
	(gr_line
		(start 128.41478 -8.012938)
		(end 128.41478 -5.980938)
		(stroke
			(width 0.762)
			(type default)
		)
		(layer "In6.Cu")
	)
	(gr_line
		(start 128.44018 -12.212828)
		(end 128.44018 -10.409428)
		(stroke
			(width 0.635)
			(type default)
		)
		(layer "In6.Cu")
	)
	(gr_line
		(start 128.44018 -10.409428)
		(end 128.54178 -10.409428)
		(stroke
			(width 0.635)
			(type default)
		)
		(layer "In6.Cu")
	)
	(gr_line
		(start 128.44018 -8.012938)
		(end 128.44018 -6.209538)
		(stroke
			(width 0.635)
			(type default)
		)
		(layer "In6.Cu")
	)
	(gr_line
		(start 128.44018 -6.209538)
		(end 128.54178 -6.209538)
		(stroke
			(width 0.635)
			(type default)
		)
		(layer "In6.Cu")
	)
	(gr_line
		(start 128.46558 -12.212828)
		(end 128.46558 -10.180828)
		(stroke
			(width 0.762)
			(type default)
		)
		(layer "In6.Cu")
	)
	(gr_line
		(start 128.46558 -12.187428)
		(end 128.46558 -10.155428)
		(stroke
			(width 0.762)
			(type default)
		)
		(layer "In6.Cu")
	)
	(gr_line
		(start 128.46558 -12.136628)
		(end 128.46558 -10.358628)
		(stroke
			(width 0.635)
			(type default)
		)
		(layer "In6.Cu")
	)
	(gr_line
		(start 128.46558 -8.012938)
		(end 128.46558 -5.980938)
		(stroke
			(width 0.762)
			(type default)
		)
		(layer "In6.Cu")
	)
	(gr_line
		(start 128.46558 -7.987538)
		(end 128.46558 -5.955538)
		(stroke
			(width 0.762)
			(type default)
		)
		(layer "In6.Cu")
	)
	(gr_line
		(start 128.46558 -7.936738)
		(end 128.46558 -6.158738)
		(stroke
			(width 0.635)
			(type default)
		)
		(layer "In6.Cu")
	)
	(gr_line
		(start 128.51638 -12.212828)
		(end 128.51638 -10.180828)
		(stroke
			(width 0.762)
			(type default)
		)
		(layer "In6.Cu")
	)
	(gr_line
		(start 128.51638 -8.012938)
		(end 128.51638 -5.980938)
		(stroke
			(width 0.762)
			(type default)
		)
		(layer "In6.Cu")
	)
	(gr_line
		(start 128.54178 -12.212828)
		(end 128.54178 -10.180828)
		(stroke
			(width 0.762)
			(type default)
		)
		(layer "In6.Cu")
	)
	(gr_line
		(start 128.54178 -12.187428)
		(end 128.54178 -10.155428)
		(stroke
			(width 0.762)
			(type default)
		)
		(layer "In6.Cu")
	)
	(gr_line
		(start 128.54178 -12.136628)
		(end 128.46558 -12.136628)
		(stroke
			(width 0.635)
			(type default)
		)
		(layer "In6.Cu")
	)
	(gr_line
		(start 128.54178 -10.409428)
		(end 128.54178 -12.136628)
		(stroke
			(width 0.635)
			(type default)
		)
		(layer "In6.Cu")
	)
	(gr_line
		(start 128.54178 -8.012938)
		(end 128.54178 -5.980938)
		(stroke
			(width 0.762)
			(type default)
		)
		(layer "In6.Cu")
	)
	(gr_line
		(start 128.54178 -7.987538)
		(end 128.54178 -5.955538)
		(stroke
			(width 0.762)
			(type default)
		)
		(layer "In6.Cu")
	)
	(gr_line
		(start 128.54178 -7.936738)
		(end 128.46558 -7.936738)
		(stroke
			(width 0.635)
			(type default)
		)
		(layer "In6.Cu")
	)
	(gr_line
		(start 128.54178 -6.209538)
		(end 128.54178 -7.936738)
		(stroke
			(width 0.635)
			(type default)
		)
		(layer "In6.Cu")
	)
	(gr_line
		(start 128.59258 -12.187428)
		(end 128.59258 -10.155428)
		(stroke
			(width 0.762)
			(type default)
		)
		(layer "In6.Cu")
	)
	(gr_line
		(start 128.59258 -7.987538)
		(end 128.59258 -5.955538)
		(stroke
			(width 0.762)
			(type default)
		)
		(layer "In6.Cu")
	)
	(gr_line
		(start 128.61798 -12.187428)
		(end 128.61798 -10.155428)
		(stroke
			(width 0.762)
			(type default)
		)
		(layer "In6.Cu")
	)
	(gr_line
		(start 128.61798 -7.987538)
		(end 128.61798 -5.955538)
		(stroke
			(width 0.762)
			(type default)
		)
		(layer "In6.Cu")
	)
	(gr_line
		(start 128.66878 -12.212828)
		(end 128.66878 -10.180828)
		(stroke
			(width 0.762)
			(type default)
		)
		(layer "In6.Cu")
	)
	(gr_line
		(start 128.66878 -8.012938)
		(end 128.66878 -5.980938)
		(stroke
			(width 0.762)
			(type default)
		)
		(layer "In6.Cu")
	)
	(gr_line
		(start 128.69418 -12.543028)
		(end 129.20218 -12.543028)
		(stroke
			(width 0.1016)
			(type default)
		)
		(layer "In6.Cu")
	)
	(gr_line
		(start 128.69418 -12.187428)
		(end 128.69418 -10.155428)
		(stroke
			(width 0.762)
			(type default)
		)
		(layer "In6.Cu")
	)
	(gr_line
		(start 128.69418 -8.343138)
		(end 129.20218 -8.343138)
		(stroke
			(width 0.1016)
			(type default)
		)
		(layer "In6.Cu")
	)
	(gr_line
		(start 128.69418 -7.987538)
		(end 128.69418 -5.955538)
		(stroke
			(width 0.762)
			(type default)
		)
		(layer "In6.Cu")
	)
	(gr_line
		(start 128.74498 -12.212828)
		(end 128.74498 -10.180828)
		(stroke
			(width 0.762)
			(type default)
		)
		(layer "In6.Cu")
	)
	(gr_line
		(start 128.74498 -12.187428)
		(end 128.74498 -10.155428)
		(stroke
			(width 0.762)
			(type default)
		)
		(layer "In6.Cu")
	)
	(gr_line
		(start 128.74498 -8.012938)
		(end 128.74498 -5.980938)
		(stroke
			(width 0.762)
			(type default)
		)
		(layer "In6.Cu")
	)
	(gr_line
		(start 128.74498 -7.987538)
		(end 128.74498 -5.955538)
		(stroke
			(width 0.762)
			(type default)
		)
		(layer "In6.Cu")
	)
	(gr_line
		(start 128.77038 -12.187428)
		(end 128.77038 -10.155428)
		(stroke
			(width 0.762)
			(type default)
		)
		(layer "In6.Cu")
	)
	(gr_line
		(start 128.77038 -7.987538)
		(end 128.77038 -5.955538)
		(stroke
			(width 0.762)
			(type default)
		)
		(layer "In6.Cu")
	)
	(gr_line
		(start 128.79578 -12.263628)
		(end 128.16078 -12.263628)
		(stroke
			(width 0.508)
			(type default)
		)
		(layer "In6.Cu")
	)
	(gr_line
		(start 128.79578 -12.263628)
		(end 128.21158 -12.263628)
		(stroke
			(width 0.635)
			(type default)
		)
		(layer "In6.Cu")
	)
	(gr_line
		(start 128.79578 -8.063738)
		(end 128.16078 -8.063738)
		(stroke
			(width 0.508)
			(type default)
		)
		(layer "In6.Cu")
	)
	(gr_line
		(start 128.79578 -8.063738)
		(end 128.21158 -8.063738)
		(stroke
			(width 0.635)
			(type default)
		)
		(layer "In6.Cu")
	)
	(gr_line
		(start 128.82118 -12.187428)
		(end 128.82118 -10.155428)
		(stroke
			(width 0.762)
			(type default)
		)
		(layer "In6.Cu")
	)
	(gr_line
		(start 128.82118 -7.987538)
		(end 128.82118 -5.955538)
		(stroke
			(width 0.762)
			(type default)
		)
		(layer "In6.Cu")
	)
	(gr_line
		(start 128.84658 -12.416028)
		(end 128.00838 -12.416028)
		(stroke
			(width 0.3556)
			(type default)
		)
		(layer "In6.Cu")
	)
	(gr_line
		(start 128.84658 -12.390628)
		(end 128.05918 -12.390628)
		(stroke
			(width 0.381)
			(type default)
		)
		(layer "In6.Cu")
	)
	(gr_line
		(start 128.84658 -8.216138)
		(end 128.00838 -8.216138)
		(stroke
			(width 0.3556)
			(type default)
		)
		(layer "In6.Cu")
	)
	(gr_line
		(start 128.84658 -8.190738)
		(end 128.05918 -8.190738)
		(stroke
			(width 0.381)
			(type default)
		)
		(layer "In6.Cu")
	)
	(gr_line
		(start 128.87198 -12.212828)
		(end 128.87198 -10.180828)
		(stroke
			(width 0.762)
			(type default)
		)
		(layer "In6.Cu")
	)
	(gr_line
		(start 128.87198 -8.012938)
		(end 128.87198 -5.980938)
		(stroke
			(width 0.762)
			(type default)
		)
		(layer "In6.Cu")
	)
	(gr_line
		(start 128.89738 -12.466828)
		(end 127.95758 -12.466828)
		(stroke
			(width 0.254)
			(type default)
		)
		(layer "In6.Cu")
	)
	(gr_line
		(start 128.89738 -12.212828)
		(end 128.44018 -12.212828)
		(stroke
			(width 0.635)
			(type default)
		)
		(layer "In6.Cu")
	)
	(gr_line
		(start 128.89738 -10.130028)
		(end 128.89738 -12.212828)
		(stroke
			(width 0.635)
			(type default)
		)
		(layer "In6.Cu")
	)
	(gr_line
		(start 128.89738 -8.266938)
		(end 127.95758 -8.266938)
		(stroke
			(width 0.254)
			(type default)
		)
		(layer "In6.Cu")
	)
	(gr_line
		(start 128.89738 -8.012938)
		(end 128.44018 -8.012938)
		(stroke
			(width 0.635)
			(type default)
		)
		(layer "In6.Cu")
	)
	(gr_line
		(start 128.89738 -5.930138)
		(end 128.89738 -8.012938)
		(stroke
			(width 0.635)
			(type default)
		)
		(layer "In6.Cu")
	)
	(gr_line
		(start 128.92278 -12.492228)
		(end 127.90678 -12.492228)
		(stroke
			(width 0.1778)
			(type default)
		)
		(layer "In6.Cu")
	)
	(gr_line
		(start 128.92278 -12.263628)
		(end 128.79578 -12.263628)
		(stroke
			(width 0.508)
			(type default)
		)
		(layer "In6.Cu")
	)
	(gr_line
		(start 128.92278 -10.079228)
		(end 128.92278 -12.263628)
		(stroke
			(width 0.508)
			(type default)
		)
		(layer "In6.Cu")
	)
	(gr_line
		(start 128.92278 -8.292338)
		(end 127.90678 -8.292338)
		(stroke
			(width 0.1778)
			(type default)
		)
		(layer "In6.Cu")
	)
	(gr_line
		(start 128.92278 -8.063738)
		(end 128.79578 -8.063738)
		(stroke
			(width 0.508)
			(type default)
		)
		(layer "In6.Cu")
	)
	(gr_line
		(start 128.92278 -5.879338)
		(end 128.92278 -8.063738)
		(stroke
			(width 0.508)
			(type default)
		)
		(layer "In6.Cu")
	)
	(gr_line
		(start 128.94818 -12.263628)
		(end 128.79578 -12.263628)
		(stroke
			(width 0.381)
			(type default)
		)
		(layer "In6.Cu")
	)
	(gr_line
		(start 128.94818 -10.079228)
		(end 128.94818 -12.263628)
		(stroke
			(width 0.381)
			(type default)
		)
		(layer "In6.Cu")
	)
	(gr_line
		(start 128.94818 -8.063738)
		(end 128.79578 -8.063738)
		(stroke
			(width 0.381)
			(type default)
		)
		(layer "In6.Cu")
	)
	(gr_line
		(start 128.94818 -5.879338)
		(end 128.94818 -8.063738)
		(stroke
			(width 0.381)
			(type default)
		)
		(layer "In6.Cu")
	)
	(gr_line
		(start 128.99898 -12.339828)
		(end 128.13538 -12.339828)
		(stroke
			(width 0.381)
			(type default)
		)
		(layer "In6.Cu")
	)
	(gr_line
		(start 128.99898 -10.028428)
		(end 128.99898 -12.339828)
		(stroke
			(width 0.381)
			(type default)
		)
		(layer "In6.Cu")
	)
	(gr_line
		(start 128.99898 -8.139938)
		(end 128.13538 -8.139938)
		(stroke
			(width 0.381)
			(type default)
		)
		(layer "In6.Cu")
	)
	(gr_line
		(start 128.99898 -5.828538)
		(end 128.99898 -8.139938)
		(stroke
			(width 0.381)
			(type default)
		)
		(layer "In6.Cu")
	)
	(gr_line
		(start 129.04978 -12.390628)
		(end 128.84658 -12.390628)
		(stroke
			(width 0.3556)
			(type default)
		)
		(layer "In6.Cu")
	)
	(gr_line
		(start 129.04978 -9.977628)
		(end 129.04978 -12.390628)
		(stroke
			(width 0.3556)
			(type default)
		)
		(layer "In6.Cu")
	)
	(gr_line
		(start 129.04978 -8.190738)
		(end 128.84658 -8.190738)
		(stroke
			(width 0.3556)
			(type default)
		)
		(layer "In6.Cu")
	)
	(gr_line
		(start 129.04978 -5.777738)
		(end 129.04978 -8.190738)
		(stroke
			(width 0.3556)
			(type default)
		)
		(layer "In6.Cu")
	)
	(gr_line
		(start 129.07518 -12.517628)
		(end 127.88138 -12.517628)
		(stroke
			(width 0.127)
			(type default)
		)
		(layer "In6.Cu")
	)
	(gr_line
		(start 129.07518 -8.317738)
		(end 127.88138 -8.317738)
		(stroke
			(width 0.127)
			(type default)
		)
		(layer "In6.Cu")
	)
	(gr_line
		(start 129.10058 -12.416028)
		(end 128.84658 -12.416028)
		(stroke
			(width 0.254)
			(type default)
		)
		(layer "In6.Cu")
	)
	(gr_line
		(start 129.10058 -9.952228)
		(end 129.10058 -12.416028)
		(stroke
			(width 0.254)
			(type default)
		)
		(layer "In6.Cu")
	)
	(gr_line
		(start 129.10058 -8.216138)
		(end 128.84658 -8.216138)
		(stroke
			(width 0.254)
			(type default)
		)
		(layer "In6.Cu")
	)
	(gr_line
		(start 129.10058 -5.752338)
		(end 129.10058 -8.216138)
		(stroke
			(width 0.254)
			(type default)
		)
		(layer "In6.Cu")
	)
	(gr_line
		(start 129.12598 -12.466828)
		(end 127.98298 -12.466828)
		(stroke
			(width 0.254)
			(type default)
		)
		(layer "In6.Cu")
	)
	(gr_line
		(start 129.12598 -12.466828)
		(end 128.89738 -12.466828)
		(stroke
			(width 0.1778)
			(type default)
		)
		(layer "In6.Cu")
	)
	(gr_line
		(start 129.12598 -9.926828)
		(end 129.12598 -12.466828)
		(stroke
			(width 0.254)
			(type default)
		)
		(layer "In6.Cu")
	)
	(gr_line
		(start 129.12598 -9.901428)
		(end 129.12598 -12.466828)
		(stroke
			(width 0.1778)
			(type default)
		)
		(layer "In6.Cu")
	)
	(gr_line
		(start 129.12598 -8.266938)
		(end 127.98298 -8.266938)
		(stroke
			(width 0.254)
			(type default)
		)
		(layer "In6.Cu")
	)
	(gr_line
		(start 129.12598 -8.266938)
		(end 128.89738 -8.266938)
		(stroke
			(width 0.1778)
			(type default)
		)
		(layer "In6.Cu")
	)
	(gr_line
		(start 129.12598 -5.726938)
		(end 129.12598 -8.266938)
		(stroke
			(width 0.254)
			(type default)
		)
		(layer "In6.Cu")
	)
	(gr_line
		(start 129.12598 -5.701538)
		(end 129.12598 -8.266938)
		(stroke
			(width 0.1778)
			(type default)
		)
		(layer "In6.Cu")
	)
	(gr_line
		(start 129.15138 -12.492228)
		(end 127.93218 -12.492228)
		(stroke
			(width 0.1778)
			(type default)
		)
		(layer "In6.Cu")
	)
	(gr_line
		(start 129.15138 -12.492228)
		(end 128.92278 -12.492228)
		(stroke
			(width 0.127)
			(type default)
		)
		(layer "In6.Cu")
	)
	(gr_line
		(start 129.15138 -9.876028)
		(end 129.15138 -12.492228)
		(stroke
			(width 0.127)
			(type default)
		)
		(layer "In6.Cu")
	)
	(gr_line
		(start 129.15138 -9.876028)
		(end 129.15138 -12.492228)
		(stroke
			(width 0.1778)
			(type default)
		)
		(layer "In6.Cu")
	)
	(gr_line
		(start 129.15138 -8.292338)
		(end 127.93218 -8.292338)
		(stroke
			(width 0.1778)
			(type default)
		)
		(layer "In6.Cu")
	)
	(gr_line
		(start 129.15138 -8.292338)
		(end 128.92278 -8.292338)
		(stroke
			(width 0.127)
			(type default)
		)
		(layer "In6.Cu")
	)
	(gr_line
		(start 129.15138 -5.676138)
		(end 129.15138 -8.292338)
		(stroke
			(width 0.127)
			(type default)
		)
		(layer "In6.Cu")
	)
	(gr_line
		(start 129.15138 -5.676138)
		(end 129.15138 -8.292338)
		(stroke
			(width 0.1778)
			(type default)
		)
		(layer "In6.Cu")
	)
	(gr_line
		(start 129.17678 -12.517628)
		(end 127.90678 -12.517628)
		(stroke
			(width 0.127)
			(type default)
		)
		(layer "In6.Cu")
	)
	(gr_line
		(start 129.17678 -9.850628)
		(end 129.17678 -12.517628)
		(stroke
			(width 0.127)
			(type default)
		)
		(layer "In6.Cu")
	)
	(gr_line
		(start 129.17678 -8.317738)
		(end 127.90678 -8.317738)
		(stroke
			(width 0.127)
			(type default)
		)
		(layer "In6.Cu")
	)
	(gr_line
		(start 129.17678 -5.650738)
		(end 129.17678 -8.317738)
		(stroke
			(width 0.127)
			(type default)
		)
		(layer "In6.Cu")
	)
	(gr_line
		(start 129.20218 -12.543028)
		(end 129.20218 -9.825228)
		(stroke
			(width 0.1016)
			(type default)
		)
		(layer "In6.Cu")
	)
	(gr_line
		(start 129.20218 -9.825228)
		(end 127.85598 -9.825228)
		(stroke
			(width 0.1016)
			(type default)
		)
		(layer "In6.Cu")
	)
	(gr_line
		(start 129.20218 -8.343138)
		(end 129.20218 -5.625338)
		(stroke
			(width 0.1016)
			(type default)
		)
		(layer "In6.Cu")
	)
	(gr_line
		(start 129.20218 -5.625338)
		(end 127.85598 -5.625338)
		(stroke
			(width 0.1016)
			(type default)
		)
		(layer "In6.Cu")
	)
	(gr_line
		(start 132.9182 -3.95732)
		(end 132.9182 -5.22732)
		(stroke
			(width 1.016)
			(type default)
		)
		(layer "In6.Cu")
	)
	(gr_arc
		(start 132.990082 -52.319936)
		(mid 133.697187 -52.027043)
		(end 133.99008 -51.319938)
		(stroke
			(width 1.016)
			(type default)
		)
		(layer "In6.Cu")
	)
	(gr_line
		(start 133.99008 -51.319938)
		(end 133.99008 -50.8)
		(stroke
			(width 1.016)
			(type default)
		)
		(layer "In6.Cu")
	)
	(gr_arc
		(start 134.990078 -49.800002)
		(mid 134.282987 -50.092902)
		(end 133.99008 -50.8)
		(stroke
			(width 1.016)
			(type default)
		)
		(layer "In6.Cu")
	)
	(gr_line
		(start 134.990078 -49.800002)
		(end 149.990048 -49.800002)
		(stroke
			(width 1.016)
			(type default)
		)
		(layer "In6.Cu")
	)
	(gr_line
		(start 139.4968 -11.3792)
		(end 139.4968 -9.1948)
		(stroke
			(width 0.254)
			(type default)
		)
		(layer "In6.Cu")
	)
	(gr_line
		(start 139.4968 -9.1948)
		(end 141.0716 -9.1948)
		(stroke
			(width 0.254)
			(type default)
		)
		(layer "In6.Cu")
	)
	(gr_line
		(start 139.5222 -11.3792)
		(end 139.5222 -9.2456)
		(stroke
			(width 0.254)
			(type default)
		)
		(layer "In6.Cu")
	)
	(gr_line
		(start 139.5222 -9.2456)
		(end 141.0462 -9.2456)
		(stroke
			(width 0.254)
			(type default)
		)
		(layer "In6.Cu")
	)
	(gr_line
		(start 139.573 -11.3538)
		(end 139.573 -9.3726)
		(stroke
			(width 0.254)
			(type default)
		)
		(layer "In6.Cu")
	)
	(gr_line
		(start 139.573 -9.3726)
		(end 141.0208 -9.3726)
		(stroke
			(width 0.254)
			(type default)
		)
		(layer "In6.Cu")
	)
	(gr_line
		(start 139.627102 -11.303)
		(end 139.931902 -11.303)
		(stroke
			(width 0.1016)
			(type default)
		)
		(layer "In6.Cu")
	)
	(gr_line
		(start 139.627102 -9.2964)
		(end 139.627102 -11.303)
		(stroke
			(width 0.1016)
			(type default)
		)
		(layer "In6.Cu")
	)
	(gr_line
		(start 139.677902 -11.2268)
		(end 140.770102 -11.2268)
		(stroke
			(width 0.2032)
			(type default)
		)
		(layer "In6.Cu")
	)
	(gr_line
		(start 139.677902 -9.3726)
		(end 139.677902 -11.2268)
		(stroke
			(width 0.2032)
			(type default)
		)
		(layer "In6.Cu")
	)
	(gr_line
		(start 139.703302 -11.2268)
		(end 140.871702 -11.2268)
		(stroke
			(width 0.2032)
			(type default)
		)
		(layer "In6.Cu")
	)
	(gr_line
		(start 139.703302 -9.4234)
		(end 139.703302 -11.2268)
		(stroke
			(width 0.2032)
			(type default)
		)
		(layer "In6.Cu")
	)
	(gr_line
		(start 139.7508 -11.1252)
		(end 139.7508 -9.5758)
		(stroke
			(width 0.762)
			(type default)
		)
		(layer "In6.Cu")
	)
	(gr_line
		(start 139.7508 -11.1252)
		(end 140.6652 -11.1252)
		(stroke
			(width 0.762)
			(type default)
		)
		(layer "In6.Cu")
	)
	(gr_line
		(start 139.7508 -11.0998)
		(end 139.7508 -9.5504)
		(stroke
			(width 0.762)
			(type default)
		)
		(layer "In6.Cu")
	)
	(gr_line
		(start 139.7508 -10.9982)
		(end 139.7508 -9.4488)
		(stroke
			(width 0.762)
			(type default)
		)
		(layer "In6.Cu")
	)
	(gr_line
		(start 139.7508 -9.4488)
		(end 140.6652 -9.4488)
		(stroke
			(width 0.762)
			(type default)
		)
		(layer "In6.Cu")
	)
	(gr_line
		(start 139.754102 -11.176)
		(end 140.846302 -11.176)
		(stroke
			(width 0.2032)
			(type default)
		)
		(layer "In6.Cu")
	)
	(gr_line
		(start 139.754102 -9.4742)
		(end 139.754102 -11.176)
		(stroke
			(width 0.2032)
			(type default)
		)
		(layer "In6.Cu")
	)
	(gr_line
		(start 139.7762 -10.9982)
		(end 140.6906 -10.9982)
		(stroke
			(width 0.762)
			(type default)
		)
		(layer "In6.Cu")
	)
	(gr_line
		(start 139.7762 -9.5758)
		(end 140.6906 -9.5758)
		(stroke
			(width 0.762)
			(type default)
		)
		(layer "In6.Cu")
	)
	(gr_line
		(start 139.855702 -11.0744)
		(end 140.643102 -11.0744)
		(stroke
			(width 0.508)
			(type default)
		)
		(layer "In6.Cu")
	)
	(gr_line
		(start 139.855702 -11.049)
		(end 139.855702 -9.525)
		(stroke
			(width 0.508)
			(type default)
		)
		(layer "In6.Cu")
	)
	(gr_line
		(start 139.881102 -11.0744)
		(end 139.881102 -9.5504)
		(stroke
			(width 0.508)
			(type default)
		)
		(layer "In6.Cu")
	)
	(gr_line
		(start 139.9032 -11.1252)
		(end 140.8176 -11.1252)
		(stroke
			(width 0.762)
			(type default)
		)
		(layer "In6.Cu")
	)
	(gr_line
		(start 139.9032 -9.4488)
		(end 140.8176 -9.4488)
		(stroke
			(width 0.762)
			(type default)
		)
		(layer "In6.Cu")
	)
	(gr_line
		(start 139.906502 -9.525)
		(end 140.643102 -9.525)
		(stroke
			(width 0.508)
			(type default)
		)
		(layer "In6.Cu")
	)
	(gr_line
		(start 139.931902 -11.303)
		(end 140.922502 -11.303)
		(stroke
			(width 0.1016)
			(type default)
		)
		(layer "In6.Cu")
	)
	(gr_line
		(start 139.931902 -11.0744)
		(end 139.931902 -9.5504)
		(stroke
			(width 0.508)
			(type default)
		)
		(layer "In6.Cu")
	)
	(gr_line
		(start 139.957302 -11.0744)
		(end 139.957302 -9.5504)
		(stroke
			(width 0.508)
			(type default)
		)
		(layer "In6.Cu")
	)
	(gr_line
		(start 139.982702 -11.0744)
		(end 139.982702 -9.5504)
		(stroke
			(width 0.508)
			(type default)
		)
		(layer "In6.Cu")
	)
	(gr_line
		(start 140.008102 -11.0744)
		(end 140.008102 -9.5504)
		(stroke
			(width 0.508)
			(type default)
		)
		(layer "In6.Cu")
	)
	(gr_line
		(start 140.008102 -11.049)
		(end 140.008102 -9.525)
		(stroke
			(width 0.508)
			(type default)
		)
		(layer "In6.Cu")
	)
	(gr_line
		(start 140.033502 -11.0744)
		(end 140.033502 -9.5504)
		(stroke
			(width 0.508)
			(type default)
		)
		(layer "In6.Cu")
	)
	(gr_line
		(start 140.058902 -11.0744)
		(end 140.058902 -9.5504)
		(stroke
			(width 0.508)
			(type default)
		)
		(layer "In6.Cu")
	)
	(gr_line
		(start 140.109702 -11.0744)
		(end 140.109702 -9.5504)
		(stroke
			(width 0.508)
			(type default)
		)
		(layer "In6.Cu")
	)
	(gr_line
		(start 140.109702 -11.049)
		(end 140.109702 -9.525)
		(stroke
			(width 0.508)
			(type default)
		)
		(layer "In6.Cu")
	)
	(gr_line
		(start 140.135102 -11.0744)
		(end 140.135102 -9.5504)
		(stroke
			(width 0.508)
			(type default)
		)
		(layer "In6.Cu")
	)
	(gr_line
		(start 140.160502 -11.0744)
		(end 140.160502 -9.5504)
		(stroke
			(width 0.508)
			(type default)
		)
		(layer "In6.Cu")
	)
	(gr_line
		(start 140.185902 -11.0744)
		(end 140.185902 -9.5504)
		(stroke
			(width 0.508)
			(type default)
		)
		(layer "In6.Cu")
	)
	(gr_line
		(start 140.236702 -11.0744)
		(end 140.236702 -9.5504)
		(stroke
			(width 0.508)
			(type default)
		)
		(layer "In6.Cu")
	)
	(gr_line
		(start 140.262102 -11.0744)
		(end 140.262102 -9.5504)
		(stroke
			(width 0.508)
			(type default)
		)
		(layer "In6.Cu")
	)
	(gr_line
		(start 140.262102 -11.049)
		(end 140.262102 -9.525)
		(stroke
			(width 0.508)
			(type default)
		)
		(layer "In6.Cu")
	)
	(gr_line
		(start 140.287502 -11.0744)
		(end 140.287502 -9.5504)
		(stroke
			(width 0.508)
			(type default)
		)
		(layer "In6.Cu")
	)
	(gr_line
		(start 140.312902 -11.0744)
		(end 140.312902 -9.5504)
		(stroke
			(width 0.508)
			(type default)
		)
		(layer "In6.Cu")
	)
	(gr_line
		(start 140.338302 -11.0744)
		(end 140.338302 -9.5504)
		(stroke
			(width 0.508)
			(type default)
		)
		(layer "In6.Cu")
	)
	(gr_line
		(start 140.338302 -11.049)
		(end 140.338302 -9.525)
		(stroke
			(width 0.508)
			(type default)
		)
		(layer "In6.Cu")
	)
	(gr_line
		(start 140.363702 -11.0744)
		(end 140.363702 -9.5504)
		(stroke
			(width 0.508)
			(type default)
		)
		(layer "In6.Cu")
	)
	(gr_line
		(start 140.389102 -11.0744)
		(end 140.389102 -9.5504)
		(stroke
			(width 0.508)
			(type default)
		)
		(layer "In6.Cu")
	)
	(gr_line
		(start 140.389102 -11.049)
		(end 140.389102 -9.525)
		(stroke
			(width 0.508)
			(type default)
		)
		(layer "In6.Cu")
	)
	(gr_line
		(start 140.414502 -11.0744)
		(end 140.414502 -9.5504)
		(stroke
			(width 0.508)
			(type default)
		)
		(layer "In6.Cu")
	)
	(gr_line
		(start 140.414502 -11.049)
		(end 140.414502 -9.525)
		(stroke
			(width 0.508)
			(type default)
		)
		(layer "In6.Cu")
	)
	(gr_line
		(start 140.439902 -11.049)
		(end 140.439902 -9.525)
		(stroke
			(width 0.508)
			(type default)
		)
		(layer "In6.Cu")
	)
	(gr_line
		(start 140.465302 -11.0744)
		(end 140.465302 -9.5504)
		(stroke
			(width 0.508)
			(type default)
		)
		(layer "In6.Cu")
	)
	(gr_line
		(start 140.4874 -11.3792)
		(end 139.4968 -11.3792)
		(stroke
			(width 0.254)
			(type default)
		)
		(layer "In6.Cu")
	)
	(gr_line
		(start 140.490702 -11.049)
		(end 140.490702 -9.525)
		(stroke
			(width 0.508)
			(type default)
		)
		(layer "In6.Cu")
	)
	(gr_line
		(start 140.516102 -11.049)
		(end 140.516102 -9.525)
		(stroke
			(width 0.508)
			(type default)
		)
		(layer "In6.Cu")
	)
	(gr_line
		(start 140.541502 -11.0744)
		(end 140.541502 -9.5504)
		(stroke
			(width 0.508)
			(type default)
		)
		(layer "In6.Cu")
	)
	(gr_line
		(start 140.566902 -11.0744)
		(end 140.566902 -9.5504)
		(stroke
			(width 0.508)
			(type default)
		)
		(layer "In6.Cu")
	)
	(gr_line
		(start 140.566902 -11.049)
		(end 140.566902 -9.525)
		(stroke
			(width 0.508)
			(type default)
		)
		(layer "In6.Cu")
	)
	(gr_line
		(start 140.617702 -11.0744)
		(end 140.617702 -9.5504)
		(stroke
			(width 0.508)
			(type default)
		)
		(layer "In6.Cu")
	)
	(gr_line
		(start 140.617702 -11.049)
		(end 140.617702 -9.525)
		(stroke
			(width 0.508)
			(type default)
		)
		(layer "In6.Cu")
	)
	(gr_line
		(start 140.668502 -11.0744)
		(end 140.668502 -9.5504)
		(stroke
			(width 0.508)
			(type default)
		)
		(layer "In6.Cu")
	)
	(gr_line
		(start 140.668502 -11.049)
		(end 140.668502 -9.525)
		(stroke
			(width 0.508)
			(type default)
		)
		(layer "In6.Cu")
	)
	(gr_line
		(start 140.6906 -11.0998)
		(end 140.6906 -9.5504)
		(stroke
			(width 0.762)
			(type default)
		)
		(layer "In6.Cu")
	)
	(gr_line
		(start 140.693902 -11.0744)
		(end 140.693902 -9.5504)
		(stroke
			(width 0.508)
			(type default)
		)
		(layer "In6.Cu")
	)
	(gr_line
		(start 140.719302 -11.0744)
		(end 140.719302 -9.5504)
		(stroke
			(width 0.508)
			(type default)
		)
		(layer "In6.Cu")
	)
	(gr_line
		(start 140.770102 -11.2268)
		(end 140.795502 -11.2268)
		(stroke
			(width 0.2032)
			(type default)
		)
		(layer "In6.Cu")
	)
	(gr_line
		(start 140.795502 -11.2268)
		(end 140.795502 -9.4742)
		(stroke
			(width 0.2032)
			(type default)
		)
		(layer "In6.Cu")
	)
	(gr_line
		(start 140.795502 -9.4742)
		(end 139.754102 -9.4742)
		(stroke
			(width 0.2032)
			(type default)
		)
		(layer "In6.Cu")
	)
	(gr_line
		(start 140.8176 -11.1252)
		(end 140.8176 -9.5758)
		(stroke
			(width 0.762)
			(type default)
		)
		(layer "In6.Cu")
	)
	(gr_line
		(start 140.8176 -11.0998)
		(end 140.8176 -9.6012)
		(stroke
			(width 0.762)
			(type default)
		)
		(layer "In6.Cu")
	)
	(gr_line
		(start 140.8176 -10.9982)
		(end 140.8176 -9.4488)
		(stroke
			(width 0.762)
			(type default)
		)
		(layer "In6.Cu")
	)
	(gr_line
		(start 140.846302 -11.176)
		(end 140.846302 -9.4234)
		(stroke
			(width 0.2032)
			(type default)
		)
		(layer "In6.Cu")
	)
	(gr_line
		(start 140.846302 -9.4234)
		(end 139.703302 -9.4234)
		(stroke
			(width 0.2032)
			(type default)
		)
		(layer "In6.Cu")
	)
	(gr_line
		(start 140.871702 -11.2268)
		(end 140.871702 -9.3726)
		(stroke
			(width 0.2032)
			(type default)
		)
		(layer "In6.Cu")
	)
	(gr_line
		(start 140.871702 -9.3726)
		(end 139.677902 -9.3726)
		(stroke
			(width 0.2032)
			(type default)
		)
		(layer "In6.Cu")
	)
	(gr_line
		(start 140.922502 -11.303)
		(end 140.922502 -9.2964)
		(stroke
			(width 0.1016)
			(type default)
		)
		(layer "In6.Cu")
	)
	(gr_line
		(start 140.922502 -9.2964)
		(end 139.627102 -9.2964)
		(stroke
			(width 0.1016)
			(type default)
		)
		(layer "In6.Cu")
	)
	(gr_line
		(start 141.0208 -11.2268)
		(end 140.770102 -11.2268)
		(stroke
			(width 0.254)
			(type default)
		)
		(layer "In6.Cu")
	)
	(gr_line
		(start 141.0208 -9.3726)
		(end 141.0208 -11.2268)
		(stroke
			(width 0.254)
			(type default)
		)
		(layer "In6.Cu")
	)
	(gr_line
		(start 141.0462 -11.3538)
		(end 139.573 -11.3538)
		(stroke
			(width 0.254)
			(type default)
		)
		(layer "In6.Cu")
	)
	(gr_line
		(start 141.0462 -9.2456)
		(end 141.0462 -11.3538)
		(stroke
			(width 0.254)
			(type default)
		)
		(layer "In6.Cu")
	)
	(gr_line
		(start 141.0716 -11.3792)
		(end 139.5222 -11.3792)
		(stroke
			(width 0.254)
			(type default)
		)
		(layer "In6.Cu")
	)
	(gr_line
		(start 141.0716 -9.1948)
		(end 141.0716 -11.3792)
		(stroke
			(width 0.254)
			(type default)
		)
		(layer "In6.Cu")
	)
	(gr_line
		(start 144.296892 -11.3792)
		(end 144.296892 -9.1948)
		(stroke
			(width 0.254)
			(type default)
		)
		(layer "In6.Cu")
	)
	(gr_line
		(start 144.296892 -9.1948)
		(end 145.871692 -9.1948)
		(stroke
			(width 0.254)
			(type default)
		)
		(layer "In6.Cu")
	)
	(gr_line
		(start 144.322292 -11.3792)
		(end 144.322292 -9.2456)
		(stroke
			(width 0.254)
			(type default)
		)
		(layer "In6.Cu")
	)
	(gr_line
		(start 144.322292 -9.2456)
		(end 145.846292 -9.2456)
		(stroke
			(width 0.254)
			(type default)
		)
		(layer "In6.Cu")
	)
	(gr_line
		(start 144.373092 -11.3538)
		(end 144.373092 -9.3726)
		(stroke
			(width 0.254)
			(type default)
		)
		(layer "In6.Cu")
	)
	(gr_line
		(start 144.373092 -9.3726)
		(end 145.820892 -9.3726)
		(stroke
			(width 0.254)
			(type default)
		)
		(layer "In6.Cu")
	)
	(gr_line
		(start 144.427194 -11.303)
		(end 144.731994 -11.303)
		(stroke
			(width 0.1016)
			(type default)
		)
		(layer "In6.Cu")
	)
	(gr_line
		(start 144.427194 -9.2964)
		(end 144.427194 -11.303)
		(stroke
			(width 0.1016)
			(type default)
		)
		(layer "In6.Cu")
	)
	(gr_line
		(start 144.455134 -5.715)
		(end 145.725134 -5.715)
		(stroke
			(width 1.016)
			(type default)
		)
		(layer "In6.Cu")
	)
	(gr_line
		(start 144.477994 -11.2268)
		(end 145.570194 -11.2268)
		(stroke
			(width 0.2032)
			(type default)
		)
		(layer "In6.Cu")
	)
	(gr_line
		(start 144.477994 -9.3726)
		(end 144.477994 -11.2268)
		(stroke
			(width 0.2032)
			(type default)
		)
		(layer "In6.Cu")
	)
	(gr_line
		(start 144.503394 -11.2268)
		(end 145.671794 -11.2268)
		(stroke
			(width 0.2032)
			(type default)
		)
		(layer "In6.Cu")
	)
	(gr_line
		(start 144.503394 -9.4234)
		(end 144.503394 -11.2268)
		(stroke
			(width 0.2032)
			(type default)
		)
		(layer "In6.Cu")
	)
	(gr_line
		(start 144.550892 -11.1252)
		(end 144.550892 -9.5758)
		(stroke
			(width 0.762)
			(type default)
		)
		(layer "In6.Cu")
	)
	(gr_line
		(start 144.550892 -11.1252)
		(end 145.465292 -11.1252)
		(stroke
			(width 0.762)
			(type default)
		)
		(layer "In6.Cu")
	)
	(gr_line
		(start 144.550892 -11.0998)
		(end 144.550892 -9.5504)
		(stroke
			(width 0.762)
			(type default)
		)
		(layer "In6.Cu")
	)
	(gr_line
		(start 144.550892 -10.9982)
		(end 144.550892 -9.4488)
		(stroke
			(width 0.762)
			(type default)
		)
		(layer "In6.Cu")
	)
	(gr_line
		(start 144.550892 -9.4488)
		(end 145.465292 -9.4488)
		(stroke
			(width 0.762)
			(type default)
		)
		(layer "In6.Cu")
	)
	(gr_line
		(start 144.554194 -11.176)
		(end 145.646394 -11.176)
		(stroke
			(width 0.2032)
			(type default)
		)
		(layer "In6.Cu")
	)
	(gr_line
		(start 144.554194 -9.4742)
		(end 144.554194 -11.176)
		(stroke
			(width 0.2032)
			(type default)
		)
		(layer "In6.Cu")
	)
	(gr_line
		(start 144.576292 -10.9982)
		(end 145.490692 -10.9982)
		(stroke
			(width 0.762)
			(type default)
		)
		(layer "In6.Cu")
	)
	(gr_line
		(start 144.576292 -9.5758)
		(end 145.490692 -9.5758)
		(stroke
			(width 0.762)
			(type default)
		)
		(layer "In6.Cu")
	)
	(gr_line
		(start 144.655794 -11.0744)
		(end 145.443194 -11.0744)
		(stroke
			(width 0.508)
			(type default)
		)
		(layer "In6.Cu")
	)
	(gr_line
		(start 144.655794 -11.049)
		(end 144.655794 -9.525)
		(stroke
			(width 0.508)
			(type default)
		)
		(layer "In6.Cu")
	)
	(gr_line
		(start 144.681194 -11.0744)
		(end 144.681194 -9.5504)
		(stroke
			(width 0.508)
			(type default)
		)
		(layer "In6.Cu")
	)
	(gr_line
		(start 144.703292 -11.1252)
		(end 145.617692 -11.1252)
		(stroke
			(width 0.762)
			(type default)
		)
		(layer "In6.Cu")
	)
	(gr_line
		(start 144.703292 -9.4488)
		(end 145.617692 -9.4488)
		(stroke
			(width 0.762)
			(type default)
		)
		(layer "In6.Cu")
	)
	(gr_line
		(start 144.706594 -9.525)
		(end 145.443194 -9.525)
		(stroke
			(width 0.508)
			(type default)
		)
		(layer "In6.Cu")
	)
	(gr_line
		(start 144.731994 -11.303)
		(end 145.722594 -11.303)
		(stroke
			(width 0.1016)
			(type default)
		)
		(layer "In6.Cu")
	)
	(gr_line
		(start 144.731994 -11.0744)
		(end 144.731994 -9.5504)
		(stroke
			(width 0.508)
			(type default)
		)
		(layer "In6.Cu")
	)
	(gr_line
		(start 144.757394 -11.0744)
		(end 144.757394 -9.5504)
		(stroke
			(width 0.508)
			(type default)
		)
		(layer "In6.Cu")
	)
	(gr_line
		(start 144.782794 -11.0744)
		(end 144.782794 -9.5504)
		(stroke
			(width 0.508)
			(type default)
		)
		(layer "In6.Cu")
	)
	(gr_line
		(start 144.808194 -11.0744)
		(end 144.808194 -9.5504)
		(stroke
			(width 0.508)
			(type default)
		)
		(layer "In6.Cu")
	)
	(gr_line
		(start 144.808194 -11.049)
		(end 144.808194 -9.525)
		(stroke
			(width 0.508)
			(type default)
		)
		(layer "In6.Cu")
	)
	(gr_line
		(start 144.833594 -11.0744)
		(end 144.833594 -9.5504)
		(stroke
			(width 0.508)
			(type default)
		)
		(layer "In6.Cu")
	)
	(gr_line
		(start 144.858994 -11.0744)
		(end 144.858994 -9.5504)
		(stroke
			(width 0.508)
			(type default)
		)
		(layer "In6.Cu")
	)
	(gr_line
		(start 144.909794 -11.0744)
		(end 144.909794 -9.5504)
		(stroke
			(width 0.508)
			(type default)
		)
		(layer "In6.Cu")
	)
	(gr_line
		(start 144.909794 -11.049)
		(end 144.909794 -9.525)
		(stroke
			(width 0.508)
			(type default)
		)
		(layer "In6.Cu")
	)
	(gr_line
		(start 144.935194 -11.0744)
		(end 144.935194 -9.5504)
		(stroke
			(width 0.508)
			(type default)
		)
		(layer "In6.Cu")
	)
	(gr_line
		(start 144.960594 -11.0744)
		(end 144.960594 -9.5504)
		(stroke
			(width 0.508)
			(type default)
		)
		(layer "In6.Cu")
	)
	(gr_line
		(start 144.985994 -11.0744)
		(end 144.985994 -9.5504)
		(stroke
			(width 0.508)
			(type default)
		)
		(layer "In6.Cu")
	)
	(gr_line
		(start 145.036794 -11.0744)
		(end 145.036794 -9.5504)
		(stroke
			(width 0.508)
			(type default)
		)
		(layer "In6.Cu")
	)
	(gr_line
		(start 145.062194 -11.0744)
		(end 145.062194 -9.5504)
		(stroke
			(width 0.508)
			(type default)
		)
		(layer "In6.Cu")
	)
	(gr_line
		(start 145.062194 -11.049)
		(end 145.062194 -9.525)
		(stroke
			(width 0.508)
			(type default)
		)
		(layer "In6.Cu")
	)
	(gr_line
		(start 145.087594 -11.0744)
		(end 145.087594 -9.5504)
		(stroke
			(width 0.508)
			(type default)
		)
		(layer "In6.Cu")
	)
	(gr_line
		(start 145.112994 -11.0744)
		(end 145.112994 -9.5504)
		(stroke
			(width 0.508)
			(type default)
		)
		(layer "In6.Cu")
	)
	(gr_line
		(start 145.138394 -11.0744)
		(end 145.138394 -9.5504)
		(stroke
			(width 0.508)
			(type default)
		)
		(layer "In6.Cu")
	)
	(gr_line
		(start 145.138394 -11.049)
		(end 145.138394 -9.525)
		(stroke
			(width 0.508)
			(type default)
		)
		(layer "In6.Cu")
	)
	(gr_line
		(start 145.163794 -11.0744)
		(end 145.163794 -9.5504)
		(stroke
			(width 0.508)
			(type default)
		)
		(layer "In6.Cu")
	)
	(gr_line
		(start 145.189194 -11.0744)
		(end 145.189194 -9.5504)
		(stroke
			(width 0.508)
			(type default)
		)
		(layer "In6.Cu")
	)
	(gr_line
		(start 145.189194 -11.049)
		(end 145.189194 -9.525)
		(stroke
			(width 0.508)
			(type default)
		)
		(layer "In6.Cu")
	)
	(gr_line
		(start 145.214594 -11.0744)
		(end 145.214594 -9.5504)
		(stroke
			(width 0.508)
			(type default)
		)
		(layer "In6.Cu")
	)
	(gr_line
		(start 145.214594 -11.049)
		(end 145.214594 -9.525)
		(stroke
			(width 0.508)
			(type default)
		)
		(layer "In6.Cu")
	)
	(gr_line
		(start 145.239994 -11.049)
		(end 145.239994 -9.525)
		(stroke
			(width 0.508)
			(type default)
		)
		(layer "In6.Cu")
	)
	(gr_line
		(start 145.265394 -11.0744)
		(end 145.265394 -9.5504)
		(stroke
			(width 0.508)
			(type default)
		)
		(layer "In6.Cu")
	)
	(gr_line
		(start 145.287492 -11.3792)
		(end 144.296892 -11.3792)
		(stroke
			(width 0.254)
			(type default)
		)
		(layer "In6.Cu")
	)
	(gr_line
		(start 145.290794 -11.049)
		(end 145.290794 -9.525)
		(stroke
			(width 0.508)
			(type default)
		)
		(layer "In6.Cu")
	)
	(gr_line
		(start 145.316194 -11.049)
		(end 145.316194 -9.525)
		(stroke
			(width 0.508)
			(type default)
		)
		(layer "In6.Cu")
	)
	(gr_line
		(start 145.341594 -11.0744)
		(end 145.341594 -9.5504)
		(stroke
			(width 0.508)
			(type default)
		)
		(layer "In6.Cu")
	)
	(gr_line
		(start 145.366994 -11.0744)
		(end 145.366994 -9.5504)
		(stroke
			(width 0.508)
			(type default)
		)
		(layer "In6.Cu")
	)
	(gr_line
		(start 145.366994 -11.049)
		(end 145.366994 -9.525)
		(stroke
			(width 0.508)
			(type default)
		)
		(layer "In6.Cu")
	)
	(gr_line
		(start 145.417794 -11.0744)
		(end 145.417794 -9.5504)
		(stroke
			(width 0.508)
			(type default)
		)
		(layer "In6.Cu")
	)
	(gr_line
		(start 145.417794 -11.049)
		(end 145.417794 -9.525)
		(stroke
			(width 0.508)
			(type default)
		)
		(layer "In6.Cu")
	)
	(gr_line
		(start 145.468594 -11.0744)
		(end 145.468594 -9.5504)
		(stroke
			(width 0.508)
			(type default)
		)
		(layer "In6.Cu")
	)
	(gr_line
		(start 145.468594 -11.049)
		(end 145.468594 -9.525)
		(stroke
			(width 0.508)
			(type default)
		)
		(layer "In6.Cu")
	)
	(gr_line
		(start 145.490692 -11.0998)
		(end 145.490692 -9.5504)
		(stroke
			(width 0.762)
			(type default)
		)
		(layer "In6.Cu")
	)
	(gr_line
		(start 145.493994 -11.0744)
		(end 145.493994 -9.5504)
		(stroke
			(width 0.508)
			(type default)
		)
		(layer "In6.Cu")
	)
	(gr_line
		(start 145.519394 -11.0744)
		(end 145.519394 -9.5504)
		(stroke
			(width 0.508)
			(type default)
		)
		(layer "In6.Cu")
	)
	(gr_line
		(start 145.570194 -11.2268)
		(end 145.595594 -11.2268)
		(stroke
			(width 0.2032)
			(type default)
		)
		(layer "In6.Cu")
	)
	(gr_line
		(start 145.595594 -11.2268)
		(end 145.595594 -9.4742)
		(stroke
			(width 0.2032)
			(type default)
		)
		(layer "In6.Cu")
	)
	(gr_line
		(start 145.595594 -9.4742)
		(end 144.554194 -9.4742)
		(stroke
			(width 0.2032)
			(type default)
		)
		(layer "In6.Cu")
	)
	(gr_line
		(start 145.617692 -11.1252)
		(end 145.617692 -9.5758)
		(stroke
			(width 0.762)
			(type default)
		)
		(layer "In6.Cu")
	)
	(gr_line
		(start 145.617692 -11.0998)
		(end 145.617692 -9.6012)
		(stroke
			(width 0.762)
			(type default)
		)
		(layer "In6.Cu")
	)
	(gr_line
		(start 145.617692 -10.9982)
		(end 145.617692 -9.4488)
		(stroke
			(width 0.762)
			(type default)
		)
		(layer "In6.Cu")
	)
	(gr_line
		(start 145.646394 -11.176)
		(end 145.646394 -9.4234)
		(stroke
			(width 0.2032)
			(type default)
		)
		(layer "In6.Cu")
	)
	(gr_line
		(start 145.646394 -9.4234)
		(end 144.503394 -9.4234)
		(stroke
			(width 0.2032)
			(type default)
		)
		(layer "In6.Cu")
	)
	(gr_line
		(start 145.671794 -11.2268)
		(end 145.671794 -9.3726)
		(stroke
			(width 0.2032)
			(type default)
		)
		(layer "In6.Cu")
	)
	(gr_line
		(start 145.671794 -9.3726)
		(end 144.477994 -9.3726)
		(stroke
			(width 0.2032)
			(type default)
		)
		(layer "In6.Cu")
	)
	(gr_line
		(start 145.722594 -11.303)
		(end 145.722594 -9.2964)
		(stroke
			(width 0.1016)
			(type default)
		)
		(layer "In6.Cu")
	)
	(gr_line
		(start 145.722594 -9.2964)
		(end 144.427194 -9.2964)
		(stroke
			(width 0.1016)
			(type default)
		)
		(layer "In6.Cu")
	)
	(gr_line
		(start 145.820892 -11.2268)
		(end 145.570194 -11.2268)
		(stroke
			(width 0.254)
			(type default)
		)
		(layer "In6.Cu")
	)
	(gr_line
		(start 145.820892 -9.3726)
		(end 145.820892 -11.2268)
		(stroke
			(width 0.254)
			(type default)
		)
		(layer "In6.Cu")
	)
	(gr_line
		(start 145.846292 -11.3538)
		(end 144.373092 -11.3538)
		(stroke
			(width 0.254)
			(type default)
		)
		(layer "In6.Cu")
	)
	(gr_line
		(start 145.846292 -9.2456)
		(end 145.846292 -11.3538)
		(stroke
			(width 0.254)
			(type default)
		)
		(layer "In6.Cu")
	)
	(gr_line
		(start 145.871692 -11.3792)
		(end 144.322292 -11.3792)
		(stroke
			(width 0.254)
			(type default)
		)
		(layer "In6.Cu")
	)
	(gr_line
		(start 145.871692 -9.1948)
		(end 145.871692 -11.3792)
		(stroke
			(width 0.254)
			(type default)
		)
		(layer "In6.Cu")
	)
	(gr_arc
		(start 150.990046 -51.319938)
		(mid 151.282939 -52.027043)
		(end 151.990044 -52.319936)
		(stroke
			(width 1.016)
			(type default)
		)
		(layer "In6.Cu")
	)
	(gr_arc
		(start 150.990046 -50.8)
		(mid 150.697156 -50.092878)
		(end 149.990048 -49.800002)
		(stroke
			(width 1.016)
			(type default)
		)
		(layer "In6.Cu")
	)
	(gr_line
		(start 150.990046 -50.8)
		(end 150.990046 -51.319938)
		(stroke
			(width 1.016)
			(type default)
		)
		(layer "In6.Cu")
	)
	(gr_line
		(start 151.990044 -52.319936)
		(end 158.99003 -52.319936)
		(stroke
			(width 1.016)
			(type default)
		)
		(layer "In6.Cu")
	)
	(gr_line
		(start 158.99003 -52.319936)
		(end 159.372554 -52.24399)
		(stroke
			(width 1.016)
			(type default)
		)
		(layer "In6.Cu")
	)
	(gr_line
		(start 159.372554 -52.24399)
		(end 159.697166 -52.027074)
		(stroke
			(width 1.016)
			(type default)
		)
		(layer "In6.Cu")
	)
	(gr_line
		(start 159.697166 -52.027074)
		(end 159.913828 -51.702716)
		(stroke
			(width 1.016)
			(type default)
		)
		(layer "In6.Cu")
	)
	(gr_line
		(start 159.913828 -51.702716)
		(end 159.982154 -51.376072)
		(stroke
			(width 1.016)
			(type default)
		)
		(layer "In6.Cu")
	)
	(gr_line
		(start 159.982154 -51.376072)
		(end 160.0708 -50.996088)
		(stroke
			(width 1.016)
			(type default)
		)
		(layer "In6.Cu")
	)
	(gr_line
		(start 160.0708 -50.996088)
		(end 160.288732 -50.677064)
		(stroke
			(width 1.016)
			(type default)
		)
		(layer "In6.Cu")
	)
	(gr_line
		(start 160.288732 -50.677064)
		(end 160.611058 -50.464466)
		(stroke
			(width 1.016)
			(type default)
		)
		(layer "In6.Cu")
	)
	(gr_line
		(start 160.611058 -50.464466)
		(end 160.990026 -50.390044)
		(stroke
			(width 1.016)
			(type default)
		)
		(layer "In6.Cu")
	)
	(gr_line
		(start 160.990026 -50.390044)
		(end 202.989942 -50.390044)
		(stroke
			(width 1.016)
			(type default)
		)
		(layer "In6.Cu")
	)
	(gr_line
		(start 164.2872 -13.8176)
		(end 165.0746 -13.8176)
		(stroke
			(width 0.1016)
			(type default)
		)
		(layer "In6.Cu")
	)
	(gr_line
		(start 164.2872 -13.7668)
		(end 164.2872 -11.1506)
		(stroke
			(width 0.1016)
			(type default)
		)
		(layer "In6.Cu")
	)
	(gr_line
		(start 164.2872 -11.1506)
		(end 164.2872 -13.8176)
		(stroke
			(width 0.1016)
			(type default)
		)
		(layer "In6.Cu")
	)
	(gr_line
		(start 164.2872 -11.1506)
		(end 165.481 -11.1506)
		(stroke
			(width 0.1016)
			(type default)
		)
		(layer "In6.Cu")
	)
	(gr_line
		(start 164.2872 -9.617456)
		(end 165.0746 -9.617456)
		(stroke
			(width 0.1016)
			(type default)
		)
		(layer "In6.Cu")
	)
	(gr_line
		(start 164.2872 -9.566656)
		(end 164.2872 -6.950456)
		(stroke
			(width 0.1016)
			(type default)
		)
		(layer "In6.Cu")
	)
	(gr_line
		(start 164.2872 -6.950456)
		(end 164.2872 -9.617456)
		(stroke
			(width 0.1016)
			(type default)
		)
		(layer "In6.Cu")
	)
	(gr_line
		(start 164.2872 -6.950456)
		(end 165.481 -6.950456)
		(stroke
			(width 0.1016)
			(type default)
		)
		(layer "In6.Cu")
	)
	(gr_line
		(start 164.2872 -5.417312)
		(end 165.0746 -5.417312)
		(stroke
			(width 0.1016)
			(type default)
		)
		(layer "In6.Cu")
	)
	(gr_line
		(start 164.2872 -5.366512)
		(end 164.2872 -2.750312)
		(stroke
			(width 0.1016)
			(type default)
		)
		(layer "In6.Cu")
	)
	(gr_line
		(start 164.2872 -2.750312)
		(end 164.2872 -5.417312)
		(stroke
			(width 0.1016)
			(type default)
		)
		(layer "In6.Cu")
	)
	(gr_line
		(start 164.2872 -2.750312)
		(end 165.481 -2.750312)
		(stroke
			(width 0.1016)
			(type default)
		)
		(layer "In6.Cu")
	)
	(gr_line
		(start 164.3126 -13.7668)
		(end 164.3126 -11.176)
		(stroke
			(width 0.1016)
			(type default)
		)
		(layer "In6.Cu")
	)
	(gr_line
		(start 164.3126 -11.176)
		(end 165.4556 -11.176)
		(stroke
			(width 0.1016)
			(type default)
		)
		(layer "In6.Cu")
	)
	(gr_line
		(start 164.3126 -9.566656)
		(end 164.3126 -6.975856)
		(stroke
			(width 0.1016)
			(type default)
		)
		(layer "In6.Cu")
	)
	(gr_line
		(start 164.3126 -6.975856)
		(end 165.4556 -6.975856)
		(stroke
			(width 0.1016)
			(type default)
		)
		(layer "In6.Cu")
	)
	(gr_line
		(start 164.3126 -5.366512)
		(end 164.3126 -2.775712)
		(stroke
			(width 0.1016)
			(type default)
		)
		(layer "In6.Cu")
	)
	(gr_line
		(start 164.3126 -2.775712)
		(end 165.4556 -2.775712)
		(stroke
			(width 0.1016)
			(type default)
		)
		(layer "In6.Cu")
	)
	(gr_line
		(start 164.338 -13.7668)
		(end 164.338 -11.2014)
		(stroke
			(width 0.1016)
			(type default)
		)
		(layer "In6.Cu")
	)
	(gr_line
		(start 164.338 -11.2014)
		(end 164.592 -11.2014)
		(stroke
			(width 0.1016)
			(type default)
		)
		(layer "In6.Cu")
	)
	(gr_line
		(start 164.338 -9.566656)
		(end 164.338 -7.001256)
		(stroke
			(width 0.1016)
			(type default)
		)
		(layer "In6.Cu")
	)
	(gr_line
		(start 164.338 -7.001256)
		(end 164.592 -7.001256)
		(stroke
			(width 0.1016)
			(type default)
		)
		(layer "In6.Cu")
	)
	(gr_line
		(start 164.338 -5.366512)
		(end 164.338 -2.801112)
		(stroke
			(width 0.1016)
			(type default)
		)
		(layer "In6.Cu")
	)
	(gr_line
		(start 164.338 -2.801112)
		(end 164.592 -2.801112)
		(stroke
			(width 0.1016)
			(type default)
		)
		(layer "In6.Cu")
	)
	(gr_line
		(start 164.3634 -13.7668)
		(end 164.3634 -11.2014)
		(stroke
			(width 0.2032)
			(type default)
		)
		(layer "In6.Cu")
	)
	(gr_line
		(start 164.3634 -11.2014)
		(end 165.3794 -11.2014)
		(stroke
			(width 0.2032)
			(type default)
		)
		(layer "In6.Cu")
	)
	(gr_line
		(start 164.3634 -9.566656)
		(end 164.3634 -7.001256)
		(stroke
			(width 0.2032)
			(type default)
		)
		(layer "In6.Cu")
	)
	(gr_line
		(start 164.3634 -7.001256)
		(end 165.3794 -7.001256)
		(stroke
			(width 0.2032)
			(type default)
		)
		(layer "In6.Cu")
	)
	(gr_line
		(start 164.3634 -5.366512)
		(end 164.3634 -2.801112)
		(stroke
			(width 0.2032)
			(type default)
		)
		(layer "In6.Cu")
	)
	(gr_line
		(start 164.3634 -2.801112)
		(end 165.3794 -2.801112)
		(stroke
			(width 0.2032)
			(type default)
		)
		(layer "In6.Cu")
	)
	(gr_line
		(start 164.4142 -13.7414)
		(end 164.4142 -11.2522)
		(stroke
			(width 0.2032)
			(type default)
		)
		(layer "In6.Cu")
	)
	(gr_line
		(start 164.4142 -13.7414)
		(end 164.4142 -11.2522)
		(stroke
			(width 0.254)
			(type default)
		)
		(layer "In6.Cu")
	)
	(gr_line
		(start 164.4142 -11.2522)
		(end 164.6174 -11.2522)
		(stroke
			(width 0.2032)
			(type default)
		)
		(layer "In6.Cu")
	)
	(gr_line
		(start 164.4142 -11.2522)
		(end 165.3032 -11.2522)
		(stroke
			(width 0.254)
			(type default)
		)
		(layer "In6.Cu")
	)
	(gr_line
		(start 164.4142 -9.541256)
		(end 164.4142 -7.052056)
		(stroke
			(width 0.2032)
			(type default)
		)
		(layer "In6.Cu")
	)
	(gr_line
		(start 164.4142 -9.541256)
		(end 164.4142 -7.052056)
		(stroke
			(width 0.254)
			(type default)
		)
		(layer "In6.Cu")
	)
	(gr_line
		(start 164.4142 -7.052056)
		(end 164.6174 -7.052056)
		(stroke
			(width 0.2032)
			(type default)
		)
		(layer "In6.Cu")
	)
	(gr_line
		(start 164.4142 -7.052056)
		(end 165.3032 -7.052056)
		(stroke
			(width 0.254)
			(type default)
		)
		(layer "In6.Cu")
	)
	(gr_line
		(start 164.4142 -5.341112)
		(end 164.4142 -2.851912)
		(stroke
			(width 0.2032)
			(type default)
		)
		(layer "In6.Cu")
	)
	(gr_line
		(start 164.4142 -5.341112)
		(end 164.4142 -2.851912)
		(stroke
			(width 0.254)
			(type default)
		)
		(layer "In6.Cu")
	)
	(gr_line
		(start 164.4142 -2.851912)
		(end 164.6174 -2.851912)
		(stroke
			(width 0.2032)
			(type default)
		)
		(layer "In6.Cu")
	)
	(gr_line
		(start 164.4142 -2.851912)
		(end 165.3032 -2.851912)
		(stroke
			(width 0.254)
			(type default)
		)
		(layer "In6.Cu")
	)
	(gr_line
		(start 164.4396 -13.716)
		(end 164.4396 -11.2776)
		(stroke
			(width 0.254)
			(type default)
		)
		(layer "In6.Cu")
	)
	(gr_line
		(start 164.4396 -11.2776)
		(end 165.2778 -11.2776)
		(stroke
			(width 0.254)
			(type default)
		)
		(layer "In6.Cu")
	)
	(gr_line
		(start 164.4396 -9.515856)
		(end 164.4396 -7.077456)
		(stroke
			(width 0.254)
			(type default)
		)
		(layer "In6.Cu")
	)
	(gr_line
		(start 164.4396 -7.077456)
		(end 165.2778 -7.077456)
		(stroke
			(width 0.254)
			(type default)
		)
		(layer "In6.Cu")
	)
	(gr_line
		(start 164.4396 -5.315712)
		(end 164.4396 -2.877312)
		(stroke
			(width 0.254)
			(type default)
		)
		(layer "In6.Cu")
	)
	(gr_line
		(start 164.4396 -2.877312)
		(end 165.2778 -2.877312)
		(stroke
			(width 0.254)
			(type default)
		)
		(layer "In6.Cu")
	)
	(gr_line
		(start 164.465 -13.6906)
		(end 164.465 -11.303)
		(stroke
			(width 0.254)
			(type default)
		)
		(layer "In6.Cu")
	)
	(gr_line
		(start 164.465 -11.303)
		(end 165.2524 -11.303)
		(stroke
			(width 0.254)
			(type default)
		)
		(layer "In6.Cu")
	)
	(gr_line
		(start 164.465 -9.490456)
		(end 164.465 -7.102856)
		(stroke
			(width 0.254)
			(type default)
		)
		(layer "In6.Cu")
	)
	(gr_line
		(start 164.465 -7.102856)
		(end 165.2524 -7.102856)
		(stroke
			(width 0.254)
			(type default)
		)
		(layer "In6.Cu")
	)
	(gr_line
		(start 164.465 -5.290312)
		(end 164.465 -2.902712)
		(stroke
			(width 0.254)
			(type default)
		)
		(layer "In6.Cu")
	)
	(gr_line
		(start 164.465 -2.902712)
		(end 165.2524 -2.902712)
		(stroke
			(width 0.254)
			(type default)
		)
		(layer "In6.Cu")
	)
	(gr_line
		(start 164.4904 -13.6144)
		(end 165.1254 -13.6144)
		(stroke
			(width 0.508)
			(type default)
		)
		(layer "In6.Cu")
	)
	(gr_line
		(start 164.4904 -11.43)
		(end 165.1254 -11.43)
		(stroke
			(width 0.508)
			(type default)
		)
		(layer "In6.Cu")
	)
	(gr_line
		(start 164.4904 -11.3792)
		(end 165.1254 -11.3792)
		(stroke
			(width 0.508)
			(type default)
		)
		(layer "In6.Cu")
	)
	(gr_line
		(start 164.4904 -9.414256)
		(end 165.1254 -9.414256)
		(stroke
			(width 0.508)
			(type default)
		)
		(layer "In6.Cu")
	)
	(gr_line
		(start 164.4904 -7.229856)
		(end 165.1254 -7.229856)
		(stroke
			(width 0.508)
			(type default)
		)
		(layer "In6.Cu")
	)
	(gr_line
		(start 164.4904 -7.179056)
		(end 165.1254 -7.179056)
		(stroke
			(width 0.508)
			(type default)
		)
		(layer "In6.Cu")
	)
	(gr_line
		(start 164.4904 -5.214112)
		(end 165.1254 -5.214112)
		(stroke
			(width 0.508)
			(type default)
		)
		(layer "In6.Cu")
	)
	(gr_line
		(start 164.4904 -3.029712)
		(end 165.1254 -3.029712)
		(stroke
			(width 0.508)
			(type default)
		)
		(layer "In6.Cu")
	)
	(gr_line
		(start 164.4904 -2.978912)
		(end 165.1254 -2.978912)
		(stroke
			(width 0.508)
			(type default)
		)
		(layer "In6.Cu")
	)
	(gr_line
		(start 164.5158 -11.684)
		(end 165.1508 -11.684)
		(stroke
			(width 0.508)
			(type default)
		)
		(layer "In6.Cu")
	)
	(gr_line
		(start 164.5158 -7.483856)
		(end 165.1508 -7.483856)
		(stroke
			(width 0.508)
			(type default)
		)
		(layer "In6.Cu")
	)
	(gr_line
		(start 164.5158 -3.283712)
		(end 165.1508 -3.283712)
		(stroke
			(width 0.508)
			(type default)
		)
		(layer "In6.Cu")
	)
	(gr_line
		(start 164.5412 -13.6398)
		(end 164.5412 -11.3792)
		(stroke
			(width 0.254)
			(type default)
		)
		(layer "In6.Cu")
	)
	(gr_line
		(start 164.5412 -13.4874)
		(end 165.1762 -13.4874)
		(stroke
			(width 0.508)
			(type default)
		)
		(layer "In6.Cu")
	)
	(gr_line
		(start 164.5412 -11.3792)
		(end 165.1762 -11.3792)
		(stroke
			(width 0.254)
			(type default)
		)
		(layer "In6.Cu")
	)
	(gr_line
		(start 164.5412 -9.439656)
		(end 164.5412 -7.179056)
		(stroke
			(width 0.254)
			(type default)
		)
		(layer "In6.Cu")
	)
	(gr_line
		(start 164.5412 -9.287256)
		(end 165.1762 -9.287256)
		(stroke
			(width 0.508)
			(type default)
		)
		(layer "In6.Cu")
	)
	(gr_line
		(start 164.5412 -7.179056)
		(end 165.1762 -7.179056)
		(stroke
			(width 0.254)
			(type default)
		)
		(layer "In6.Cu")
	)
	(gr_line
		(start 164.5412 -5.239512)
		(end 164.5412 -2.978912)
		(stroke
			(width 0.254)
			(type default)
		)
		(layer "In6.Cu")
	)
	(gr_line
		(start 164.5412 -5.087112)
		(end 165.1762 -5.087112)
		(stroke
			(width 0.508)
			(type default)
		)
		(layer "In6.Cu")
	)
	(gr_line
		(start 164.5412 -2.978912)
		(end 165.1762 -2.978912)
		(stroke
			(width 0.254)
			(type default)
		)
		(layer "In6.Cu")
	)
	(gr_line
		(start 164.5666 -13.335)
		(end 165.2016 -13.335)
		(stroke
			(width 0.508)
			(type default)
		)
		(layer "In6.Cu")
	)
	(gr_line
		(start 164.5666 -9.134856)
		(end 165.2016 -9.134856)
		(stroke
			(width 0.508)
			(type default)
		)
		(layer "In6.Cu")
	)
	(gr_line
		(start 164.5666 -4.934712)
		(end 165.2016 -4.934712)
		(stroke
			(width 0.508)
			(type default)
		)
		(layer "In6.Cu")
	)
	(gr_line
		(start 164.592 -13.6144)
		(end 165.227 -13.6144)
		(stroke
			(width 0.508)
			(type default)
		)
		(layer "In6.Cu")
	)
	(gr_line
		(start 164.592 -11.2014)
		(end 165.4302 -11.2014)
		(stroke
			(width 0.2032)
			(type default)
		)
		(layer "In6.Cu")
	)
	(gr_line
		(start 164.592 -9.414256)
		(end 165.227 -9.414256)
		(stroke
			(width 0.508)
			(type default)
		)
		(layer "In6.Cu")
	)
	(gr_line
		(start 164.592 -7.001256)
		(end 165.4302 -7.001256)
		(stroke
			(width 0.2032)
			(type default)
		)
		(layer "In6.Cu")
	)
	(gr_line
		(start 164.592 -5.214112)
		(end 165.227 -5.214112)
		(stroke
			(width 0.508)
			(type default)
		)
		(layer "In6.Cu")
	)
	(gr_line
		(start 164.592 -2.801112)
		(end 165.4302 -2.801112)
		(stroke
			(width 0.2032)
			(type default)
		)
		(layer "In6.Cu")
	)
	(gr_line
		(start 164.6174 -13.6144)
		(end 164.6174 -11.43)
		(stroke
			(width 0.254)
			(type default)
		)
		(layer "In6.Cu")
	)
	(gr_line
		(start 164.6174 -11.43)
		(end 165.1 -11.43)
		(stroke
			(width 0.254)
			(type default)
		)
		(layer "In6.Cu")
	)
	(gr_line
		(start 164.6174 -11.2522)
		(end 165.354 -11.2522)
		(stroke
			(width 0.254)
			(type default)
		)
		(layer "In6.Cu")
	)
	(gr_line
		(start 164.6174 -9.414256)
		(end 164.6174 -7.229856)
		(stroke
			(width 0.254)
			(type default)
		)
		(layer "In6.Cu")
	)
	(gr_line
		(start 164.6174 -7.229856)
		(end 165.1 -7.229856)
		(stroke
			(width 0.254)
			(type default)
		)
		(layer "In6.Cu")
	)
	(gr_line
		(start 164.6174 -7.052056)
		(end 165.354 -7.052056)
		(stroke
			(width 0.254)
			(type default)
		)
		(layer "In6.Cu")
	)
	(gr_line
		(start 164.6174 -5.214112)
		(end 164.6174 -3.029712)
		(stroke
			(width 0.254)
			(type default)
		)
		(layer "In6.Cu")
	)
	(gr_line
		(start 164.6174 -3.029712)
		(end 165.1 -3.029712)
		(stroke
			(width 0.254)
			(type default)
		)
		(layer "In6.Cu")
	)
	(gr_line
		(start 164.6174 -2.851912)
		(end 165.354 -2.851912)
		(stroke
			(width 0.254)
			(type default)
		)
		(layer "In6.Cu")
	)
	(gr_line
		(start 164.635942 -11.36523)
		(end 165.270942 -11.36523)
		(stroke
			(width 0.508)
			(type default)
		)
		(layer "In6.Cu")
	)
	(gr_line
		(start 164.635942 -7.165086)
		(end 165.270942 -7.165086)
		(stroke
			(width 0.508)
			(type default)
		)
		(layer "In6.Cu")
	)
	(gr_line
		(start 164.635942 -2.964942)
		(end 165.270942 -2.964942)
		(stroke
			(width 0.508)
			(type default)
		)
		(layer "In6.Cu")
	)
	(gr_line
		(start 164.6428 -13.6144)
		(end 165.2778 -13.6144)
		(stroke
			(width 0.508)
			(type default)
		)
		(layer "In6.Cu")
	)
	(gr_line
		(start 164.6428 -13.4874)
		(end 164.6428 -11.5062)
		(stroke
			(width 0.762)
			(type default)
		)
		(layer "In6.Cu")
	)
	(gr_line
		(start 164.6428 -11.5062)
		(end 165.2778 -11.5062)
		(stroke
			(width 0.508)
			(type default)
		)
		(layer "In6.Cu")
	)
	(gr_line
		(start 164.6428 -9.414256)
		(end 165.2778 -9.414256)
		(stroke
			(width 0.508)
			(type default)
		)
		(layer "In6.Cu")
	)
	(gr_line
		(start 164.6428 -9.287256)
		(end 164.6428 -7.306056)
		(stroke
			(width 0.762)
			(type default)
		)
		(layer "In6.Cu")
	)
	(gr_line
		(start 164.6428 -7.306056)
		(end 165.2778 -7.306056)
		(stroke
			(width 0.508)
			(type default)
		)
		(layer "In6.Cu")
	)
	(gr_line
		(start 164.6428 -5.214112)
		(end 165.2778 -5.214112)
		(stroke
			(width 0.508)
			(type default)
		)
		(layer "In6.Cu")
	)
	(gr_line
		(start 164.6428 -5.087112)
		(end 164.6428 -3.105912)
		(stroke
			(width 0.762)
			(type default)
		)
		(layer "In6.Cu")
	)
	(gr_line
		(start 164.6428 -3.105912)
		(end 165.2778 -3.105912)
		(stroke
			(width 0.508)
			(type default)
		)
		(layer "In6.Cu")
	)
	(gr_line
		(start 164.6936 -13.5382)
		(end 164.6936 -11.5062)
		(stroke
			(width 0.254)
			(type default)
		)
		(layer "In6.Cu")
	)
	(gr_line
		(start 164.6936 -11.5062)
		(end 165.0238 -11.5062)
		(stroke
			(width 0.254)
			(type default)
		)
		(layer "In6.Cu")
	)
	(gr_line
		(start 164.6936 -9.338056)
		(end 164.6936 -7.306056)
		(stroke
			(width 0.254)
			(type default)
		)
		(layer "In6.Cu")
	)
	(gr_line
		(start 164.6936 -7.306056)
		(end 165.0238 -7.306056)
		(stroke
			(width 0.254)
			(type default)
		)
		(layer "In6.Cu")
	)
	(gr_line
		(start 164.6936 -5.137912)
		(end 164.6936 -3.105912)
		(stroke
			(width 0.254)
			(type default)
		)
		(layer "In6.Cu")
	)
	(gr_line
		(start 164.6936 -3.105912)
		(end 165.0238 -3.105912)
		(stroke
			(width 0.254)
			(type default)
		)
		(layer "In6.Cu")
	)
	(gr_line
		(start 164.7952 -13.462)
		(end 164.7952 -11.6586)
		(stroke
			(width 0.254)
			(type default)
		)
		(layer "In6.Cu")
	)
	(gr_line
		(start 164.7952 -13.462)
		(end 164.7952 -11.4808)
		(stroke
			(width 0.762)
			(type default)
		)
		(layer "In6.Cu")
	)
	(gr_line
		(start 164.7952 -11.6586)
		(end 164.8968 -11.6586)
		(stroke
			(width 0.254)
			(type default)
		)
		(layer "In6.Cu")
	)
	(gr_line
		(start 164.7952 -9.261856)
		(end 164.7952 -7.458456)
		(stroke
			(width 0.254)
			(type default)
		)
		(layer "In6.Cu")
	)
	(gr_line
		(start 164.7952 -9.261856)
		(end 164.7952 -7.280656)
		(stroke
			(width 0.762)
			(type default)
		)
		(layer "In6.Cu")
	)
	(gr_line
		(start 164.7952 -7.458456)
		(end 164.8968 -7.458456)
		(stroke
			(width 0.254)
			(type default)
		)
		(layer "In6.Cu")
	)
	(gr_line
		(start 164.7952 -5.061712)
		(end 164.7952 -3.258312)
		(stroke
			(width 0.254)
			(type default)
		)
		(layer "In6.Cu")
	)
	(gr_line
		(start 164.7952 -5.061712)
		(end 164.7952 -3.080512)
		(stroke
			(width 0.762)
			(type default)
		)
		(layer "In6.Cu")
	)
	(gr_line
		(start 164.7952 -3.258312)
		(end 164.8968 -3.258312)
		(stroke
			(width 0.254)
			(type default)
		)
		(layer "In6.Cu")
	)
	(gr_line
		(start 164.8968 -13.5636)
		(end 164.846 -13.5636)
		(stroke
			(width 0.254)
			(type default)
		)
		(layer "In6.Cu")
	)
	(gr_line
		(start 164.8968 -11.6586)
		(end 164.8968 -13.5636)
		(stroke
			(width 0.254)
			(type default)
		)
		(layer "In6.Cu")
	)
	(gr_line
		(start 164.8968 -9.363456)
		(end 164.846 -9.363456)
		(stroke
			(width 0.254)
			(type default)
		)
		(layer "In6.Cu")
	)
	(gr_line
		(start 164.8968 -7.458456)
		(end 164.8968 -9.363456)
		(stroke
			(width 0.254)
			(type default)
		)
		(layer "In6.Cu")
	)
	(gr_line
		(start 164.8968 -5.163312)
		(end 164.846 -5.163312)
		(stroke
			(width 0.254)
			(type default)
		)
		(layer "In6.Cu")
	)
	(gr_line
		(start 164.8968 -3.258312)
		(end 164.8968 -5.163312)
		(stroke
			(width 0.254)
			(type default)
		)
		(layer "In6.Cu")
	)
	(gr_line
		(start 164.9476 -13.4874)
		(end 164.9476 -11.5062)
		(stroke
			(width 0.762)
			(type default)
		)
		(layer "In6.Cu")
	)
	(gr_line
		(start 164.9476 -9.287256)
		(end 164.9476 -7.306056)
		(stroke
			(width 0.762)
			(type default)
		)
		(layer "In6.Cu")
	)
	(gr_line
		(start 164.9476 -5.087112)
		(end 164.9476 -3.105912)
		(stroke
			(width 0.762)
			(type default)
		)
		(layer "In6.Cu")
	)
	(gr_line
		(start 165.0238 -13.462)
		(end 164.7952 -13.462)
		(stroke
			(width 0.254)
			(type default)
		)
		(layer "In6.Cu")
	)
	(gr_line
		(start 165.0238 -11.5062)
		(end 165.0238 -13.462)
		(stroke
			(width 0.254)
			(type default)
		)
		(layer "In6.Cu")
	)
	(gr_line
		(start 165.0238 -9.261856)
		(end 164.7952 -9.261856)
		(stroke
			(width 0.254)
			(type default)
		)
		(layer "In6.Cu")
	)
	(gr_line
		(start 165.0238 -7.306056)
		(end 165.0238 -9.261856)
		(stroke
			(width 0.254)
			(type default)
		)
		(layer "In6.Cu")
	)
	(gr_line
		(start 165.0238 -5.061712)
		(end 164.7952 -5.061712)
		(stroke
			(width 0.254)
			(type default)
		)
		(layer "In6.Cu")
	)
	(gr_line
		(start 165.0238 -3.105912)
		(end 165.0238 -5.061712)
		(stroke
			(width 0.254)
			(type default)
		)
		(layer "In6.Cu")
	)
	(gr_line
		(start 165.0746 -13.8176)
		(end 165.0746 -13.7668)
		(stroke
			(width 0.1016)
			(type default)
		)
		(layer "In6.Cu")
	)
	(gr_line
		(start 165.0746 -13.8176)
		(end 165.481 -13.8176)
		(stroke
			(width 0.1016)
			(type default)
		)
		(layer "In6.Cu")
	)
	(gr_line
		(start 165.0746 -13.7668)
		(end 164.3126 -13.7668)
		(stroke
			(width 0.1016)
			(type default)
		)
		(layer "In6.Cu")
	)
	(gr_line
		(start 165.0746 -13.4874)
		(end 165.0746 -11.5062)
		(stroke
			(width 0.762)
			(type default)
		)
		(layer "In6.Cu")
	)
	(gr_line
		(start 165.0746 -9.617456)
		(end 165.0746 -9.566656)
		(stroke
			(width 0.1016)
			(type default)
		)
		(layer "In6.Cu")
	)
	(gr_line
		(start 165.0746 -9.617456)
		(end 165.481 -9.617456)
		(stroke
			(width 0.1016)
			(type default)
		)
		(layer "In6.Cu")
	)
	(gr_line
		(start 165.0746 -9.566656)
		(end 164.3126 -9.566656)
		(stroke
			(width 0.1016)
			(type default)
		)
		(layer "In6.Cu")
	)
	(gr_line
		(start 165.0746 -9.287256)
		(end 165.0746 -7.306056)
		(stroke
			(width 0.762)
			(type default)
		)
		(layer "In6.Cu")
	)
	(gr_line
		(start 165.0746 -5.417312)
		(end 165.0746 -5.366512)
		(stroke
			(width 0.1016)
			(type default)
		)
		(layer "In6.Cu")
	)
	(gr_line
		(start 165.0746 -5.417312)
		(end 165.481 -5.417312)
		(stroke
			(width 0.1016)
			(type default)
		)
		(layer "In6.Cu")
	)
	(gr_line
		(start 165.0746 -5.366512)
		(end 164.3126 -5.366512)
		(stroke
			(width 0.1016)
			(type default)
		)
		(layer "In6.Cu")
	)
	(gr_line
		(start 165.0746 -5.087112)
		(end 165.0746 -3.105912)
		(stroke
			(width 0.762)
			(type default)
		)
		(layer "In6.Cu")
	)
	(gr_line
		(start 165.1 -13.5382)
		(end 164.6936 -13.5382)
		(stroke
			(width 0.254)
			(type default)
		)
		(layer "In6.Cu")
	)
	(gr_line
		(start 165.1 -11.43)
		(end 165.1 -13.5382)
		(stroke
			(width 0.254)
			(type default)
		)
		(layer "In6.Cu")
	)
	(gr_line
		(start 165.1 -9.338056)
		(end 164.6936 -9.338056)
		(stroke
			(width 0.254)
			(type default)
		)
		(layer "In6.Cu")
	)
	(gr_line
		(start 165.1 -7.229856)
		(end 165.1 -9.338056)
		(stroke
			(width 0.254)
			(type default)
		)
		(layer "In6.Cu")
	)
	(gr_line
		(start 165.1 -5.137912)
		(end 164.6936 -5.137912)
		(stroke
			(width 0.254)
			(type default)
		)
		(layer "In6.Cu")
	)
	(gr_line
		(start 165.1 -3.029712)
		(end 165.1 -5.137912)
		(stroke
			(width 0.254)
			(type default)
		)
		(layer "In6.Cu")
	)
	(gr_line
		(start 165.1508 -13.4874)
		(end 165.1508 -11.5062)
		(stroke
			(width 0.762)
			(type default)
		)
		(layer "In6.Cu")
	)
	(gr_line
		(start 165.1508 -9.287256)
		(end 165.1508 -7.306056)
		(stroke
			(width 0.762)
			(type default)
		)
		(layer "In6.Cu")
	)
	(gr_line
		(start 165.1508 -5.087112)
		(end 165.1508 -3.105912)
		(stroke
			(width 0.762)
			(type default)
		)
		(layer "In6.Cu")
	)
	(gr_line
		(start 165.1762 -13.6144)
		(end 164.6174 -13.6144)
		(stroke
			(width 0.254)
			(type default)
		)
		(layer "In6.Cu")
	)
	(gr_line
		(start 165.1762 -11.3792)
		(end 165.1762 -13.6144)
		(stroke
			(width 0.254)
			(type default)
		)
		(layer "In6.Cu")
	)
	(gr_line
		(start 165.1762 -9.414256)
		(end 164.6174 -9.414256)
		(stroke
			(width 0.254)
			(type default)
		)
		(layer "In6.Cu")
	)
	(gr_line
		(start 165.1762 -7.179056)
		(end 165.1762 -9.414256)
		(stroke
			(width 0.254)
			(type default)
		)
		(layer "In6.Cu")
	)
	(gr_line
		(start 165.1762 -5.214112)
		(end 164.6174 -5.214112)
		(stroke
			(width 0.254)
			(type default)
		)
		(layer "In6.Cu")
	)
	(gr_line
		(start 165.1762 -2.978912)
		(end 165.1762 -5.214112)
		(stroke
			(width 0.254)
			(type default)
		)
		(layer "In6.Cu")
	)
	(gr_line
		(start 165.2524 -13.6398)
		(end 164.5412 -13.6398)
		(stroke
			(width 0.254)
			(type default)
		)
		(layer "In6.Cu")
	)
	(gr_line
		(start 165.2524 -11.303)
		(end 165.2524 -13.6398)
		(stroke
			(width 0.254)
			(type default)
		)
		(layer "In6.Cu")
	)
	(gr_line
		(start 165.2524 -9.439656)
		(end 164.5412 -9.439656)
		(stroke
			(width 0.254)
			(type default)
		)
		(layer "In6.Cu")
	)
	(gr_line
		(start 165.2524 -7.102856)
		(end 165.2524 -9.439656)
		(stroke
			(width 0.254)
			(type default)
		)
		(layer "In6.Cu")
	)
	(gr_line
		(start 165.2524 -5.239512)
		(end 164.5412 -5.239512)
		(stroke
			(width 0.254)
			(type default)
		)
		(layer "In6.Cu")
	)
	(gr_line
		(start 165.2524 -2.902712)
		(end 165.2524 -5.239512)
		(stroke
			(width 0.254)
			(type default)
		)
		(layer "In6.Cu")
	)
	(gr_line
		(start 165.2778 -13.7668)
		(end 164.2872 -13.7668)
		(stroke
			(width 0.1016)
			(type default)
		)
		(layer "In6.Cu")
	)
	(gr_line
		(start 165.2778 -13.6906)
		(end 164.465 -13.6906)
		(stroke
			(width 0.254)
			(type default)
		)
		(layer "In6.Cu")
	)
	(gr_line
		(start 165.2778 -11.2776)
		(end 165.2778 -13.6906)
		(stroke
			(width 0.254)
			(type default)
		)
		(layer "In6.Cu")
	)
	(gr_line
		(start 165.2778 -9.566656)
		(end 164.2872 -9.566656)
		(stroke
			(width 0.1016)
			(type default)
		)
		(layer "In6.Cu")
	)
	(gr_line
		(start 165.2778 -9.490456)
		(end 164.465 -9.490456)
		(stroke
			(width 0.254)
			(type default)
		)
		(layer "In6.Cu")
	)
	(gr_line
		(start 165.2778 -7.077456)
		(end 165.2778 -9.490456)
		(stroke
			(width 0.254)
			(type default)
		)
		(layer "In6.Cu")
	)
	(gr_line
		(start 165.2778 -5.366512)
		(end 164.2872 -5.366512)
		(stroke
			(width 0.1016)
			(type default)
		)
		(layer "In6.Cu")
	)
	(gr_line
		(start 165.2778 -5.290312)
		(end 164.465 -5.290312)
		(stroke
			(width 0.254)
			(type default)
		)
		(layer "In6.Cu")
	)
	(gr_line
		(start 165.2778 -2.877312)
		(end 165.2778 -5.290312)
		(stroke
			(width 0.254)
			(type default)
		)
		(layer "In6.Cu")
	)
	(gr_line
		(start 165.3032 -13.716)
		(end 164.4396 -13.716)
		(stroke
			(width 0.254)
			(type default)
		)
		(layer "In6.Cu")
	)
	(gr_line
		(start 165.3032 -11.2522)
		(end 165.3032 -13.716)
		(stroke
			(width 0.254)
			(type default)
		)
		(layer "In6.Cu")
	)
	(gr_line
		(start 165.3032 -9.515856)
		(end 164.4396 -9.515856)
		(stroke
			(width 0.254)
			(type default)
		)
		(layer "In6.Cu")
	)
	(gr_line
		(start 165.3032 -7.052056)
		(end 165.3032 -9.515856)
		(stroke
			(width 0.254)
			(type default)
		)
		(layer "In6.Cu")
	)
	(gr_line
		(start 165.3032 -5.315712)
		(end 164.4396 -5.315712)
		(stroke
			(width 0.254)
			(type default)
		)
		(layer "In6.Cu")
	)
	(gr_line
		(start 165.3032 -2.851912)
		(end 165.3032 -5.315712)
		(stroke
			(width 0.254)
			(type default)
		)
		(layer "In6.Cu")
	)
	(gr_line
		(start 165.354 -13.7414)
		(end 164.4142 -13.7414)
		(stroke
			(width 0.254)
			(type default)
		)
		(layer "In6.Cu")
	)
	(gr_line
		(start 165.354 -11.2522)
		(end 165.354 -13.7414)
		(stroke
			(width 0.254)
			(type default)
		)
		(layer "In6.Cu")
	)
	(gr_line
		(start 165.354 -9.541256)
		(end 164.4142 -9.541256)
		(stroke
			(width 0.254)
			(type default)
		)
		(layer "In6.Cu")
	)
	(gr_line
		(start 165.354 -7.052056)
		(end 165.354 -9.541256)
		(stroke
			(width 0.254)
			(type default)
		)
		(layer "In6.Cu")
	)
	(gr_line
		(start 165.354 -5.341112)
		(end 164.4142 -5.341112)
		(stroke
			(width 0.254)
			(type default)
		)
		(layer "In6.Cu")
	)
	(gr_line
		(start 165.354 -2.851912)
		(end 165.354 -5.341112)
		(stroke
			(width 0.254)
			(type default)
		)
		(layer "In6.Cu")
	)
	(gr_line
		(start 165.3794 -13.7414)
		(end 164.4142 -13.7414)
		(stroke
			(width 0.2032)
			(type default)
		)
		(layer "In6.Cu")
	)
	(gr_line
		(start 165.3794 -11.2014)
		(end 165.3794 -13.7414)
		(stroke
			(width 0.2032)
			(type default)
		)
		(layer "In6.Cu")
	)
	(gr_line
		(start 165.3794 -9.541256)
		(end 164.4142 -9.541256)
		(stroke
			(width 0.2032)
			(type default)
		)
		(layer "In6.Cu")
	)
	(gr_line
		(start 165.3794 -7.001256)
		(end 165.3794 -9.541256)
		(stroke
			(width 0.2032)
			(type default)
		)
		(layer "In6.Cu")
	)
	(gr_line
		(start 165.3794 -5.341112)
		(end 164.4142 -5.341112)
		(stroke
			(width 0.2032)
			(type default)
		)
		(layer "In6.Cu")
	)
	(gr_line
		(start 165.3794 -2.801112)
		(end 165.3794 -5.341112)
		(stroke
			(width 0.2032)
			(type default)
		)
		(layer "In6.Cu")
	)
	(gr_line
		(start 165.4302 -13.7668)
		(end 164.3634 -13.7668)
		(stroke
			(width 0.2032)
			(type default)
		)
		(layer "In6.Cu")
	)
	(gr_line
		(start 165.4302 -11.2014)
		(end 165.4302 -13.7668)
		(stroke
			(width 0.2032)
			(type default)
		)
		(layer "In6.Cu")
	)
	(gr_line
		(start 165.4302 -9.566656)
		(end 164.3634 -9.566656)
		(stroke
			(width 0.2032)
			(type default)
		)
		(layer "In6.Cu")
	)
	(gr_line
		(start 165.4302 -7.001256)
		(end 165.4302 -9.566656)
		(stroke
			(width 0.2032)
			(type default)
		)
		(layer "In6.Cu")
	)
	(gr_line
		(start 165.4302 -5.366512)
		(end 164.3634 -5.366512)
		(stroke
			(width 0.2032)
			(type default)
		)
		(layer "In6.Cu")
	)
	(gr_line
		(start 165.4302 -2.801112)
		(end 165.4302 -5.366512)
		(stroke
			(width 0.2032)
			(type default)
		)
		(layer "In6.Cu")
	)
	(gr_line
		(start 165.4556 -13.7668)
		(end 164.338 -13.7668)
		(stroke
			(width 0.1016)
			(type default)
		)
		(layer "In6.Cu")
	)
	(gr_line
		(start 165.4556 -11.176)
		(end 165.4556 -13.7668)
		(stroke
			(width 0.1016)
			(type default)
		)
		(layer "In6.Cu")
	)
	(gr_line
		(start 165.4556 -9.566656)
		(end 164.338 -9.566656)
		(stroke
			(width 0.1016)
			(type default)
		)
		(layer "In6.Cu")
	)
	(gr_line
		(start 165.4556 -6.975856)
		(end 165.4556 -9.566656)
		(stroke
			(width 0.1016)
			(type default)
		)
		(layer "In6.Cu")
	)
	(gr_line
		(start 165.4556 -5.366512)
		(end 164.338 -5.366512)
		(stroke
			(width 0.1016)
			(type default)
		)
		(layer "In6.Cu")
	)
	(gr_line
		(start 165.4556 -2.775712)
		(end 165.4556 -5.366512)
		(stroke
			(width 0.1016)
			(type default)
		)
		(layer "In6.Cu")
	)
	(gr_line
		(start 165.481 -13.8176)
		(end 165.0746 -13.8176)
		(stroke
			(width 0.1016)
			(type default)
		)
		(layer "In6.Cu")
	)
	(gr_line
		(start 165.481 -13.8176)
		(end 165.481 -11.1506)
		(stroke
			(width 0.1016)
			(type default)
		)
		(layer "In6.Cu")
	)
	(gr_line
		(start 165.481 -11.1506)
		(end 164.2872 -11.1506)
		(stroke
			(width 0.1016)
			(type default)
		)
		(layer "In6.Cu")
	)
	(gr_line
		(start 165.481 -11.1506)
		(end 165.481 -13.8176)
		(stroke
			(width 0.1016)
			(type default)
		)
		(layer "In6.Cu")
	)
	(gr_line
		(start 165.481 -9.617456)
		(end 165.0746 -9.617456)
		(stroke
			(width 0.1016)
			(type default)
		)
		(layer "In6.Cu")
	)
	(gr_line
		(start 165.481 -9.617456)
		(end 165.481 -6.950456)
		(stroke
			(width 0.1016)
			(type default)
		)
		(layer "In6.Cu")
	)
	(gr_line
		(start 165.481 -6.950456)
		(end 164.2872 -6.950456)
		(stroke
			(width 0.1016)
			(type default)
		)
		(layer "In6.Cu")
	)
	(gr_line
		(start 165.481 -6.950456)
		(end 165.481 -9.617456)
		(stroke
			(width 0.1016)
			(type default)
		)
		(layer "In6.Cu")
	)
	(gr_line
		(start 165.481 -5.417312)
		(end 165.0746 -5.417312)
		(stroke
			(width 0.1016)
			(type default)
		)
		(layer "In6.Cu")
	)
	(gr_line
		(start 165.481 -5.417312)
		(end 165.481 -2.750312)
		(stroke
			(width 0.1016)
			(type default)
		)
		(layer "In6.Cu")
	)
	(gr_line
		(start 165.481 -2.750312)
		(end 164.2872 -2.750312)
		(stroke
			(width 0.1016)
			(type default)
		)
		(layer "In6.Cu")
	)
	(gr_line
		(start 165.481 -2.750312)
		(end 165.481 -5.417312)
		(stroke
			(width 0.1016)
			(type default)
		)
		(layer "In6.Cu")
	)
	(gr_line
		(start 166.2176 -24.6634)
		(end 166.2176 -23.3934)
		(stroke
			(width 0.7874)
			(type default)
		)
		(layer "In6.Cu")
	)
	(gr_line
		(start 166.287196 -12.563348)
		(end 167.074596 -12.563348)
		(stroke
			(width 0.1016)
			(type default)
		)
		(layer "In6.Cu")
	)
	(gr_line
		(start 166.287196 -12.512548)
		(end 166.287196 -9.896348)
		(stroke
			(width 0.1016)
			(type default)
		)
		(layer "In6.Cu")
	)
	(gr_line
		(start 166.287196 -12.463272)
		(end 167.074596 -12.463272)
		(stroke
			(width 0.1016)
			(type default)
		)
		(layer "In6.Cu")
	)
	(gr_line
		(start 166.287196 -12.412472)
		(end 166.287196 -9.796272)
		(stroke
			(width 0.1016)
			(type default)
		)
		(layer "In6.Cu")
	)
	(gr_line
		(start 166.287196 -9.896348)
		(end 166.287196 -12.563348)
		(stroke
			(width 0.1016)
			(type default)
		)
		(layer "In6.Cu")
	)
	(gr_line
		(start 166.287196 -9.896348)
		(end 167.480996 -9.896348)
		(stroke
			(width 0.1016)
			(type default)
		)
		(layer "In6.Cu")
	)
	(gr_line
		(start 166.287196 -9.796272)
		(end 166.287196 -12.463272)
		(stroke
			(width 0.1016)
			(type default)
		)
		(layer "In6.Cu")
	)
	(gr_line
		(start 166.287196 -9.796272)
		(end 167.480996 -9.796272)
		(stroke
			(width 0.1016)
			(type default)
		)
		(layer "In6.Cu")
	)
	(gr_line
		(start 166.287196 -8.363204)
		(end 167.074596 -8.363204)
		(stroke
			(width 0.1016)
			(type default)
		)
		(layer "In6.Cu")
	)
	(gr_line
		(start 166.287196 -8.312404)
		(end 166.287196 -5.696204)
		(stroke
			(width 0.1016)
			(type default)
		)
		(layer "In6.Cu")
	)
	(gr_line
		(start 166.287196 -8.263128)
		(end 167.074596 -8.263128)
		(stroke
			(width 0.1016)
			(type default)
		)
		(layer "In6.Cu")
	)
	(gr_line
		(start 166.287196 -8.212328)
		(end 166.287196 -5.596128)
		(stroke
			(width 0.1016)
			(type default)
		)
		(layer "In6.Cu")
	)
	(gr_line
		(start 166.287196 -5.696204)
		(end 166.287196 -8.363204)
		(stroke
			(width 0.1016)
			(type default)
		)
		(layer "In6.Cu")
	)
	(gr_line
		(start 166.287196 -5.696204)
		(end 167.480996 -5.696204)
		(stroke
			(width 0.1016)
			(type default)
		)
		(layer "In6.Cu")
	)
	(gr_line
		(start 166.287196 -5.596128)
		(end 166.287196 -8.263128)
		(stroke
			(width 0.1016)
			(type default)
		)
		(layer "In6.Cu")
	)
	(gr_line
		(start 166.287196 -5.596128)
		(end 167.480996 -5.596128)
		(stroke
			(width 0.1016)
			(type default)
		)
		(layer "In6.Cu")
	)
	(gr_line
		(start 166.287196 -4.16306)
		(end 167.074596 -4.16306)
		(stroke
			(width 0.1016)
			(type default)
		)
		(layer "In6.Cu")
	)
	(gr_line
		(start 166.287196 -4.11226)
		(end 166.287196 -1.49606)
		(stroke
			(width 0.1016)
			(type default)
		)
		(layer "In6.Cu")
	)
	(gr_line
		(start 166.287196 -4.062984)
		(end 167.074596 -4.062984)
		(stroke
			(width 0.1016)
			(type default)
		)
		(layer "In6.Cu")
	)
	(gr_line
		(start 166.287196 -4.012184)
		(end 166.287196 -1.395984)
		(stroke
			(width 0.1016)
			(type default)
		)
		(layer "In6.Cu")
	)
	(gr_line
		(start 166.287196 -1.49606)
		(end 166.287196 -4.16306)
		(stroke
			(width 0.1016)
			(type default)
		)
		(layer "In6.Cu")
	)
	(gr_line
		(start 166.287196 -1.49606)
		(end 167.480996 -1.49606)
		(stroke
			(width 0.1016)
			(type default)
		)
		(layer "In6.Cu")
	)
	(gr_line
		(start 166.287196 -1.395984)
		(end 166.287196 -4.062984)
		(stroke
			(width 0.1016)
			(type default)
		)
		(layer "In6.Cu")
	)
	(gr_line
		(start 166.287196 -1.395984)
		(end 167.480996 -1.395984)
		(stroke
			(width 0.1016)
			(type default)
		)
		(layer "In6.Cu")
	)
	(gr_line
		(start 166.312596 -12.512548)
		(end 166.312596 -9.921748)
		(stroke
			(width 0.1016)
			(type default)
		)
		(layer "In6.Cu")
	)
	(gr_line
		(start 166.312596 -12.412472)
		(end 166.312596 -9.821672)
		(stroke
			(width 0.1016)
			(type default)
		)
		(layer "In6.Cu")
	)
	(gr_line
		(start 166.312596 -9.921748)
		(end 167.455596 -9.921748)
		(stroke
			(width 0.1016)
			(type default)
		)
		(layer "In6.Cu")
	)
	(gr_line
		(start 166.312596 -9.821672)
		(end 167.455596 -9.821672)
		(stroke
			(width 0.1016)
			(type default)
		)
		(layer "In6.Cu")
	)
	(gr_line
		(start 166.312596 -8.312404)
		(end 166.312596 -5.721604)
		(stroke
			(width 0.1016)
			(type default)
		)
		(layer "In6.Cu")
	)
	(gr_line
		(start 166.312596 -8.212328)
		(end 166.312596 -5.621528)
		(stroke
			(width 0.1016)
			(type default)
		)
		(layer "In6.Cu")
	)
	(gr_line
		(start 166.312596 -5.721604)
		(end 167.455596 -5.721604)
		(stroke
			(width 0.1016)
			(type default)
		)
		(layer "In6.Cu")
	)
	(gr_line
		(start 166.312596 -5.621528)
		(end 167.455596 -5.621528)
		(stroke
			(width 0.1016)
			(type default)
		)
		(layer "In6.Cu")
	)
	(gr_line
		(start 166.312596 -4.11226)
		(end 166.312596 -1.52146)
		(stroke
			(width 0.1016)
			(type default)
		)
		(layer "In6.Cu")
	)
	(gr_line
		(start 166.312596 -4.012184)
		(end 166.312596 -1.421384)
		(stroke
			(width 0.1016)
			(type default)
		)
		(layer "In6.Cu")
	)
	(gr_line
		(start 166.312596 -1.52146)
		(end 167.455596 -1.52146)
		(stroke
			(width 0.1016)
			(type default)
		)
		(layer "In6.Cu")
	)
	(gr_line
		(start 166.312596 -1.421384)
		(end 167.455596 -1.421384)
		(stroke
			(width 0.1016)
			(type default)
		)
		(layer "In6.Cu")
	)
	(gr_line
		(start 166.337996 -12.512548)
		(end 166.337996 -9.947148)
		(stroke
			(width 0.1016)
			(type default)
		)
		(layer "In6.Cu")
	)
	(gr_line
		(start 166.337996 -12.412472)
		(end 166.337996 -9.847072)
		(stroke
			(width 0.1016)
			(type default)
		)
		(layer "In6.Cu")
	)
	(gr_line
		(start 166.337996 -9.947148)
		(end 166.591996 -9.947148)
		(stroke
			(width 0.1016)
			(type default)
		)
		(layer "In6.Cu")
	)
	(gr_line
		(start 166.337996 -9.847072)
		(end 166.591996 -9.847072)
		(stroke
			(width 0.1016)
			(type default)
		)
		(layer "In6.Cu")
	)
	(gr_line
		(start 166.337996 -8.312404)
		(end 166.337996 -5.747004)
		(stroke
			(width 0.1016)
			(type default)
		)
		(layer "In6.Cu")
	)
	(gr_line
		(start 166.337996 -8.212328)
		(end 166.337996 -5.646928)
		(stroke
			(width 0.1016)
			(type default)
		)
		(layer "In6.Cu")
	)
	(gr_line
		(start 166.337996 -5.747004)
		(end 166.591996 -5.747004)
		(stroke
			(width 0.1016)
			(type default)
		)
		(layer "In6.Cu")
	)
	(gr_line
		(start 166.337996 -5.646928)
		(end 166.591996 -5.646928)
		(stroke
			(width 0.1016)
			(type default)
		)
		(layer "In6.Cu")
	)
	(gr_line
		(start 166.337996 -4.11226)
		(end 166.337996 -1.54686)
		(stroke
			(width 0.1016)
			(type default)
		)
		(layer "In6.Cu")
	)
	(gr_line
		(start 166.337996 -4.012184)
		(end 166.337996 -1.446784)
		(stroke
			(width 0.1016)
			(type default)
		)
		(layer "In6.Cu")
	)
	(gr_line
		(start 166.337996 -1.54686)
		(end 166.591996 -1.54686)
		(stroke
			(width 0.1016)
			(type default)
		)
		(layer "In6.Cu")
	)
	(gr_line
		(start 166.337996 -1.446784)
		(end 166.591996 -1.446784)
		(stroke
			(width 0.1016)
			(type default)
		)
		(layer "In6.Cu")
	)
	(gr_line
		(start 166.363396 -12.512548)
		(end 166.363396 -9.947148)
		(stroke
			(width 0.2032)
			(type default)
		)
		(layer "In6.Cu")
	)
	(gr_line
		(start 166.363396 -12.412472)
		(end 166.363396 -9.847072)
		(stroke
			(width 0.2032)
			(type default)
		)
		(layer "In6.Cu")
	)
	(gr_line
		(start 166.363396 -9.947148)
		(end 167.379396 -9.947148)
		(stroke
			(width 0.2032)
			(type default)
		)
		(layer "In6.Cu")
	)
	(gr_line
		(start 166.363396 -9.847072)
		(end 167.379396 -9.847072)
		(stroke
			(width 0.2032)
			(type default)
		)
		(layer "In6.Cu")
	)
	(gr_line
		(start 166.363396 -8.312404)
		(end 166.363396 -5.747004)
		(stroke
			(width 0.2032)
			(type default)
		)
		(layer "In6.Cu")
	)
	(gr_line
		(start 166.363396 -8.212328)
		(end 166.363396 -5.646928)
		(stroke
			(width 0.2032)
			(type default)
		)
		(layer "In6.Cu")
	)
	(gr_line
		(start 166.363396 -5.747004)
		(end 167.379396 -5.747004)
		(stroke
			(width 0.2032)
			(type default)
		)
		(layer "In6.Cu")
	)
	(gr_line
		(start 166.363396 -5.646928)
		(end 167.379396 -5.646928)
		(stroke
			(width 0.2032)
			(type default)
		)
		(layer "In6.Cu")
	)
	(gr_line
		(start 166.363396 -4.11226)
		(end 166.363396 -1.54686)
		(stroke
			(width 0.2032)
			(type default)
		)
		(layer "In6.Cu")
	)
	(gr_line
		(start 166.363396 -4.012184)
		(end 166.363396 -1.446784)
		(stroke
			(width 0.2032)
			(type default)
		)
		(layer "In6.Cu")
	)
	(gr_line
		(start 166.363396 -1.54686)
		(end 167.379396 -1.54686)
		(stroke
			(width 0.2032)
			(type default)
		)
		(layer "In6.Cu")
	)
	(gr_line
		(start 166.363396 -1.446784)
		(end 167.379396 -1.446784)
		(stroke
			(width 0.2032)
			(type default)
		)
		(layer "In6.Cu")
	)
	(gr_line
		(start 166.414196 -12.487148)
		(end 166.414196 -9.997948)
		(stroke
			(width 0.2032)
			(type default)
		)
		(layer "In6.Cu")
	)
	(gr_line
		(start 166.414196 -12.487148)
		(end 166.414196 -9.997948)
		(stroke
			(width 0.254)
			(type default)
		)
		(layer "In6.Cu")
	)
	(gr_line
		(start 166.414196 -12.387072)
		(end 166.414196 -9.897872)
		(stroke
			(width 0.2032)
			(type default)
		)
		(layer "In6.Cu")
	)
	(gr_line
		(start 166.414196 -12.387072)
		(end 166.414196 -9.897872)
		(stroke
			(width 0.254)
			(type default)
		)
		(layer "In6.Cu")
	)
	(gr_line
		(start 166.414196 -9.997948)
		(end 166.617396 -9.997948)
		(stroke
			(width 0.2032)
			(type default)
		)
		(layer "In6.Cu")
	)
	(gr_line
		(start 166.414196 -9.997948)
		(end 167.303196 -9.997948)
		(stroke
			(width 0.254)
			(type default)
		)
		(layer "In6.Cu")
	)
	(gr_line
		(start 166.414196 -9.897872)
		(end 166.617396 -9.897872)
		(stroke
			(width 0.2032)
			(type default)
		)
		(layer "In6.Cu")
	)
	(gr_line
		(start 166.414196 -9.897872)
		(end 167.303196 -9.897872)
		(stroke
			(width 0.254)
			(type default)
		)
		(layer "In6.Cu")
	)
	(gr_line
		(start 166.414196 -8.287004)
		(end 166.414196 -5.797804)
		(stroke
			(width 0.2032)
			(type default)
		)
		(layer "In6.Cu")
	)
	(gr_line
		(start 166.414196 -8.287004)
		(end 166.414196 -5.797804)
		(stroke
			(width 0.254)
			(type default)
		)
		(layer "In6.Cu")
	)
	(gr_line
		(start 166.414196 -8.186928)
		(end 166.414196 -5.697728)
		(stroke
			(width 0.2032)
			(type default)
		)
		(layer "In6.Cu")
	)
	(gr_line
		(start 166.414196 -8.186928)
		(end 166.414196 -5.697728)
		(stroke
			(width 0.254)
			(type default)
		)
		(layer "In6.Cu")
	)
	(gr_line
		(start 166.414196 -5.797804)
		(end 166.617396 -5.797804)
		(stroke
			(width 0.2032)
			(type default)
		)
		(layer "In6.Cu")
	)
	(gr_line
		(start 166.414196 -5.797804)
		(end 167.303196 -5.797804)
		(stroke
			(width 0.254)
			(type default)
		)
		(layer "In6.Cu")
	)
	(gr_line
		(start 166.414196 -5.697728)
		(end 166.617396 -5.697728)
		(stroke
			(width 0.2032)
			(type default)
		)
		(layer "In6.Cu")
	)
	(gr_line
		(start 166.414196 -5.697728)
		(end 167.303196 -5.697728)
		(stroke
			(width 0.254)
			(type default)
		)
		(layer "In6.Cu")
	)
	(gr_line
		(start 166.414196 -4.08686)
		(end 166.414196 -1.59766)
		(stroke
			(width 0.2032)
			(type default)
		)
		(layer "In6.Cu")
	)
	(gr_line
		(start 166.414196 -4.08686)
		(end 166.414196 -1.59766)
		(stroke
			(width 0.254)
			(type default)
		)
		(layer "In6.Cu")
	)
	(gr_line
		(start 166.414196 -3.986784)
		(end 166.414196 -1.497584)
		(stroke
			(width 0.2032)
			(type default)
		)
		(layer "In6.Cu")
	)
	(gr_line
		(start 166.414196 -3.986784)
		(end 166.414196 -1.497584)
		(stroke
			(width 0.254)
			(type default)
		)
		(layer "In6.Cu")
	)
	(gr_line
		(start 166.414196 -1.59766)
		(end 166.617396 -1.59766)
		(stroke
			(width 0.2032)
			(type default)
		)
		(layer "In6.Cu")
	)
	(gr_line
		(start 166.414196 -1.59766)
		(end 167.303196 -1.59766)
		(stroke
			(width 0.254)
			(type default)
		)
		(layer "In6.Cu")
	)
	(gr_line
		(start 166.414196 -1.497584)
		(end 166.617396 -1.497584)
		(stroke
			(width 0.2032)
			(type default)
		)
		(layer "In6.Cu")
	)
	(gr_line
		(start 166.414196 -1.497584)
		(end 167.303196 -1.497584)
		(stroke
			(width 0.254)
			(type default)
		)
		(layer "In6.Cu")
	)
	(gr_line
		(start 166.439596 -12.461748)
		(end 166.439596 -10.023348)
		(stroke
			(width 0.254)
			(type default)
		)
		(layer "In6.Cu")
	)
	(gr_line
		(start 166.439596 -12.361672)
		(end 166.439596 -9.923272)
		(stroke
			(width 0.254)
			(type default)
		)
		(layer "In6.Cu")
	)
	(gr_line
		(start 166.439596 -10.023348)
		(end 167.277796 -10.023348)
		(stroke
			(width 0.254)
			(type default)
		)
		(layer "In6.Cu")
	)
	(gr_line
		(start 166.439596 -9.923272)
		(end 167.277796 -9.923272)
		(stroke
			(width 0.254)
			(type default)
		)
		(layer "In6.Cu")
	)
	(gr_line
		(start 166.439596 -8.261604)
		(end 166.439596 -5.823204)
		(stroke
			(width 0.254)
			(type default)
		)
		(layer "In6.Cu")
	)
	(gr_line
		(start 166.439596 -8.161528)
		(end 166.439596 -5.723128)
		(stroke
			(width 0.254)
			(type default)
		)
		(layer "In6.Cu")
	)
	(gr_line
		(start 166.439596 -5.823204)
		(end 167.277796 -5.823204)
		(stroke
			(width 0.254)
			(type default)
		)
		(layer "In6.Cu")
	)
	(gr_line
		(start 166.439596 -5.723128)
		(end 167.277796 -5.723128)
		(stroke
			(width 0.254)
			(type default)
		)
		(layer "In6.Cu")
	)
	(gr_line
		(start 166.439596 -4.06146)
		(end 166.439596 -1.62306)
		(stroke
			(width 0.254)
			(type default)
		)
		(layer "In6.Cu")
	)
	(gr_line
		(start 166.439596 -3.961384)
		(end 166.439596 -1.522984)
		(stroke
			(width 0.254)
			(type default)
		)
		(layer "In6.Cu")
	)
	(gr_line
		(start 166.439596 -1.62306)
		(end 167.277796 -1.62306)
		(stroke
			(width 0.254)
			(type default)
		)
		(layer "In6.Cu")
	)
	(gr_line
		(start 166.439596 -1.522984)
		(end 167.277796 -1.522984)
		(stroke
			(width 0.254)
			(type default)
		)
		(layer "In6.Cu")
	)
	(gr_line
		(start 166.464996 -12.436348)
		(end 166.464996 -10.048748)
		(stroke
			(width 0.254)
			(type default)
		)
		(layer "In6.Cu")
	)
	(gr_line
		(start 166.464996 -12.336272)
		(end 166.464996 -9.948672)
		(stroke
			(width 0.254)
			(type default)
		)
		(layer "In6.Cu")
	)
	(gr_line
		(start 166.464996 -10.048748)
		(end 167.252396 -10.048748)
		(stroke
			(width 0.254)
			(type default)
		)
		(layer "In6.Cu")
	)
	(gr_line
		(start 166.464996 -9.948672)
		(end 167.252396 -9.948672)
		(stroke
			(width 0.254)
			(type default)
		)
		(layer "In6.Cu")
	)
	(gr_line
		(start 166.464996 -8.236204)
		(end 166.464996 -5.848604)
		(stroke
			(width 0.254)
			(type default)
		)
		(layer "In6.Cu")
	)
	(gr_line
		(start 166.464996 -8.136128)
		(end 166.464996 -5.748528)
		(stroke
			(width 0.254)
			(type default)
		)
		(layer "In6.Cu")
	)
	(gr_line
		(start 166.464996 -5.848604)
		(end 167.252396 -5.848604)
		(stroke
			(width 0.254)
			(type default)
		)
		(layer "In6.Cu")
	)
	(gr_line
		(start 166.464996 -5.748528)
		(end 167.252396 -5.748528)
		(stroke
			(width 0.254)
			(type default)
		)
		(layer "In6.Cu")
	)
	(gr_line
		(start 166.464996 -4.03606)
		(end 166.464996 -1.64846)
		(stroke
			(width 0.254)
			(type default)
		)
		(layer "In6.Cu")
	)
	(gr_line
		(start 166.464996 -3.935984)
		(end 166.464996 -1.548384)
		(stroke
			(width 0.254)
			(type default)
		)
		(layer "In6.Cu")
	)
	(gr_line
		(start 166.464996 -1.64846)
		(end 167.252396 -1.64846)
		(stroke
			(width 0.254)
			(type default)
		)
		(layer "In6.Cu")
	)
	(gr_line
		(start 166.464996 -1.548384)
		(end 167.252396 -1.548384)
		(stroke
			(width 0.254)
			(type default)
		)
		(layer "In6.Cu")
	)
	(gr_line
		(start 166.490396 -12.360148)
		(end 167.125396 -12.360148)
		(stroke
			(width 0.508)
			(type default)
		)
		(layer "In6.Cu")
	)
	(gr_line
		(start 166.490396 -12.260072)
		(end 167.125396 -12.260072)
		(stroke
			(width 0.508)
			(type default)
		)
		(layer "In6.Cu")
	)
	(gr_line
		(start 166.490396 -10.175748)
		(end 167.125396 -10.175748)
		(stroke
			(width 0.508)
			(type default)
		)
		(layer "In6.Cu")
	)
	(gr_line
		(start 166.490396 -10.124948)
		(end 167.125396 -10.124948)
		(stroke
			(width 0.508)
			(type default)
		)
		(layer "In6.Cu")
	)
	(gr_line
		(start 166.490396 -10.075672)
		(end 167.125396 -10.075672)
		(stroke
			(width 0.508)
			(type default)
		)
		(layer "In6.Cu")
	)
	(gr_line
		(start 166.490396 -10.024872)
		(end 167.125396 -10.024872)
		(stroke
			(width 0.508)
			(type default)
		)
		(layer "In6.Cu")
	)
	(gr_line
		(start 166.490396 -8.160004)
		(end 167.125396 -8.160004)
		(stroke
			(width 0.508)
			(type default)
		)
		(layer "In6.Cu")
	)
	(gr_line
		(start 166.490396 -8.059928)
		(end 167.125396 -8.059928)
		(stroke
			(width 0.508)
			(type default)
		)
		(layer "In6.Cu")
	)
	(gr_line
		(start 166.490396 -5.975604)
		(end 167.125396 -5.975604)
		(stroke
			(width 0.508)
			(type default)
		)
		(layer "In6.Cu")
	)
	(gr_line
		(start 166.490396 -5.924804)
		(end 167.125396 -5.924804)
		(stroke
			(width 0.508)
			(type default)
		)
		(layer "In6.Cu")
	)
	(gr_line
		(start 166.490396 -5.875528)
		(end 167.125396 -5.875528)
		(stroke
			(width 0.508)
			(type default)
		)
		(layer "In6.Cu")
	)
	(gr_line
		(start 166.490396 -5.824728)
		(end 167.125396 -5.824728)
		(stroke
			(width 0.508)
			(type default)
		)
		(layer "In6.Cu")
	)
	(gr_line
		(start 166.490396 -3.95986)
		(end 167.125396 -3.95986)
		(stroke
			(width 0.508)
			(type default)
		)
		(layer "In6.Cu")
	)
	(gr_line
		(start 166.490396 -3.859784)
		(end 167.125396 -3.859784)
		(stroke
			(width 0.508)
			(type default)
		)
		(layer "In6.Cu")
	)
	(gr_line
		(start 166.490396 -1.77546)
		(end 167.125396 -1.77546)
		(stroke
			(width 0.508)
			(type default)
		)
		(layer "In6.Cu")
	)
	(gr_line
		(start 166.490396 -1.72466)
		(end 167.125396 -1.72466)
		(stroke
			(width 0.508)
			(type default)
		)
		(layer "In6.Cu")
	)
	(gr_line
		(start 166.490396 -1.675384)
		(end 167.125396 -1.675384)
		(stroke
			(width 0.508)
			(type default)
		)
		(layer "In6.Cu")
	)
	(gr_line
		(start 166.490396 -1.624584)
		(end 167.125396 -1.624584)
		(stroke
			(width 0.508)
			(type default)
		)
		(layer "In6.Cu")
	)
	(gr_line
		(start 166.515796 -10.429748)
		(end 167.150796 -10.429748)
		(stroke
			(width 0.508)
			(type default)
		)
		(layer "In6.Cu")
	)
	(gr_line
		(start 166.515796 -10.329672)
		(end 167.150796 -10.329672)
		(stroke
			(width 0.508)
			(type default)
		)
		(layer "In6.Cu")
	)
	(gr_line
		(start 166.515796 -6.229604)
		(end 167.150796 -6.229604)
		(stroke
			(width 0.508)
			(type default)
		)
		(layer "In6.Cu")
	)
	(gr_line
		(start 166.515796 -6.129528)
		(end 167.150796 -6.129528)
		(stroke
			(width 0.508)
			(type default)
		)
		(layer "In6.Cu")
	)
	(gr_line
		(start 166.515796 -2.02946)
		(end 167.150796 -2.02946)
		(stroke
			(width 0.508)
			(type default)
		)
		(layer "In6.Cu")
	)
	(gr_line
		(start 166.515796 -1.929384)
		(end 167.150796 -1.929384)
		(stroke
			(width 0.508)
			(type default)
		)
		(layer "In6.Cu")
	)
	(gr_line
		(start 166.541196 -12.385548)
		(end 166.541196 -10.124948)
		(stroke
			(width 0.254)
			(type default)
		)
		(layer "In6.Cu")
	)
	(gr_line
		(start 166.541196 -12.285472)
		(end 166.541196 -10.024872)
		(stroke
			(width 0.254)
			(type default)
		)
		(layer "In6.Cu")
	)
	(gr_line
		(start 166.541196 -12.233148)
		(end 167.176196 -12.233148)
		(stroke
			(width 0.508)
			(type default)
		)
		(layer "In6.Cu")
	)
	(gr_line
		(start 166.541196 -12.133072)
		(end 167.176196 -12.133072)
		(stroke
			(width 0.508)
			(type default)
		)
		(layer "In6.Cu")
	)
	(gr_line
		(start 166.541196 -10.124948)
		(end 167.176196 -10.124948)
		(stroke
			(width 0.254)
			(type default)
		)
		(layer "In6.Cu")
	)
	(gr_line
		(start 166.541196 -10.024872)
		(end 167.176196 -10.024872)
		(stroke
			(width 0.254)
			(type default)
		)
		(layer "In6.Cu")
	)
	(gr_line
		(start 166.541196 -8.185404)
		(end 166.541196 -5.924804)
		(stroke
			(width 0.254)
			(type default)
		)
		(layer "In6.Cu")
	)
	(gr_line
		(start 166.541196 -8.085328)
		(end 166.541196 -5.824728)
		(stroke
			(width 0.254)
			(type default)
		)
		(layer "In6.Cu")
	)
	(gr_line
		(start 166.541196 -8.033004)
		(end 167.176196 -8.033004)
		(stroke
			(width 0.508)
			(type default)
		)
		(layer "In6.Cu")
	)
	(gr_line
		(start 166.541196 -7.932928)
		(end 167.176196 -7.932928)
		(stroke
			(width 0.508)
			(type default)
		)
		(layer "In6.Cu")
	)
	(gr_line
		(start 166.541196 -5.924804)
		(end 167.176196 -5.924804)
		(stroke
			(width 0.254)
			(type default)
		)
		(layer "In6.Cu")
	)
	(gr_line
		(start 166.541196 -5.824728)
		(end 167.176196 -5.824728)
		(stroke
			(width 0.254)
			(type default)
		)
		(layer "In6.Cu")
	)
	(gr_line
		(start 166.541196 -3.98526)
		(end 166.541196 -1.72466)
		(stroke
			(width 0.254)
			(type default)
		)
		(layer "In6.Cu")
	)
	(gr_line
		(start 166.541196 -3.885184)
		(end 166.541196 -1.624584)
		(stroke
			(width 0.254)
			(type default)
		)
		(layer "In6.Cu")
	)
	(gr_line
		(start 166.541196 -3.83286)
		(end 167.176196 -3.83286)
		(stroke
			(width 0.508)
			(type default)
		)
		(layer "In6.Cu")
	)
	(gr_line
		(start 166.541196 -3.732784)
		(end 167.176196 -3.732784)
		(stroke
			(width 0.508)
			(type default)
		)
		(layer "In6.Cu")
	)
	(gr_line
		(start 166.541196 -1.72466)
		(end 167.176196 -1.72466)
		(stroke
			(width 0.254)
			(type default)
		)
		(layer "In6.Cu")
	)
	(gr_line
		(start 166.541196 -1.624584)
		(end 167.176196 -1.624584)
		(stroke
			(width 0.254)
			(type default)
		)
		(layer "In6.Cu")
	)
	(gr_line
		(start 166.566596 -12.080748)
		(end 167.201596 -12.080748)
		(stroke
			(width 0.508)
			(type default)
		)
		(layer "In6.Cu")
	)
	(gr_line
		(start 166.566596 -11.980672)
		(end 167.201596 -11.980672)
		(stroke
			(width 0.508)
			(type default)
		)
		(layer "In6.Cu")
	)
	(gr_line
		(start 166.566596 -7.880604)
		(end 167.201596 -7.880604)
		(stroke
			(width 0.508)
			(type default)
		)
		(layer "In6.Cu")
	)
	(gr_line
		(start 166.566596 -7.780528)
		(end 167.201596 -7.780528)
		(stroke
			(width 0.508)
			(type default)
		)
		(layer "In6.Cu")
	)
	(gr_line
		(start 166.566596 -3.68046)
		(end 167.201596 -3.68046)
		(stroke
			(width 0.508)
			(type default)
		)
		(layer "In6.Cu")
	)
	(gr_line
		(start 166.566596 -3.580384)
		(end 167.201596 -3.580384)
		(stroke
			(width 0.508)
			(type default)
		)
		(layer "In6.Cu")
	)
	(gr_line
		(start 166.591996 -12.360148)
		(end 167.226996 -12.360148)
		(stroke
			(width 0.508)
			(type default)
		)
		(layer "In6.Cu")
	)
	(gr_line
		(start 166.591996 -12.260072)
		(end 167.226996 -12.260072)
		(stroke
			(width 0.508)
			(type default)
		)
		(layer "In6.Cu")
	)
	(gr_line
		(start 166.591996 -9.947148)
		(end 167.430196 -9.947148)
		(stroke
			(width 0.2032)
			(type default)
		)
		(layer "In6.Cu")
	)
	(gr_line
		(start 166.591996 -9.847072)
		(end 167.430196 -9.847072)
		(stroke
			(width 0.2032)
			(type default)
		)
		(layer "In6.Cu")
	)
	(gr_line
		(start 166.591996 -8.160004)
		(end 167.226996 -8.160004)
		(stroke
			(width 0.508)
			(type default)
		)
		(layer "In6.Cu")
	)
	(gr_line
		(start 166.591996 -8.059928)
		(end 167.226996 -8.059928)
		(stroke
			(width 0.508)
			(type default)
		)
		(layer "In6.Cu")
	)
	(gr_line
		(start 166.591996 -5.747004)
		(end 167.430196 -5.747004)
		(stroke
			(width 0.2032)
			(type default)
		)
		(layer "In6.Cu")
	)
	(gr_line
		(start 166.591996 -5.646928)
		(end 167.430196 -5.646928)
		(stroke
			(width 0.2032)
			(type default)
		)
		(layer "In6.Cu")
	)
	(gr_line
		(start 166.591996 -3.95986)
		(end 167.226996 -3.95986)
		(stroke
			(width 0.508)
			(type default)
		)
		(layer "In6.Cu")
	)
	(gr_line
		(start 166.591996 -3.859784)
		(end 167.226996 -3.859784)
		(stroke
			(width 0.508)
			(type default)
		)
		(layer "In6.Cu")
	)
	(gr_line
		(start 166.591996 -1.54686)
		(end 167.430196 -1.54686)
		(stroke
			(width 0.2032)
			(type default)
		)
		(layer "In6.Cu")
	)
	(gr_line
		(start 166.591996 -1.446784)
		(end 167.430196 -1.446784)
		(stroke
			(width 0.2032)
			(type default)
		)
		(layer "In6.Cu")
	)
	(gr_line
		(start 166.617396 -12.360148)
		(end 166.617396 -10.175748)
		(stroke
			(width 0.254)
			(type default)
		)
		(layer "In6.Cu")
	)
	(gr_line
		(start 166.617396 -12.260072)
		(end 166.617396 -10.075672)
		(stroke
			(width 0.254)
			(type default)
		)
		(layer "In6.Cu")
	)
	(gr_line
		(start 166.617396 -10.175748)
		(end 167.099996 -10.175748)
		(stroke
			(width 0.254)
			(type default)
		)
		(layer "In6.Cu")
	)
	(gr_line
		(start 166.617396 -10.075672)
		(end 167.099996 -10.075672)
		(stroke
			(width 0.254)
			(type default)
		)
		(layer "In6.Cu")
	)
	(gr_line
		(start 166.617396 -9.997948)
		(end 167.353996 -9.997948)
		(stroke
			(width 0.254)
			(type default)
		)
		(layer "In6.Cu")
	)
	(gr_line
		(start 166.617396 -9.897872)
		(end 167.353996 -9.897872)
		(stroke
			(width 0.254)
			(type default)
		)
		(layer "In6.Cu")
	)
	(gr_line
		(start 166.617396 -8.160004)
		(end 166.617396 -5.975604)
		(stroke
			(width 0.254)
			(type default)
		)
		(layer "In6.Cu")
	)
	(gr_line
		(start 166.617396 -8.059928)
		(end 166.617396 -5.875528)
		(stroke
			(width 0.254)
			(type default)
		)
		(layer "In6.Cu")
	)
	(gr_line
		(start 166.617396 -5.975604)
		(end 167.099996 -5.975604)
		(stroke
			(width 0.254)
			(type default)
		)
		(layer "In6.Cu")
	)
	(gr_line
		(start 166.617396 -5.875528)
		(end 167.099996 -5.875528)
		(stroke
			(width 0.254)
			(type default)
		)
		(layer "In6.Cu")
	)
	(gr_line
		(start 166.617396 -5.797804)
		(end 167.353996 -5.797804)
		(stroke
			(width 0.254)
			(type default)
		)
		(layer "In6.Cu")
	)
	(gr_line
		(start 166.617396 -5.697728)
		(end 167.353996 -5.697728)
		(stroke
			(width 0.254)
			(type default)
		)
		(layer "In6.Cu")
	)
	(gr_line
		(start 166.617396 -3.95986)
		(end 166.617396 -1.77546)
		(stroke
			(width 0.254)
			(type default)
		)
		(layer "In6.Cu")
	)
	(gr_line
		(start 166.617396 -3.859784)
		(end 166.617396 -1.675384)
		(stroke
			(width 0.254)
			(type default)
		)
		(layer "In6.Cu")
	)
	(gr_line
		(start 166.617396 -1.77546)
		(end 167.099996 -1.77546)
		(stroke
			(width 0.254)
			(type default)
		)
		(layer "In6.Cu")
	)
	(gr_line
		(start 166.617396 -1.675384)
		(end 167.099996 -1.675384)
		(stroke
			(width 0.254)
			(type default)
		)
		(layer "In6.Cu")
	)
	(gr_line
		(start 166.617396 -1.59766)
		(end 167.353996 -1.59766)
		(stroke
			(width 0.254)
			(type default)
		)
		(layer "In6.Cu")
	)
	(gr_line
		(start 166.617396 -1.497584)
		(end 167.353996 -1.497584)
		(stroke
			(width 0.254)
			(type default)
		)
		(layer "In6.Cu")
	)
	(gr_line
		(start 166.635938 -10.110978)
		(end 167.270938 -10.110978)
		(stroke
			(width 0.508)
			(type default)
		)
		(layer "In6.Cu")
	)
	(gr_line
		(start 166.635938 -10.010902)
		(end 167.270938 -10.010902)
		(stroke
			(width 0.508)
			(type default)
		)
		(layer "In6.Cu")
	)
	(gr_line
		(start 166.635938 -5.910834)
		(end 167.270938 -5.910834)
		(stroke
			(width 0.508)
			(type default)
		)
		(layer "In6.Cu")
	)
	(gr_line
		(start 166.635938 -5.810758)
		(end 167.270938 -5.810758)
		(stroke
			(width 0.508)
			(type default)
		)
		(layer "In6.Cu")
	)
	(gr_line
		(start 166.635938 -1.71069)
		(end 167.270938 -1.71069)
		(stroke
			(width 0.508)
			(type default)
		)
		(layer "In6.Cu")
	)
	(gr_line
		(start 166.635938 -1.610614)
		(end 167.270938 -1.610614)
		(stroke
			(width 0.508)
			(type default)
		)
		(layer "In6.Cu")
	)
	(gr_line
		(start 166.642796 -12.360148)
		(end 167.277796 -12.360148)
		(stroke
			(width 0.508)
			(type default)
		)
		(layer "In6.Cu")
	)
	(gr_line
		(start 166.642796 -12.260072)
		(end 167.277796 -12.260072)
		(stroke
			(width 0.508)
			(type default)
		)
		(layer "In6.Cu")
	)
	(gr_line
		(start 166.642796 -12.233148)
		(end 166.642796 -10.251948)
		(stroke
			(width 0.762)
			(type default)
		)
		(layer "In6.Cu")
	)
	(gr_line
		(start 166.642796 -12.133072)
		(end 166.642796 -10.151872)
		(stroke
			(width 0.762)
			(type default)
		)
		(layer "In6.Cu")
	)
	(gr_line
		(start 166.642796 -10.251948)
		(end 167.277796 -10.251948)
		(stroke
			(width 0.508)
			(type default)
		)
		(layer "In6.Cu")
	)
	(gr_line
		(start 166.642796 -10.151872)
		(end 167.277796 -10.151872)
		(stroke
			(width 0.508)
			(type default)
		)
		(layer "In6.Cu")
	)
	(gr_line
		(start 166.642796 -8.160004)
		(end 167.277796 -8.160004)
		(stroke
			(width 0.508)
			(type default)
		)
		(layer "In6.Cu")
	)
	(gr_line
		(start 166.642796 -8.059928)
		(end 167.277796 -8.059928)
		(stroke
			(width 0.508)
			(type default)
		)
		(layer "In6.Cu")
	)
	(gr_line
		(start 166.642796 -8.033004)
		(end 166.642796 -6.051804)
		(stroke
			(width 0.762)
			(type default)
		)
		(layer "In6.Cu")
	)
	(gr_line
		(start 166.642796 -7.932928)
		(end 166.642796 -5.951728)
		(stroke
			(width 0.762)
			(type default)
		)
		(layer "In6.Cu")
	)
	(gr_line
		(start 166.642796 -6.051804)
		(end 167.277796 -6.051804)
		(stroke
			(width 0.508)
			(type default)
		)
		(layer "In6.Cu")
	)
	(gr_line
		(start 166.642796 -5.951728)
		(end 167.277796 -5.951728)
		(stroke
			(width 0.508)
			(type default)
		)
		(layer "In6.Cu")
	)
	(gr_line
		(start 166.642796 -3.95986)
		(end 167.277796 -3.95986)
		(stroke
			(width 0.508)
			(type default)
		)
		(layer "In6.Cu")
	)
	(gr_line
		(start 166.642796 -3.859784)
		(end 167.277796 -3.859784)
		(stroke
			(width 0.508)
			(type default)
		)
		(layer "In6.Cu")
	)
	(gr_line
		(start 166.642796 -3.83286)
		(end 166.642796 -1.85166)
		(stroke
			(width 0.762)
			(type default)
		)
		(layer "In6.Cu")
	)
	(gr_line
		(start 166.642796 -3.732784)
		(end 166.642796 -1.751584)
		(stroke
			(width 0.762)
			(type default)
		)
		(layer "In6.Cu")
	)
	(gr_line
		(start 166.642796 -1.85166)
		(end 167.277796 -1.85166)
		(stroke
			(width 0.508)
			(type default)
		)
		(layer "In6.Cu")
	)
	(gr_line
		(start 166.642796 -1.751584)
		(end 167.277796 -1.751584)
		(stroke
			(width 0.508)
			(type default)
		)
		(layer "In6.Cu")
	)
	(gr_line
		(start 166.693596 -12.283948)
		(end 166.693596 -10.251948)
		(stroke
			(width 0.254)
			(type default)
		)
		(layer "In6.Cu")
	)
	(gr_line
		(start 166.693596 -12.183872)
		(end 166.693596 -10.151872)
		(stroke
			(width 0.254)
			(type default)
		)
		(layer "In6.Cu")
	)
	(gr_line
		(start 166.693596 -10.251948)
		(end 167.023796 -10.251948)
		(stroke
			(width 0.254)
			(type default)
		)
		(layer "In6.Cu")
	)
	(gr_line
		(start 166.693596 -10.151872)
		(end 167.023796 -10.151872)
		(stroke
			(width 0.254)
			(type default)
		)
		(layer "In6.Cu")
	)
	(gr_line
		(start 166.693596 -8.083804)
		(end 166.693596 -6.051804)
		(stroke
			(width 0.254)
			(type default)
		)
		(layer "In6.Cu")
	)
	(gr_line
		(start 166.693596 -7.983728)
		(end 166.693596 -5.951728)
		(stroke
			(width 0.254)
			(type default)
		)
		(layer "In6.Cu")
	)
	(gr_line
		(start 166.693596 -6.051804)
		(end 167.023796 -6.051804)
		(stroke
			(width 0.254)
			(type default)
		)
		(layer "In6.Cu")
	)
	(gr_line
		(start 166.693596 -5.951728)
		(end 167.023796 -5.951728)
		(stroke
			(width 0.254)
			(type default)
		)
		(layer "In6.Cu")
	)
	(gr_line
		(start 166.693596 -3.88366)
		(end 166.693596 -1.85166)
		(stroke
			(width 0.254)
			(type default)
		)
		(layer "In6.Cu")
	)
	(gr_line
		(start 166.693596 -3.783584)
		(end 166.693596 -1.751584)
		(stroke
			(width 0.254)
			(type default)
		)
		(layer "In6.Cu")
	)
	(gr_line
		(start 166.693596 -1.85166)
		(end 167.023796 -1.85166)
		(stroke
			(width 0.254)
			(type default)
		)
		(layer "In6.Cu")
	)
	(gr_line
		(start 166.693596 -1.751584)
		(end 167.023796 -1.751584)
		(stroke
			(width 0.254)
			(type default)
		)
		(layer "In6.Cu")
	)
	(gr_line
		(start 166.795196 -12.207748)
		(end 166.795196 -10.404348)
		(stroke
			(width 0.254)
			(type default)
		)
		(layer "In6.Cu")
	)
	(gr_line
		(start 166.795196 -12.207748)
		(end 166.795196 -10.226548)
		(stroke
			(width 0.762)
			(type default)
		)
		(layer "In6.Cu")
	)
	(gr_line
		(start 166.795196 -12.107672)
		(end 166.795196 -10.304272)
		(stroke
			(width 0.254)
			(type default)
		)
		(layer "In6.Cu")
	)
	(gr_line
		(start 166.795196 -12.107672)
		(end 166.795196 -10.126472)
		(stroke
			(width 0.762)
			(type default)
		)
		(layer "In6.Cu")
	)
	(gr_line
		(start 166.795196 -10.404348)
		(end 166.896796 -10.404348)
		(stroke
			(width 0.254)
			(type default)
		)
		(layer "In6.Cu")
	)
	(gr_line
		(start 166.795196 -10.304272)
		(end 166.896796 -10.304272)
		(stroke
			(width 0.254)
			(type default)
		)
		(layer "In6.Cu")
	)
	(gr_line
		(start 166.795196 -8.007604)
		(end 166.795196 -6.204204)
		(stroke
			(width 0.254)
			(type default)
		)
		(layer "In6.Cu")
	)
	(gr_line
		(start 166.795196 -8.007604)
		(end 166.795196 -6.026404)
		(stroke
			(width 0.762)
			(type default)
		)
		(layer "In6.Cu")
	)
	(gr_line
		(start 166.795196 -7.907528)
		(end 166.795196 -6.104128)
		(stroke
			(width 0.254)
			(type default)
		)
		(layer "In6.Cu")
	)
	(gr_line
		(start 166.795196 -7.907528)
		(end 166.795196 -5.926328)
		(stroke
			(width 0.762)
			(type default)
		)
		(layer "In6.Cu")
	)
	(gr_line
		(start 166.795196 -6.204204)
		(end 166.896796 -6.204204)
		(stroke
			(width 0.254)
			(type default)
		)
		(layer "In6.Cu")
	)
	(gr_line
		(start 166.795196 -6.104128)
		(end 166.896796 -6.104128)
		(stroke
			(width 0.254)
			(type default)
		)
		(layer "In6.Cu")
	)
	(gr_line
		(start 166.795196 -3.80746)
		(end 166.795196 -2.00406)
		(stroke
			(width 0.254)
			(type default)
		)
		(layer "In6.Cu")
	)
	(gr_line
		(start 166.795196 -3.80746)
		(end 166.795196 -1.82626)
		(stroke
			(width 0.762)
			(type default)
		)
		(layer "In6.Cu")
	)
	(gr_line
		(start 166.795196 -3.707384)
		(end 166.795196 -1.903984)
		(stroke
			(width 0.254)
			(type default)
		)
		(layer "In6.Cu")
	)
	(gr_line
		(start 166.795196 -3.707384)
		(end 166.795196 -1.726184)
		(stroke
			(width 0.762)
			(type default)
		)
		(layer "In6.Cu")
	)
	(gr_line
		(start 166.795196 -2.00406)
		(end 166.896796 -2.00406)
		(stroke
			(width 0.254)
			(type default)
		)
		(layer "In6.Cu")
	)
	(gr_line
		(start 166.795196 -1.903984)
		(end 166.896796 -1.903984)
		(stroke
			(width 0.254)
			(type default)
		)
		(layer "In6.Cu")
	)
	(gr_line
		(start 166.896796 -12.309348)
		(end 166.845996 -12.309348)
		(stroke
			(width 0.254)
			(type default)
		)
		(layer "In6.Cu")
	)
	(gr_line
		(start 166.896796 -12.209272)
		(end 166.845996 -12.209272)
		(stroke
			(width 0.254)
			(type default)
		)
		(layer "In6.Cu")
	)
	(gr_line
		(start 166.896796 -10.404348)
		(end 166.896796 -12.309348)
		(stroke
			(width 0.254)
			(type default)
		)
		(layer "In6.Cu")
	)
	(gr_line
		(start 166.896796 -10.304272)
		(end 166.896796 -12.209272)
		(stroke
			(width 0.254)
			(type default)
		)
		(layer "In6.Cu")
	)
	(gr_line
		(start 166.896796 -8.109204)
		(end 166.845996 -8.109204)
		(stroke
			(width 0.254)
			(type default)
		)
		(layer "In6.Cu")
	)
	(gr_line
		(start 166.896796 -8.009128)
		(end 166.845996 -8.009128)
		(stroke
			(width 0.254)
			(type default)
		)
		(layer "In6.Cu")
	)
	(gr_line
		(start 166.896796 -6.204204)
		(end 166.896796 -8.109204)
		(stroke
			(width 0.254)
			(type default)
		)
		(layer "In6.Cu")
	)
	(gr_line
		(start 166.896796 -6.104128)
		(end 166.896796 -8.009128)
		(stroke
			(width 0.254)
			(type default)
		)
		(layer "In6.Cu")
	)
	(gr_line
		(start 166.896796 -3.90906)
		(end 166.845996 -3.90906)
		(stroke
			(width 0.254)
			(type default)
		)
		(layer "In6.Cu")
	)
	(gr_line
		(start 166.896796 -3.808984)
		(end 166.845996 -3.808984)
		(stroke
			(width 0.254)
			(type default)
		)
		(layer "In6.Cu")
	)
	(gr_line
		(start 166.896796 -2.00406)
		(end 166.896796 -3.90906)
		(stroke
			(width 0.254)
			(type default)
		)
		(layer "In6.Cu")
	)
	(gr_line
		(start 166.896796 -1.903984)
		(end 166.896796 -3.808984)
		(stroke
			(width 0.254)
			(type default)
		)
		(layer "In6.Cu")
	)
	(gr_line
		(start 166.947596 -12.233148)
		(end 166.947596 -10.251948)
		(stroke
			(width 0.762)
			(type default)
		)
		(layer "In6.Cu")
	)
	(gr_line
		(start 166.947596 -12.133072)
		(end 166.947596 -10.151872)
		(stroke
			(width 0.762)
			(type default)
		)
		(layer "In6.Cu")
	)
	(gr_line
		(start 166.947596 -8.033004)
		(end 166.947596 -6.051804)
		(stroke
			(width 0.762)
			(type default)
		)
		(layer "In6.Cu")
	)
	(gr_line
		(start 166.947596 -7.932928)
		(end 166.947596 -5.951728)
		(stroke
			(width 0.762)
			(type default)
		)
		(layer "In6.Cu")
	)
	(gr_line
		(start 166.947596 -3.83286)
		(end 166.947596 -1.85166)
		(stroke
			(width 0.762)
			(type default)
		)
		(layer "In6.Cu")
	)
	(gr_line
		(start 166.947596 -3.732784)
		(end 166.947596 -1.751584)
		(stroke
			(width 0.762)
			(type default)
		)
		(layer "In6.Cu")
	)
	(gr_line
		(start 167.023796 -12.207748)
		(end 166.795196 -12.207748)
		(stroke
			(width 0.254)
			(type default)
		)
		(layer "In6.Cu")
	)
	(gr_line
		(start 167.023796 -12.107672)
		(end 166.795196 -12.107672)
		(stroke
			(width 0.254)
			(type default)
		)
		(layer "In6.Cu")
	)
	(gr_line
		(start 167.023796 -10.251948)
		(end 167.023796 -12.207748)
		(stroke
			(width 0.254)
			(type default)
		)
		(layer "In6.Cu")
	)
	(gr_line
		(start 167.023796 -10.151872)
		(end 167.023796 -12.107672)
		(stroke
			(width 0.254)
			(type default)
		)
		(layer "In6.Cu")
	)
	(gr_line
		(start 167.023796 -8.007604)
		(end 166.795196 -8.007604)
		(stroke
			(width 0.254)
			(type default)
		)
		(layer "In6.Cu")
	)
	(gr_line
		(start 167.023796 -7.907528)
		(end 166.795196 -7.907528)
		(stroke
			(width 0.254)
			(type default)
		)
		(layer "In6.Cu")
	)
	(gr_line
		(start 167.023796 -6.051804)
		(end 167.023796 -8.007604)
		(stroke
			(width 0.254)
			(type default)
		)
		(layer "In6.Cu")
	)
	(gr_line
		(start 167.023796 -5.951728)
		(end 167.023796 -7.907528)
		(stroke
			(width 0.254)
			(type default)
		)
		(layer "In6.Cu")
	)
	(gr_line
		(start 167.023796 -3.80746)
		(end 166.795196 -3.80746)
		(stroke
			(width 0.254)
			(type default)
		)
		(layer "In6.Cu")
	)
	(gr_line
		(start 167.023796 -3.707384)
		(end 166.795196 -3.707384)
		(stroke
			(width 0.254)
			(type default)
		)
		(layer "In6.Cu")
	)
	(gr_line
		(start 167.023796 -1.85166)
		(end 167.023796 -3.80746)
		(stroke
			(width 0.254)
			(type default)
		)
		(layer "In6.Cu")
	)
	(gr_line
		(start 167.023796 -1.751584)
		(end 167.023796 -3.707384)
		(stroke
			(width 0.254)
			(type default)
		)
		(layer "In6.Cu")
	)
	(gr_line
		(start 167.074596 -12.563348)
		(end 167.074596 -12.512548)
		(stroke
			(width 0.1016)
			(type default)
		)
		(layer "In6.Cu")
	)
	(gr_line
		(start 167.074596 -12.563348)
		(end 167.480996 -12.563348)
		(stroke
			(width 0.1016)
			(type default)
		)
		(layer "In6.Cu")
	)
	(gr_line
		(start 167.074596 -12.512548)
		(end 166.312596 -12.512548)
		(stroke
			(width 0.1016)
			(type default)
		)
		(layer "In6.Cu")
	)
	(gr_line
		(start 167.074596 -12.463272)
		(end 167.074596 -12.412472)
		(stroke
			(width 0.1016)
			(type default)
		)
		(layer "In6.Cu")
	)
	(gr_line
		(start 167.074596 -12.463272)
		(end 167.480996 -12.463272)
		(stroke
			(width 0.1016)
			(type default)
		)
		(layer "In6.Cu")
	)
	(gr_line
		(start 167.074596 -12.412472)
		(end 166.312596 -12.412472)
		(stroke
			(width 0.1016)
			(type default)
		)
		(layer "In6.Cu")
	)
	(gr_line
		(start 167.074596 -12.233148)
		(end 167.074596 -10.251948)
		(stroke
			(width 0.762)
			(type default)
		)
		(layer "In6.Cu")
	)
	(gr_line
		(start 167.074596 -12.133072)
		(end 167.074596 -10.151872)
		(stroke
			(width 0.762)
			(type default)
		)
		(layer "In6.Cu")
	)
	(gr_line
		(start 167.074596 -8.363204)
		(end 167.074596 -8.312404)
		(stroke
			(width 0.1016)
			(type default)
		)
		(layer "In6.Cu")
	)
	(gr_line
		(start 167.074596 -8.363204)
		(end 167.480996 -8.363204)
		(stroke
			(width 0.1016)
			(type default)
		)
		(layer "In6.Cu")
	)
	(gr_line
		(start 167.074596 -8.312404)
		(end 166.312596 -8.312404)
		(stroke
			(width 0.1016)
			(type default)
		)
		(layer "In6.Cu")
	)
	(gr_line
		(start 167.074596 -8.263128)
		(end 167.074596 -8.212328)
		(stroke
			(width 0.1016)
			(type default)
		)
		(layer "In6.Cu")
	)
	(gr_line
		(start 167.074596 -8.263128)
		(end 167.480996 -8.263128)
		(stroke
			(width 0.1016)
			(type default)
		)
		(layer "In6.Cu")
	)
	(gr_line
		(start 167.074596 -8.212328)
		(end 166.312596 -8.212328)
		(stroke
			(width 0.1016)
			(type default)
		)
		(layer "In6.Cu")
	)
	(gr_line
		(start 167.074596 -8.033004)
		(end 167.074596 -6.051804)
		(stroke
			(width 0.762)
			(type default)
		)
		(layer "In6.Cu")
	)
	(gr_line
		(start 167.074596 -7.932928)
		(end 167.074596 -5.951728)
		(stroke
			(width 0.762)
			(type default)
		)
		(layer "In6.Cu")
	)
	(gr_line
		(start 167.074596 -4.16306)
		(end 167.074596 -4.11226)
		(stroke
			(width 0.1016)
			(type default)
		)
		(layer "In6.Cu")
	)
	(gr_line
		(start 167.074596 -4.16306)
		(end 167.480996 -4.16306)
		(stroke
			(width 0.1016)
			(type default)
		)
		(layer "In6.Cu")
	)
	(gr_line
		(start 167.074596 -4.11226)
		(end 166.312596 -4.11226)
		(stroke
			(width 0.1016)
			(type default)
		)
		(layer "In6.Cu")
	)
	(gr_line
		(start 167.074596 -4.062984)
		(end 167.074596 -4.012184)
		(stroke
			(width 0.1016)
			(type default)
		)
		(layer "In6.Cu")
	)
	(gr_line
		(start 167.074596 -4.062984)
		(end 167.480996 -4.062984)
		(stroke
			(width 0.1016)
			(type default)
		)
		(layer "In6.Cu")
	)
	(gr_line
		(start 167.074596 -4.012184)
		(end 166.312596 -4.012184)
		(stroke
			(width 0.1016)
			(type default)
		)
		(layer "In6.Cu")
	)
	(gr_line
		(start 167.074596 -3.83286)
		(end 167.074596 -1.85166)
		(stroke
			(width 0.762)
			(type default)
		)
		(layer "In6.Cu")
	)
	(gr_line
		(start 167.074596 -3.732784)
		(end 167.074596 -1.751584)
		(stroke
			(width 0.762)
			(type default)
		)
		(layer "In6.Cu")
	)
	(gr_line
		(start 167.099996 -12.283948)
		(end 166.693596 -12.283948)
		(stroke
			(width 0.254)
			(type default)
		)
		(layer "In6.Cu")
	)
	(gr_line
		(start 167.099996 -12.183872)
		(end 166.693596 -12.183872)
		(stroke
			(width 0.254)
			(type default)
		)
		(layer "In6.Cu")
	)
	(gr_line
		(start 167.099996 -10.175748)
		(end 167.099996 -12.283948)
		(stroke
			(width 0.254)
			(type default)
		)
		(layer "In6.Cu")
	)
	(gr_line
		(start 167.099996 -10.075672)
		(end 167.099996 -12.183872)
		(stroke
			(width 0.254)
			(type default)
		)
		(layer "In6.Cu")
	)
	(gr_line
		(start 167.099996 -8.083804)
		(end 166.693596 -8.083804)
		(stroke
			(width 0.254)
			(type default)
		)
		(layer "In6.Cu")
	)
	(gr_line
		(start 167.099996 -7.983728)
		(end 166.693596 -7.983728)
		(stroke
			(width 0.254)
			(type default)
		)
		(layer "In6.Cu")
	)
	(gr_line
		(start 167.099996 -5.975604)
		(end 167.099996 -8.083804)
		(stroke
			(width 0.254)
			(type default)
		)
		(layer "In6.Cu")
	)
	(gr_line
		(start 167.099996 -5.875528)
		(end 167.099996 -7.983728)
		(stroke
			(width 0.254)
			(type default)
		)
		(layer "In6.Cu")
	)
	(gr_line
		(start 167.099996 -3.88366)
		(end 166.693596 -3.88366)
		(stroke
			(width 0.254)
			(type default)
		)
		(layer "In6.Cu")
	)
	(gr_line
		(start 167.099996 -3.783584)
		(end 166.693596 -3.783584)
		(stroke
			(width 0.254)
			(type default)
		)
		(layer "In6.Cu")
	)
	(gr_line
		(start 167.099996 -1.77546)
		(end 167.099996 -3.88366)
		(stroke
			(width 0.254)
			(type default)
		)
		(layer "In6.Cu")
	)
	(gr_line
		(start 167.099996 -1.675384)
		(end 167.099996 -3.783584)
		(stroke
			(width 0.254)
			(type default)
		)
		(layer "In6.Cu")
	)
	(gr_line
		(start 167.150796 -12.233148)
		(end 167.150796 -10.251948)
		(stroke
			(width 0.762)
			(type default)
		)
		(layer "In6.Cu")
	)
	(gr_line
		(start 167.150796 -12.133072)
		(end 167.150796 -10.151872)
		(stroke
			(width 0.762)
			(type default)
		)
		(layer "In6.Cu")
	)
	(gr_line
		(start 167.150796 -8.033004)
		(end 167.150796 -6.051804)
		(stroke
			(width 0.762)
			(type default)
		)
		(layer "In6.Cu")
	)
	(gr_line
		(start 167.150796 -7.932928)
		(end 167.150796 -5.951728)
		(stroke
			(width 0.762)
			(type default)
		)
		(layer "In6.Cu")
	)
	(gr_line
		(start 167.150796 -3.83286)
		(end 167.150796 -1.85166)
		(stroke
			(width 0.762)
			(type default)
		)
		(layer "In6.Cu")
	)
	(gr_line
		(start 167.150796 -3.732784)
		(end 167.150796 -1.751584)
		(stroke
			(width 0.762)
			(type default)
		)
		(layer "In6.Cu")
	)
	(gr_line
		(start 167.176196 -12.360148)
		(end 166.617396 -12.360148)
		(stroke
			(width 0.254)
			(type default)
		)
		(layer "In6.Cu")
	)
	(gr_line
		(start 167.176196 -12.260072)
		(end 166.617396 -12.260072)
		(stroke
			(width 0.254)
			(type default)
		)
		(layer "In6.Cu")
	)
	(gr_line
		(start 167.176196 -10.124948)
		(end 167.176196 -12.360148)
		(stroke
			(width 0.254)
			(type default)
		)
		(layer "In6.Cu")
	)
	(gr_line
		(start 167.176196 -10.024872)
		(end 167.176196 -12.260072)
		(stroke
			(width 0.254)
			(type default)
		)
		(layer "In6.Cu")
	)
	(gr_line
		(start 167.176196 -8.160004)
		(end 166.617396 -8.160004)
		(stroke
			(width 0.254)
			(type default)
		)
		(layer "In6.Cu")
	)
	(gr_line
		(start 167.176196 -8.059928)
		(end 166.617396 -8.059928)
		(stroke
			(width 0.254)
			(type default)
		)
		(layer "In6.Cu")
	)
	(gr_line
		(start 167.176196 -5.924804)
		(end 167.176196 -8.160004)
		(stroke
			(width 0.254)
			(type default)
		)
		(layer "In6.Cu")
	)
	(gr_line
		(start 167.176196 -5.824728)
		(end 167.176196 -8.059928)
		(stroke
			(width 0.254)
			(type default)
		)
		(layer "In6.Cu")
	)
	(gr_line
		(start 167.176196 -3.95986)
		(end 166.617396 -3.95986)
		(stroke
			(width 0.254)
			(type default)
		)
		(layer "In6.Cu")
	)
	(gr_line
		(start 167.176196 -3.859784)
		(end 166.617396 -3.859784)
		(stroke
			(width 0.254)
			(type default)
		)
		(layer "In6.Cu")
	)
	(gr_line
		(start 167.176196 -1.72466)
		(end 167.176196 -3.95986)
		(stroke
			(width 0.254)
			(type default)
		)
		(layer "In6.Cu")
	)
	(gr_line
		(start 167.176196 -1.624584)
		(end 167.176196 -3.859784)
		(stroke
			(width 0.254)
			(type default)
		)
		(layer "In6.Cu")
	)
	(gr_line
		(start 167.252396 -12.385548)
		(end 166.541196 -12.385548)
		(stroke
			(width 0.254)
			(type default)
		)
		(layer "In6.Cu")
	)
	(gr_line
		(start 167.252396 -12.285472)
		(end 166.541196 -12.285472)
		(stroke
			(width 0.254)
			(type default)
		)
		(layer "In6.Cu")
	)
	(gr_line
		(start 167.252396 -10.048748)
		(end 167.252396 -12.385548)
		(stroke
			(width 0.254)
			(type default)
		)
		(layer "In6.Cu")
	)
	(gr_line
		(start 167.252396 -9.948672)
		(end 167.252396 -12.285472)
		(stroke
			(width 0.254)
			(type default)
		)
		(layer "In6.Cu")
	)
	(gr_line
		(start 167.252396 -8.185404)
		(end 166.541196 -8.185404)
		(stroke
			(width 0.254)
			(type default)
		)
		(layer "In6.Cu")
	)
	(gr_line
		(start 167.252396 -8.085328)
		(end 166.541196 -8.085328)
		(stroke
			(width 0.254)
			(type default)
		)
		(layer "In6.Cu")
	)
	(gr_line
		(start 167.252396 -5.848604)
		(end 167.252396 -8.185404)
		(stroke
			(width 0.254)
			(type default)
		)
		(layer "In6.Cu")
	)
	(gr_line
		(start 167.252396 -5.748528)
		(end 167.252396 -8.085328)
		(stroke
			(width 0.254)
			(type default)
		)
		(layer "In6.Cu")
	)
	(gr_line
		(start 167.252396 -3.98526)
		(end 166.541196 -3.98526)
		(stroke
			(width 0.254)
			(type default)
		)
		(layer "In6.Cu")
	)
	(gr_line
		(start 167.252396 -3.885184)
		(end 166.541196 -3.885184)
		(stroke
			(width 0.254)
			(type default)
		)
		(layer "In6.Cu")
	)
	(gr_line
		(start 167.252396 -1.64846)
		(end 167.252396 -3.98526)
		(stroke
			(width 0.254)
			(type default)
		)
		(layer "In6.Cu")
	)
	(gr_line
		(start 167.252396 -1.548384)
		(end 167.252396 -3.885184)
		(stroke
			(width 0.254)
			(type default)
		)
		(layer "In6.Cu")
	)
	(gr_line
		(start 167.277796 -12.512548)
		(end 166.287196 -12.512548)
		(stroke
			(width 0.1016)
			(type default)
		)
		(layer "In6.Cu")
	)
	(gr_line
		(start 167.277796 -12.436348)
		(end 166.464996 -12.436348)
		(stroke
			(width 0.254)
			(type default)
		)
		(layer "In6.Cu")
	)
	(gr_line
		(start 167.277796 -12.412472)
		(end 166.287196 -12.412472)
		(stroke
			(width 0.1016)
			(type default)
		)
		(layer "In6.Cu")
	)
	(gr_line
		(start 167.277796 -12.336272)
		(end 166.464996 -12.336272)
		(stroke
			(width 0.254)
			(type default)
		)
		(layer "In6.Cu")
	)
	(gr_line
		(start 167.277796 -10.023348)
		(end 167.277796 -12.436348)
		(stroke
			(width 0.254)
			(type default)
		)
		(layer "In6.Cu")
	)
	(gr_line
		(start 167.277796 -9.923272)
		(end 167.277796 -12.336272)
		(stroke
			(width 0.254)
			(type default)
		)
		(layer "In6.Cu")
	)
	(gr_line
		(start 167.277796 -8.312404)
		(end 166.287196 -8.312404)
		(stroke
			(width 0.1016)
			(type default)
		)
		(layer "In6.Cu")
	)
	(gr_line
		(start 167.277796 -8.236204)
		(end 166.464996 -8.236204)
		(stroke
			(width 0.254)
			(type default)
		)
		(layer "In6.Cu")
	)
	(gr_line
		(start 167.277796 -8.212328)
		(end 166.287196 -8.212328)
		(stroke
			(width 0.1016)
			(type default)
		)
		(layer "In6.Cu")
	)
	(gr_line
		(start 167.277796 -8.136128)
		(end 166.464996 -8.136128)
		(stroke
			(width 0.254)
			(type default)
		)
		(layer "In6.Cu")
	)
	(gr_line
		(start 167.277796 -5.823204)
		(end 167.277796 -8.236204)
		(stroke
			(width 0.254)
			(type default)
		)
		(layer "In6.Cu")
	)
	(gr_line
		(start 167.277796 -5.723128)
		(end 167.277796 -8.136128)
		(stroke
			(width 0.254)
			(type default)
		)
		(layer "In6.Cu")
	)
	(gr_line
		(start 167.277796 -4.11226)
		(end 166.287196 -4.11226)
		(stroke
			(width 0.1016)
			(type default)
		)
		(layer "In6.Cu")
	)
	(gr_line
		(start 167.277796 -4.03606)
		(end 166.464996 -4.03606)
		(stroke
			(width 0.254)
			(type default)
		)
		(layer "In6.Cu")
	)
	(gr_line
		(start 167.277796 -4.012184)
		(end 166.287196 -4.012184)
		(stroke
			(width 0.1016)
			(type default)
		)
		(layer "In6.Cu")
	)
	(gr_line
		(start 167.277796 -3.935984)
		(end 166.464996 -3.935984)
		(stroke
			(width 0.254)
			(type default)
		)
		(layer "In6.Cu")
	)
	(gr_line
		(start 167.277796 -1.62306)
		(end 167.277796 -4.03606)
		(stroke
			(width 0.254)
			(type default)
		)
		(layer "In6.Cu")
	)
	(gr_line
		(start 167.277796 -1.522984)
		(end 167.277796 -3.935984)
		(stroke
			(width 0.254)
			(type default)
		)
		(layer "In6.Cu")
	)
	(gr_line
		(start 167.303196 -12.461748)
		(end 166.439596 -12.461748)
		(stroke
			(width 0.254)
			(type default)
		)
		(layer "In6.Cu")
	)
	(gr_line
		(start 167.303196 -12.361672)
		(end 166.439596 -12.361672)
		(stroke
			(width 0.254)
			(type default)
		)
		(layer "In6.Cu")
	)
	(gr_line
		(start 167.303196 -9.997948)
		(end 167.303196 -12.461748)
		(stroke
			(width 0.254)
			(type default)
		)
		(layer "In6.Cu")
	)
	(gr_line
		(start 167.303196 -9.897872)
		(end 167.303196 -12.361672)
		(stroke
			(width 0.254)
			(type default)
		)
		(layer "In6.Cu")
	)
	(gr_line
		(start 167.303196 -8.261604)
		(end 166.439596 -8.261604)
		(stroke
			(width 0.254)
			(type default)
		)
		(layer "In6.Cu")
	)
	(gr_line
		(start 167.303196 -8.161528)
		(end 166.439596 -8.161528)
		(stroke
			(width 0.254)
			(type default)
		)
		(layer "In6.Cu")
	)
	(gr_line
		(start 167.303196 -5.797804)
		(end 167.303196 -8.261604)
		(stroke
			(width 0.254)
			(type default)
		)
		(layer "In6.Cu")
	)
	(gr_line
		(start 167.303196 -5.697728)
		(end 167.303196 -8.161528)
		(stroke
			(width 0.254)
			(type default)
		)
		(layer "In6.Cu")
	)
	(gr_line
		(start 167.303196 -4.06146)
		(end 166.439596 -4.06146)
		(stroke
			(width 0.254)
			(type default)
		)
		(layer "In6.Cu")
	)
	(gr_line
		(start 167.303196 -3.961384)
		(end 166.439596 -3.961384)
		(stroke
			(width 0.254)
			(type default)
		)
		(layer "In6.Cu")
	)
	(gr_line
		(start 167.303196 -1.59766)
		(end 167.303196 -4.06146)
		(stroke
			(width 0.254)
			(type default)
		)
		(layer "In6.Cu")
	)
	(gr_line
		(start 167.303196 -1.497584)
		(end 167.303196 -3.961384)
		(stroke
			(width 0.254)
			(type default)
		)
		(layer "In6.Cu")
	)
	(gr_line
		(start 167.353996 -12.487148)
		(end 166.414196 -12.487148)
		(stroke
			(width 0.254)
			(type default)
		)
		(layer "In6.Cu")
	)
	(gr_line
		(start 167.353996 -12.387072)
		(end 166.414196 -12.387072)
		(stroke
			(width 0.254)
			(type default)
		)
		(layer "In6.Cu")
	)
	(gr_line
		(start 167.353996 -9.997948)
		(end 167.353996 -12.487148)
		(stroke
			(width 0.254)
			(type default)
		)
		(layer "In6.Cu")
	)
	(gr_line
		(start 167.353996 -9.897872)
		(end 167.353996 -12.387072)
		(stroke
			(width 0.254)
			(type default)
		)
		(layer "In6.Cu")
	)
	(gr_line
		(start 167.353996 -8.287004)
		(end 166.414196 -8.287004)
		(stroke
			(width 0.254)
			(type default)
		)
		(layer "In6.Cu")
	)
	(gr_line
		(start 167.353996 -8.186928)
		(end 166.414196 -8.186928)
		(stroke
			(width 0.254)
			(type default)
		)
		(layer "In6.Cu")
	)
	(gr_line
		(start 167.353996 -5.797804)
		(end 167.353996 -8.287004)
		(stroke
			(width 0.254)
			(type default)
		)
		(layer "In6.Cu")
	)
	(gr_line
		(start 167.353996 -5.697728)
		(end 167.353996 -8.186928)
		(stroke
			(width 0.254)
			(type default)
		)
		(layer "In6.Cu")
	)
	(gr_line
		(start 167.353996 -4.08686)
		(end 166.414196 -4.08686)
		(stroke
			(width 0.254)
			(type default)
		)
		(layer "In6.Cu")
	)
	(gr_line
		(start 167.353996 -3.986784)
		(end 166.414196 -3.986784)
		(stroke
			(width 0.254)
			(type default)
		)
		(layer "In6.Cu")
	)
	(gr_line
		(start 167.353996 -1.59766)
		(end 167.353996 -4.08686)
		(stroke
			(width 0.254)
			(type default)
		)
		(layer "In6.Cu")
	)
	(gr_line
		(start 167.353996 -1.497584)
		(end 167.353996 -3.986784)
		(stroke
			(width 0.254)
			(type default)
		)
		(layer "In6.Cu")
	)
	(gr_line
		(start 167.379396 -12.487148)
		(end 166.414196 -12.487148)
		(stroke
			(width 0.2032)
			(type default)
		)
		(layer "In6.Cu")
	)
	(gr_line
		(start 167.379396 -12.387072)
		(end 166.414196 -12.387072)
		(stroke
			(width 0.2032)
			(type default)
		)
		(layer "In6.Cu")
	)
	(gr_line
		(start 167.379396 -9.947148)
		(end 167.379396 -12.487148)
		(stroke
			(width 0.2032)
			(type default)
		)
		(layer "In6.Cu")
	)
	(gr_line
		(start 167.379396 -9.847072)
		(end 167.379396 -12.387072)
		(stroke
			(width 0.2032)
			(type default)
		)
		(layer "In6.Cu")
	)
	(gr_line
		(start 167.379396 -8.287004)
		(end 166.414196 -8.287004)
		(stroke
			(width 0.2032)
			(type default)
		)
		(layer "In6.Cu")
	)
	(gr_line
		(start 167.379396 -8.186928)
		(end 166.414196 -8.186928)
		(stroke
			(width 0.2032)
			(type default)
		)
		(layer "In6.Cu")
	)
	(gr_line
		(start 167.379396 -5.747004)
		(end 167.379396 -8.287004)
		(stroke
			(width 0.2032)
			(type default)
		)
		(layer "In6.Cu")
	)
	(gr_line
		(start 167.379396 -5.646928)
		(end 167.379396 -8.186928)
		(stroke
			(width 0.2032)
			(type default)
		)
		(layer "In6.Cu")
	)
	(gr_line
		(start 167.379396 -4.08686)
		(end 166.414196 -4.08686)
		(stroke
			(width 0.2032)
			(type default)
		)
		(layer "In6.Cu")
	)
	(gr_line
		(start 167.379396 -3.986784)
		(end 166.414196 -3.986784)
		(stroke
			(width 0.2032)
			(type default)
		)
		(layer "In6.Cu")
	)
	(gr_line
		(start 167.379396 -1.54686)
		(end 167.379396 -4.08686)
		(stroke
			(width 0.2032)
			(type default)
		)
		(layer "In6.Cu")
	)
	(gr_line
		(start 167.379396 -1.446784)
		(end 167.379396 -3.986784)
		(stroke
			(width 0.2032)
			(type default)
		)
		(layer "In6.Cu")
	)
	(gr_line
		(start 167.430196 -12.512548)
		(end 166.363396 -12.512548)
		(stroke
			(width 0.2032)
			(type default)
		)
		(layer "In6.Cu")
	)
	(gr_line
		(start 167.430196 -12.412472)
		(end 166.363396 -12.412472)
		(stroke
			(width 0.2032)
			(type default)
		)
		(layer "In6.Cu")
	)
	(gr_line
		(start 167.430196 -9.947148)
		(end 167.430196 -12.512548)
		(stroke
			(width 0.2032)
			(type default)
		)
		(layer "In6.Cu")
	)
	(gr_line
		(start 167.430196 -9.847072)
		(end 167.430196 -12.412472)
		(stroke
			(width 0.2032)
			(type default)
		)
		(layer "In6.Cu")
	)
	(gr_line
		(start 167.430196 -8.312404)
		(end 166.363396 -8.312404)
		(stroke
			(width 0.2032)
			(type default)
		)
		(layer "In6.Cu")
	)
	(gr_line
		(start 167.430196 -8.212328)
		(end 166.363396 -8.212328)
		(stroke
			(width 0.2032)
			(type default)
		)
		(layer "In6.Cu")
	)
	(gr_line
		(start 167.430196 -5.747004)
		(end 167.430196 -8.312404)
		(stroke
			(width 0.2032)
			(type default)
		)
		(layer "In6.Cu")
	)
	(gr_line
		(start 167.430196 -5.646928)
		(end 167.430196 -8.212328)
		(stroke
			(width 0.2032)
			(type default)
		)
		(layer "In6.Cu")
	)
	(gr_line
		(start 167.430196 -4.11226)
		(end 166.363396 -4.11226)
		(stroke
			(width 0.2032)
			(type default)
		)
		(layer "In6.Cu")
	)
	(gr_line
		(start 167.430196 -4.012184)
		(end 166.363396 -4.012184)
		(stroke
			(width 0.2032)
			(type default)
		)
		(layer "In6.Cu")
	)
	(gr_line
		(start 167.430196 -1.54686)
		(end 167.430196 -4.11226)
		(stroke
			(width 0.2032)
			(type default)
		)
		(layer "In6.Cu")
	)
	(gr_line
		(start 167.430196 -1.446784)
		(end 167.430196 -4.012184)
		(stroke
			(width 0.2032)
			(type default)
		)
		(layer "In6.Cu")
	)
	(gr_line
		(start 167.455596 -12.512548)
		(end 166.337996 -12.512548)
		(stroke
			(width 0.1016)
			(type default)
		)
		(layer "In6.Cu")
	)
	(gr_line
		(start 167.455596 -12.412472)
		(end 166.337996 -12.412472)
		(stroke
			(width 0.1016)
			(type default)
		)
		(layer "In6.Cu")
	)
	(gr_line
		(start 167.455596 -9.921748)
		(end 167.455596 -12.512548)
		(stroke
			(width 0.1016)
			(type default)
		)
		(layer "In6.Cu")
	)
	(gr_line
		(start 167.455596 -9.821672)
		(end 167.455596 -12.412472)
		(stroke
			(width 0.1016)
			(type default)
		)
		(layer "In6.Cu")
	)
	(gr_line
		(start 167.455596 -8.312404)
		(end 166.337996 -8.312404)
		(stroke
			(width 0.1016)
			(type default)
		)
		(layer "In6.Cu")
	)
	(gr_line
		(start 167.455596 -8.212328)
		(end 166.337996 -8.212328)
		(stroke
			(width 0.1016)
			(type default)
		)
		(layer "In6.Cu")
	)
	(gr_line
		(start 167.455596 -5.721604)
		(end 167.455596 -8.312404)
		(stroke
			(width 0.1016)
			(type default)
		)
		(layer "In6.Cu")
	)
	(gr_line
		(start 167.455596 -5.621528)
		(end 167.455596 -8.212328)
		(stroke
			(width 0.1016)
			(type default)
		)
		(layer "In6.Cu")
	)
	(gr_line
		(start 167.455596 -4.11226)
		(end 166.337996 -4.11226)
		(stroke
			(width 0.1016)
			(type default)
		)
		(layer "In6.Cu")
	)
	(gr_line
		(start 167.455596 -4.012184)
		(end 166.337996 -4.012184)
		(stroke
			(width 0.1016)
			(type default)
		)
		(layer "In6.Cu")
	)
	(gr_line
		(start 167.455596 -1.52146)
		(end 167.455596 -4.11226)
		(stroke
			(width 0.1016)
			(type default)
		)
		(layer "In6.Cu")
	)
	(gr_line
		(start 167.455596 -1.421384)
		(end 167.455596 -4.012184)
		(stroke
			(width 0.1016)
			(type default)
		)
		(layer "In6.Cu")
	)
	(gr_line
		(start 167.480996 -12.563348)
		(end 167.074596 -12.563348)
		(stroke
			(width 0.1016)
			(type default)
		)
		(layer "In6.Cu")
	)
	(gr_line
		(start 167.480996 -12.563348)
		(end 167.480996 -9.896348)
		(stroke
			(width 0.1016)
			(type default)
		)
		(layer "In6.Cu")
	)
	(gr_line
		(start 167.480996 -12.463272)
		(end 167.074596 -12.463272)
		(stroke
			(width 0.1016)
			(type default)
		)
		(layer "In6.Cu")
	)
	(gr_line
		(start 167.480996 -12.463272)
		(end 167.480996 -9.796272)
		(stroke
			(width 0.1016)
			(type default)
		)
		(layer "In6.Cu")
	)
	(gr_line
		(start 167.480996 -9.896348)
		(end 166.287196 -9.896348)
		(stroke
			(width 0.1016)
			(type default)
		)
		(layer "In6.Cu")
	)
	(gr_line
		(start 167.480996 -9.896348)
		(end 167.480996 -12.563348)
		(stroke
			(width 0.1016)
			(type default)
		)
		(layer "In6.Cu")
	)
	(gr_line
		(start 167.480996 -9.796272)
		(end 166.287196 -9.796272)
		(stroke
			(width 0.1016)
			(type default)
		)
		(layer "In6.Cu")
	)
	(gr_line
		(start 167.480996 -9.796272)
		(end 167.480996 -12.463272)
		(stroke
			(width 0.1016)
			(type default)
		)
		(layer "In6.Cu")
	)
	(gr_line
		(start 167.480996 -8.363204)
		(end 167.074596 -8.363204)
		(stroke
			(width 0.1016)
			(type default)
		)
		(layer "In6.Cu")
	)
	(gr_line
		(start 167.480996 -8.363204)
		(end 167.480996 -5.696204)
		(stroke
			(width 0.1016)
			(type default)
		)
		(layer "In6.Cu")
	)
	(gr_line
		(start 167.480996 -8.263128)
		(end 167.074596 -8.263128)
		(stroke
			(width 0.1016)
			(type default)
		)
		(layer "In6.Cu")
	)
	(gr_line
		(start 167.480996 -8.263128)
		(end 167.480996 -5.596128)
		(stroke
			(width 0.1016)
			(type default)
		)
		(layer "In6.Cu")
	)
	(gr_line
		(start 167.480996 -5.696204)
		(end 166.287196 -5.696204)
		(stroke
			(width 0.1016)
			(type default)
		)
		(layer "In6.Cu")
	)
	(gr_line
		(start 167.480996 -5.696204)
		(end 167.480996 -8.363204)
		(stroke
			(width 0.1016)
			(type default)
		)
		(layer "In6.Cu")
	)
	(gr_line
		(start 167.480996 -5.596128)
		(end 166.287196 -5.596128)
		(stroke
			(width 0.1016)
			(type default)
		)
		(layer "In6.Cu")
	)
	(gr_line
		(start 167.480996 -5.596128)
		(end 167.480996 -8.263128)
		(stroke
			(width 0.1016)
			(type default)
		)
		(layer "In6.Cu")
	)
	(gr_line
		(start 167.480996 -4.16306)
		(end 167.074596 -4.16306)
		(stroke
			(width 0.1016)
			(type default)
		)
		(layer "In6.Cu")
	)
	(gr_line
		(start 167.480996 -4.16306)
		(end 167.480996 -1.49606)
		(stroke
			(width 0.1016)
			(type default)
		)
		(layer "In6.Cu")
	)
	(gr_line
		(start 167.480996 -4.062984)
		(end 167.074596 -4.062984)
		(stroke
			(width 0.1016)
			(type default)
		)
		(layer "In6.Cu")
	)
	(gr_line
		(start 167.480996 -4.062984)
		(end 167.480996 -1.395984)
		(stroke
			(width 0.1016)
			(type default)
		)
		(layer "In6.Cu")
	)
	(gr_line
		(start 167.480996 -1.49606)
		(end 166.287196 -1.49606)
		(stroke
			(width 0.1016)
			(type default)
		)
		(layer "In6.Cu")
	)
	(gr_line
		(start 167.480996 -1.49606)
		(end 167.480996 -4.16306)
		(stroke
			(width 0.1016)
			(type default)
		)
		(layer "In6.Cu")
	)
	(gr_line
		(start 167.480996 -1.395984)
		(end 166.287196 -1.395984)
		(stroke
			(width 0.1016)
			(type default)
		)
		(layer "In6.Cu")
	)
	(gr_line
		(start 167.480996 -1.395984)
		(end 167.480996 -4.062984)
		(stroke
			(width 0.1016)
			(type default)
		)
		(layer "In6.Cu")
	)
	(gr_line
		(start 168.287192 -13.8176)
		(end 169.074592 -13.8176)
		(stroke
			(width 0.1016)
			(type default)
		)
		(layer "In6.Cu")
	)
	(gr_line
		(start 168.287192 -13.7668)
		(end 168.287192 -11.1506)
		(stroke
			(width 0.1016)
			(type default)
		)
		(layer "In6.Cu")
	)
	(gr_line
		(start 168.287192 -11.1506)
		(end 168.287192 -13.8176)
		(stroke
			(width 0.1016)
			(type default)
		)
		(layer "In6.Cu")
	)
	(gr_line
		(start 168.287192 -11.1506)
		(end 169.480992 -11.1506)
		(stroke
			(width 0.1016)
			(type default)
		)
		(layer "In6.Cu")
	)
	(gr_line
		(start 168.287192 -9.617456)
		(end 169.074592 -9.617456)
		(stroke
			(width 0.1016)
			(type default)
		)
		(layer "In6.Cu")
	)
	(gr_line
		(start 168.287192 -9.566656)
		(end 168.287192 -6.950456)
		(stroke
			(width 0.1016)
			(type default)
		)
		(layer "In6.Cu")
	)
	(gr_line
		(start 168.287192 -6.950456)
		(end 168.287192 -9.617456)
		(stroke
			(width 0.1016)
			(type default)
		)
		(layer "In6.Cu")
	)
	(gr_line
		(start 168.287192 -6.950456)
		(end 169.480992 -6.950456)
		(stroke
			(width 0.1016)
			(type default)
		)
		(layer "In6.Cu")
	)
	(gr_line
		(start 168.312592 -13.7668)
		(end 168.312592 -11.176)
		(stroke
			(width 0.1016)
			(type default)
		)
		(layer "In6.Cu")
	)
	(gr_line
		(start 168.312592 -11.176)
		(end 169.455592 -11.176)
		(stroke
			(width 0.1016)
			(type default)
		)
		(layer "In6.Cu")
	)
	(gr_line
		(start 168.312592 -9.566656)
		(end 168.312592 -6.975856)
		(stroke
			(width 0.1016)
			(type default)
		)
		(layer "In6.Cu")
	)
	(gr_line
		(start 168.312592 -6.975856)
		(end 169.455592 -6.975856)
		(stroke
			(width 0.1016)
			(type default)
		)
		(layer "In6.Cu")
	)
	(gr_line
		(start 168.337992 -13.7668)
		(end 168.337992 -11.2014)
		(stroke
			(width 0.1016)
			(type default)
		)
		(layer "In6.Cu")
	)
	(gr_line
		(start 168.337992 -11.2014)
		(end 168.591992 -11.2014)
		(stroke
			(width 0.1016)
			(type default)
		)
		(layer "In6.Cu")
	)
	(gr_line
		(start 168.337992 -9.566656)
		(end 168.337992 -7.001256)
		(stroke
			(width 0.1016)
			(type default)
		)
		(layer "In6.Cu")
	)
	(gr_line
		(start 168.337992 -7.001256)
		(end 168.591992 -7.001256)
		(stroke
			(width 0.1016)
			(type default)
		)
		(layer "In6.Cu")
	)
	(gr_line
		(start 168.363392 -13.7668)
		(end 168.363392 -11.2014)
		(stroke
			(width 0.2032)
			(type default)
		)
		(layer "In6.Cu")
	)
	(gr_line
		(start 168.363392 -11.2014)
		(end 169.379392 -11.2014)
		(stroke
			(width 0.2032)
			(type default)
		)
		(layer "In6.Cu")
	)
	(gr_line
		(start 168.363392 -9.566656)
		(end 168.363392 -7.001256)
		(stroke
			(width 0.2032)
			(type default)
		)
		(layer "In6.Cu")
	)
	(gr_line
		(start 168.363392 -7.001256)
		(end 169.379392 -7.001256)
		(stroke
			(width 0.2032)
			(type default)
		)
		(layer "In6.Cu")
	)
	(gr_line
		(start 168.414192 -13.7414)
		(end 168.414192 -11.2522)
		(stroke
			(width 0.2032)
			(type default)
		)
		(layer "In6.Cu")
	)
	(gr_line
		(start 168.414192 -13.7414)
		(end 168.414192 -11.2522)
		(stroke
			(width 0.254)
			(type default)
		)
		(layer "In6.Cu")
	)
	(gr_line
		(start 168.414192 -11.2522)
		(end 168.617392 -11.2522)
		(stroke
			(width 0.2032)
			(type default)
		)
		(layer "In6.Cu")
	)
	(gr_line
		(start 168.414192 -11.2522)
		(end 169.303192 -11.2522)
		(stroke
			(width 0.254)
			(type default)
		)
		(layer "In6.Cu")
	)
	(gr_line
		(start 168.414192 -9.541256)
		(end 168.414192 -7.052056)
		(stroke
			(width 0.2032)
			(type default)
		)
		(layer "In6.Cu")
	)
	(gr_line
		(start 168.414192 -9.541256)
		(end 168.414192 -7.052056)
		(stroke
			(width 0.254)
			(type default)
		)
		(layer "In6.Cu")
	)
	(gr_line
		(start 168.414192 -7.052056)
		(end 168.617392 -7.052056)
		(stroke
			(width 0.2032)
			(type default)
		)
		(layer "In6.Cu")
	)
	(gr_line
		(start 168.414192 -7.052056)
		(end 169.303192 -7.052056)
		(stroke
			(width 0.254)
			(type default)
		)
		(layer "In6.Cu")
	)
	(gr_line
		(start 168.439592 -13.716)
		(end 168.439592 -11.2776)
		(stroke
			(width 0.254)
			(type default)
		)
		(layer "In6.Cu")
	)
	(gr_line
		(start 168.439592 -11.2776)
		(end 169.277792 -11.2776)
		(stroke
			(width 0.254)
			(type default)
		)
		(layer "In6.Cu")
	)
	(gr_line
		(start 168.439592 -9.515856)
		(end 168.439592 -7.077456)
		(stroke
			(width 0.254)
			(type default)
		)
		(layer "In6.Cu")
	)
	(gr_line
		(start 168.439592 -7.077456)
		(end 169.277792 -7.077456)
		(stroke
			(width 0.254)
			(type default)
		)
		(layer "In6.Cu")
	)
	(gr_line
		(start 168.464992 -13.6906)
		(end 168.464992 -11.303)
		(stroke
			(width 0.254)
			(type default)
		)
		(layer "In6.Cu")
	)
	(gr_line
		(start 168.464992 -11.303)
		(end 169.252392 -11.303)
		(stroke
			(width 0.254)
			(type default)
		)
		(layer "In6.Cu")
	)
	(gr_line
		(start 168.464992 -9.490456)
		(end 168.464992 -7.102856)
		(stroke
			(width 0.254)
			(type default)
		)
		(layer "In6.Cu")
	)
	(gr_line
		(start 168.464992 -7.102856)
		(end 169.252392 -7.102856)
		(stroke
			(width 0.254)
			(type default)
		)
		(layer "In6.Cu")
	)
	(gr_line
		(start 168.490392 -13.6144)
		(end 169.125392 -13.6144)
		(stroke
			(width 0.508)
			(type default)
		)
		(layer "In6.Cu")
	)
	(gr_line
		(start 168.490392 -11.43)
		(end 169.125392 -11.43)
		(stroke
			(width 0.508)
			(type default)
		)
		(layer "In6.Cu")
	)
	(gr_line
		(start 168.490392 -11.3792)
		(end 169.125392 -11.3792)
		(stroke
			(width 0.508)
			(type default)
		)
		(layer "In6.Cu")
	)
	(gr_line
		(start 168.490392 -9.414256)
		(end 169.125392 -9.414256)
		(stroke
			(width 0.508)
			(type default)
		)
		(layer "In6.Cu")
	)
	(gr_line
		(start 168.490392 -7.229856)
		(end 169.125392 -7.229856)
		(stroke
			(width 0.508)
			(type default)
		)
		(layer "In6.Cu")
	)
	(gr_line
		(start 168.490392 -7.179056)
		(end 169.125392 -7.179056)
		(stroke
			(width 0.508)
			(type default)
		)
		(layer "In6.Cu")
	)
	(gr_line
		(start 168.515792 -11.684)
		(end 169.150792 -11.684)
		(stroke
			(width 0.508)
			(type default)
		)
		(layer "In6.Cu")
	)
	(gr_line
		(start 168.515792 -7.483856)
		(end 169.150792 -7.483856)
		(stroke
			(width 0.508)
			(type default)
		)
		(layer "In6.Cu")
	)
	(gr_line
		(start 168.541192 -13.6398)
		(end 168.541192 -11.3792)
		(stroke
			(width 0.254)
			(type default)
		)
		(layer "In6.Cu")
	)
	(gr_line
		(start 168.541192 -13.4874)
		(end 169.176192 -13.4874)
		(stroke
			(width 0.508)
			(type default)
		)
		(layer "In6.Cu")
	)
	(gr_line
		(start 168.541192 -11.3792)
		(end 169.176192 -11.3792)
		(stroke
			(width 0.254)
			(type default)
		)
		(layer "In6.Cu")
	)
	(gr_line
		(start 168.541192 -9.439656)
		(end 168.541192 -7.179056)
		(stroke
			(width 0.254)
			(type default)
		)
		(layer "In6.Cu")
	)
	(gr_line
		(start 168.541192 -9.287256)
		(end 169.176192 -9.287256)
		(stroke
			(width 0.508)
			(type default)
		)
		(layer "In6.Cu")
	)
	(gr_line
		(start 168.541192 -7.179056)
		(end 169.176192 -7.179056)
		(stroke
			(width 0.254)
			(type default)
		)
		(layer "In6.Cu")
	)
	(gr_line
		(start 168.566592 -13.335)
		(end 169.201592 -13.335)
		(stroke
			(width 0.508)
			(type default)
		)
		(layer "In6.Cu")
	)
	(gr_line
		(start 168.566592 -9.134856)
		(end 169.201592 -9.134856)
		(stroke
			(width 0.508)
			(type default)
		)
		(layer "In6.Cu")
	)
	(gr_line
		(start 168.591992 -13.6144)
		(end 169.226992 -13.6144)
		(stroke
			(width 0.508)
			(type default)
		)
		(layer "In6.Cu")
	)
	(gr_line
		(start 168.591992 -11.2014)
		(end 169.430192 -11.2014)
		(stroke
			(width 0.2032)
			(type default)
		)
		(layer "In6.Cu")
	)
	(gr_line
		(start 168.591992 -9.414256)
		(end 169.226992 -9.414256)
		(stroke
			(width 0.508)
			(type default)
		)
		(layer "In6.Cu")
	)
	(gr_line
		(start 168.591992 -7.001256)
		(end 169.430192 -7.001256)
		(stroke
			(width 0.2032)
			(type default)
		)
		(layer "In6.Cu")
	)
	(gr_line
		(start 168.617392 -13.6144)
		(end 168.617392 -11.43)
		(stroke
			(width 0.254)
			(type default)
		)
		(layer "In6.Cu")
	)
	(gr_line
		(start 168.617392 -11.43)
		(end 169.099992 -11.43)
		(stroke
			(width 0.254)
			(type default)
		)
		(layer "In6.Cu")
	)
	(gr_line
		(start 168.617392 -11.2522)
		(end 169.353992 -11.2522)
		(stroke
			(width 0.254)
			(type default)
		)
		(layer "In6.Cu")
	)
	(gr_line
		(start 168.617392 -9.414256)
		(end 168.617392 -7.229856)
		(stroke
			(width 0.254)
			(type default)
		)
		(layer "In6.Cu")
	)
	(gr_line
		(start 168.617392 -7.229856)
		(end 169.099992 -7.229856)
		(stroke
			(width 0.254)
			(type default)
		)
		(layer "In6.Cu")
	)
	(gr_line
		(start 168.617392 -7.052056)
		(end 169.353992 -7.052056)
		(stroke
			(width 0.254)
			(type default)
		)
		(layer "In6.Cu")
	)
	(gr_line
		(start 168.635934 -11.36523)
		(end 169.270934 -11.36523)
		(stroke
			(width 0.508)
			(type default)
		)
		(layer "In6.Cu")
	)
	(gr_line
		(start 168.635934 -7.165086)
		(end 169.270934 -7.165086)
		(stroke
			(width 0.508)
			(type default)
		)
		(layer "In6.Cu")
	)
	(gr_line
		(start 168.642792 -13.6144)
		(end 169.277792 -13.6144)
		(stroke
			(width 0.508)
			(type default)
		)
		(layer "In6.Cu")
	)
	(gr_line
		(start 168.642792 -13.4874)
		(end 168.642792 -11.5062)
		(stroke
			(width 0.762)
			(type default)
		)
		(layer "In6.Cu")
	)
	(gr_line
		(start 168.642792 -11.5062)
		(end 169.277792 -11.5062)
		(stroke
			(width 0.508)
			(type default)
		)
		(layer "In6.Cu")
	)
	(gr_line
		(start 168.642792 -9.414256)
		(end 169.277792 -9.414256)
		(stroke
			(width 0.508)
			(type default)
		)
		(layer "In6.Cu")
	)
	(gr_line
		(start 168.642792 -9.287256)
		(end 168.642792 -7.306056)
		(stroke
			(width 0.762)
			(type default)
		)
		(layer "In6.Cu")
	)
	(gr_line
		(start 168.642792 -7.306056)
		(end 169.277792 -7.306056)
		(stroke
			(width 0.508)
			(type default)
		)
		(layer "In6.Cu")
	)
	(gr_line
		(start 168.693592 -13.5382)
		(end 168.693592 -11.5062)
		(stroke
			(width 0.254)
			(type default)
		)
		(layer "In6.Cu")
	)
	(gr_line
		(start 168.693592 -11.5062)
		(end 169.023792 -11.5062)
		(stroke
			(width 0.254)
			(type default)
		)
		(layer "In6.Cu")
	)
	(gr_line
		(start 168.693592 -9.338056)
		(end 168.693592 -7.306056)
		(stroke
			(width 0.254)
			(type default)
		)
		(layer "In6.Cu")
	)
	(gr_line
		(start 168.693592 -7.306056)
		(end 169.023792 -7.306056)
		(stroke
			(width 0.254)
			(type default)
		)
		(layer "In6.Cu")
	)
	(gr_line
		(start 168.73474 -18.5166)
		(end 167.46474 -18.5166)
		(stroke
			(width 0.7874)
			(type default)
		)
		(layer "In6.Cu")
	)
	(gr_line
		(start 168.795192 -13.462)
		(end 168.795192 -11.6586)
		(stroke
			(width 0.254)
			(type default)
		)
		(layer "In6.Cu")
	)
	(gr_line
		(start 168.795192 -13.462)
		(end 168.795192 -11.4808)
		(stroke
			(width 0.762)
			(type default)
		)
		(layer "In6.Cu")
	)
	(gr_line
		(start 168.795192 -11.6586)
		(end 168.896792 -11.6586)
		(stroke
			(width 0.254)
			(type default)
		)
		(layer "In6.Cu")
	)
	(gr_line
		(start 168.795192 -9.261856)
		(end 168.795192 -7.458456)
		(stroke
			(width 0.254)
			(type default)
		)
		(layer "In6.Cu")
	)
	(gr_line
		(start 168.795192 -9.261856)
		(end 168.795192 -7.280656)
		(stroke
			(width 0.762)
			(type default)
		)
		(layer "In6.Cu")
	)
	(gr_line
		(start 168.795192 -7.458456)
		(end 168.896792 -7.458456)
		(stroke
			(width 0.254)
			(type default)
		)
		(layer "In6.Cu")
	)
	(gr_line
		(start 168.896792 -13.5636)
		(end 168.845992 -13.5636)
		(stroke
			(width 0.254)
			(type default)
		)
		(layer "In6.Cu")
	)
	(gr_line
		(start 168.896792 -11.6586)
		(end 168.896792 -13.5636)
		(stroke
			(width 0.254)
			(type default)
		)
		(layer "In6.Cu")
	)
	(gr_line
		(start 168.896792 -9.363456)
		(end 168.845992 -9.363456)
		(stroke
			(width 0.254)
			(type default)
		)
		(layer "In6.Cu")
	)
	(gr_line
		(start 168.896792 -7.458456)
		(end 168.896792 -9.363456)
		(stroke
			(width 0.254)
			(type default)
		)
		(layer "In6.Cu")
	)
	(gr_line
		(start 168.947592 -13.4874)
		(end 168.947592 -11.5062)
		(stroke
			(width 0.762)
			(type default)
		)
		(layer "In6.Cu")
	)
	(gr_line
		(start 168.947592 -9.287256)
		(end 168.947592 -7.306056)
		(stroke
			(width 0.762)
			(type default)
		)
		(layer "In6.Cu")
	)
	(gr_line
		(start 169.023792 -13.462)
		(end 168.795192 -13.462)
		(stroke
			(width 0.254)
			(type default)
		)
		(layer "In6.Cu")
	)
	(gr_line
		(start 169.023792 -11.5062)
		(end 169.023792 -13.462)
		(stroke
			(width 0.254)
			(type default)
		)
		(layer "In6.Cu")
	)
	(gr_line
		(start 169.023792 -9.261856)
		(end 168.795192 -9.261856)
		(stroke
			(width 0.254)
			(type default)
		)
		(layer "In6.Cu")
	)
	(gr_line
		(start 169.023792 -7.306056)
		(end 169.023792 -9.261856)
		(stroke
			(width 0.254)
			(type default)
		)
		(layer "In6.Cu")
	)
	(gr_line
		(start 169.074592 -13.8176)
		(end 169.074592 -13.7668)
		(stroke
			(width 0.1016)
			(type default)
		)
		(layer "In6.Cu")
	)
	(gr_line
		(start 169.074592 -13.8176)
		(end 169.480992 -13.8176)
		(stroke
			(width 0.1016)
			(type default)
		)
		(layer "In6.Cu")
	)
	(gr_line
		(start 169.074592 -13.7668)
		(end 168.312592 -13.7668)
		(stroke
			(width 0.1016)
			(type default)
		)
		(layer "In6.Cu")
	)
	(gr_line
		(start 169.074592 -13.4874)
		(end 169.074592 -11.5062)
		(stroke
			(width 0.762)
			(type default)
		)
		(layer "In6.Cu")
	)
	(gr_line
		(start 169.074592 -9.617456)
		(end 169.074592 -9.566656)
		(stroke
			(width 0.1016)
			(type default)
		)
		(layer "In6.Cu")
	)
	(gr_line
		(start 169.074592 -9.617456)
		(end 169.480992 -9.617456)
		(stroke
			(width 0.1016)
			(type default)
		)
		(layer "In6.Cu")
	)
	(gr_line
		(start 169.074592 -9.566656)
		(end 168.312592 -9.566656)
		(stroke
			(width 0.1016)
			(type default)
		)
		(layer "In6.Cu")
	)
	(gr_line
		(start 169.074592 -9.287256)
		(end 169.074592 -7.306056)
		(stroke
			(width 0.762)
			(type default)
		)
		(layer "In6.Cu")
	)
	(gr_line
		(start 169.099992 -13.5382)
		(end 168.693592 -13.5382)
		(stroke
			(width 0.254)
			(type default)
		)
		(layer "In6.Cu")
	)
	(gr_line
		(start 169.099992 -11.43)
		(end 169.099992 -13.5382)
		(stroke
			(width 0.254)
			(type default)
		)
		(layer "In6.Cu")
	)
	(gr_line
		(start 169.099992 -9.338056)
		(end 168.693592 -9.338056)
		(stroke
			(width 0.254)
			(type default)
		)
		(layer "In6.Cu")
	)
	(gr_line
		(start 169.099992 -7.229856)
		(end 169.099992 -9.338056)
		(stroke
			(width 0.254)
			(type default)
		)
		(layer "In6.Cu")
	)
	(gr_line
		(start 169.150792 -13.4874)
		(end 169.150792 -11.5062)
		(stroke
			(width 0.762)
			(type default)
		)
		(layer "In6.Cu")
	)
	(gr_line
		(start 169.150792 -9.287256)
		(end 169.150792 -7.306056)
		(stroke
			(width 0.762)
			(type default)
		)
		(layer "In6.Cu")
	)
	(gr_line
		(start 169.176192 -13.6144)
		(end 168.617392 -13.6144)
		(stroke
			(width 0.254)
			(type default)
		)
		(layer "In6.Cu")
	)
	(gr_line
		(start 169.176192 -11.3792)
		(end 169.176192 -13.6144)
		(stroke
			(width 0.254)
			(type default)
		)
		(layer "In6.Cu")
	)
	(gr_line
		(start 169.176192 -9.414256)
		(end 168.617392 -9.414256)
		(stroke
			(width 0.254)
			(type default)
		)
		(layer "In6.Cu")
	)
	(gr_line
		(start 169.176192 -7.179056)
		(end 169.176192 -9.414256)
		(stroke
			(width 0.254)
			(type default)
		)
		(layer "In6.Cu")
	)
	(gr_line
		(start 169.252392 -13.6398)
		(end 168.541192 -13.6398)
		(stroke
			(width 0.254)
			(type default)
		)
		(layer "In6.Cu")
	)
	(gr_line
		(start 169.252392 -11.303)
		(end 169.252392 -13.6398)
		(stroke
			(width 0.254)
			(type default)
		)
		(layer "In6.Cu")
	)
	(gr_line
		(start 169.252392 -9.439656)
		(end 168.541192 -9.439656)
		(stroke
			(width 0.254)
			(type default)
		)
		(layer "In6.Cu")
	)
	(gr_line
		(start 169.252392 -7.102856)
		(end 169.252392 -9.439656)
		(stroke
			(width 0.254)
			(type default)
		)
		(layer "In6.Cu")
	)
	(gr_line
		(start 169.277792 -13.7668)
		(end 168.287192 -13.7668)
		(stroke
			(width 0.1016)
			(type default)
		)
		(layer "In6.Cu")
	)
	(gr_line
		(start 169.277792 -13.6906)
		(end 168.464992 -13.6906)
		(stroke
			(width 0.254)
			(type default)
		)
		(layer "In6.Cu")
	)
	(gr_line
		(start 169.277792 -11.2776)
		(end 169.277792 -13.6906)
		(stroke
			(width 0.254)
			(type default)
		)
		(layer "In6.Cu")
	)
	(gr_line
		(start 169.277792 -9.566656)
		(end 168.287192 -9.566656)
		(stroke
			(width 0.1016)
			(type default)
		)
		(layer "In6.Cu")
	)
	(gr_line
		(start 169.277792 -9.490456)
		(end 168.464992 -9.490456)
		(stroke
			(width 0.254)
			(type default)
		)
		(layer "In6.Cu")
	)
	(gr_line
		(start 169.277792 -7.077456)
		(end 169.277792 -9.490456)
		(stroke
			(width 0.254)
			(type default)
		)
		(layer "In6.Cu")
	)
	(gr_line
		(start 169.303192 -13.716)
		(end 168.439592 -13.716)
		(stroke
			(width 0.254)
			(type default)
		)
		(layer "In6.Cu")
	)
	(gr_line
		(start 169.303192 -11.2522)
		(end 169.303192 -13.716)
		(stroke
			(width 0.254)
			(type default)
		)
		(layer "In6.Cu")
	)
	(gr_line
		(start 169.303192 -9.515856)
		(end 168.439592 -9.515856)
		(stroke
			(width 0.254)
			(type default)
		)
		(layer "In6.Cu")
	)
	(gr_line
		(start 169.303192 -7.052056)
		(end 169.303192 -9.515856)
		(stroke
			(width 0.254)
			(type default)
		)
		(layer "In6.Cu")
	)
	(gr_line
		(start 169.319956 -30.734)
		(end 168.049956 -30.734)
		(stroke
			(width 0.7874)
			(type default)
		)
		(layer "In6.Cu")
	)
	(gr_line
		(start 169.353992 -13.7414)
		(end 168.414192 -13.7414)
		(stroke
			(width 0.254)
			(type default)
		)
		(layer "In6.Cu")
	)
	(gr_line
		(start 169.353992 -11.2522)
		(end 169.353992 -13.7414)
		(stroke
			(width 0.254)
			(type default)
		)
		(layer "In6.Cu")
	)
	(gr_line
		(start 169.353992 -9.541256)
		(end 168.414192 -9.541256)
		(stroke
			(width 0.254)
			(type default)
		)
		(layer "In6.Cu")
	)
	(gr_line
		(start 169.353992 -7.052056)
		(end 169.353992 -9.541256)
		(stroke
			(width 0.254)
			(type default)
		)
		(layer "In6.Cu")
	)
	(gr_line
		(start 169.379392 -13.7414)
		(end 168.414192 -13.7414)
		(stroke
			(width 0.2032)
			(type default)
		)
		(layer "In6.Cu")
	)
	(gr_line
		(start 169.379392 -11.2014)
		(end 169.379392 -13.7414)
		(stroke
			(width 0.2032)
			(type default)
		)
		(layer "In6.Cu")
	)
	(gr_line
		(start 169.379392 -9.541256)
		(end 168.414192 -9.541256)
		(stroke
			(width 0.2032)
			(type default)
		)
		(layer "In6.Cu")
	)
	(gr_line
		(start 169.379392 -7.001256)
		(end 169.379392 -9.541256)
		(stroke
			(width 0.2032)
			(type default)
		)
		(layer "In6.Cu")
	)
	(gr_line
		(start 169.430192 -13.7668)
		(end 168.363392 -13.7668)
		(stroke
			(width 0.2032)
			(type default)
		)
		(layer "In6.Cu")
	)
	(gr_line
		(start 169.430192 -11.2014)
		(end 169.430192 -13.7668)
		(stroke
			(width 0.2032)
			(type default)
		)
		(layer "In6.Cu")
	)
	(gr_line
		(start 169.430192 -9.566656)
		(end 168.363392 -9.566656)
		(stroke
			(width 0.2032)
			(type default)
		)
		(layer "In6.Cu")
	)
	(gr_line
		(start 169.430192 -7.001256)
		(end 169.430192 -9.566656)
		(stroke
			(width 0.2032)
			(type default)
		)
		(layer "In6.Cu")
	)
	(gr_line
		(start 169.455592 -13.7668)
		(end 168.337992 -13.7668)
		(stroke
			(width 0.1016)
			(type default)
		)
		(layer "In6.Cu")
	)
	(gr_line
		(start 169.455592 -11.176)
		(end 169.455592 -13.7668)
		(stroke
			(width 0.1016)
			(type default)
		)
		(layer "In6.Cu")
	)
	(gr_line
		(start 169.455592 -9.566656)
		(end 168.337992 -9.566656)
		(stroke
			(width 0.1016)
			(type default)
		)
		(layer "In6.Cu")
	)
	(gr_line
		(start 169.455592 -6.975856)
		(end 169.455592 -9.566656)
		(stroke
			(width 0.1016)
			(type default)
		)
		(layer "In6.Cu")
	)
	(gr_line
		(start 169.480992 -13.8176)
		(end 169.074592 -13.8176)
		(stroke
			(width 0.1016)
			(type default)
		)
		(layer "In6.Cu")
	)
	(gr_line
		(start 169.480992 -13.8176)
		(end 169.480992 -11.1506)
		(stroke
			(width 0.1016)
			(type default)
		)
		(layer "In6.Cu")
	)
	(gr_line
		(start 169.480992 -11.1506)
		(end 168.287192 -11.1506)
		(stroke
			(width 0.1016)
			(type default)
		)
		(layer "In6.Cu")
	)
	(gr_line
		(start 169.480992 -11.1506)
		(end 169.480992 -13.8176)
		(stroke
			(width 0.1016)
			(type default)
		)
		(layer "In6.Cu")
	)
	(gr_line
		(start 169.480992 -9.617456)
		(end 169.074592 -9.617456)
		(stroke
			(width 0.1016)
			(type default)
		)
		(layer "In6.Cu")
	)
	(gr_line
		(start 169.480992 -9.617456)
		(end 169.480992 -6.950456)
		(stroke
			(width 0.1016)
			(type default)
		)
		(layer "In6.Cu")
	)
	(gr_line
		(start 169.480992 -6.950456)
		(end 168.287192 -6.950456)
		(stroke
			(width 0.1016)
			(type default)
		)
		(layer "In6.Cu")
	)
	(gr_line
		(start 169.480992 -6.950456)
		(end 169.480992 -9.617456)
		(stroke
			(width 0.1016)
			(type default)
		)
		(layer "In6.Cu")
	)
	(gr_line
		(start 170.287188 -12.563348)
		(end 171.074588 -12.563348)
		(stroke
			(width 0.1016)
			(type default)
		)
		(layer "In6.Cu")
	)
	(gr_line
		(start 170.287188 -12.512548)
		(end 170.287188 -9.896348)
		(stroke
			(width 0.1016)
			(type default)
		)
		(layer "In6.Cu")
	)
	(gr_line
		(start 170.287188 -12.463272)
		(end 171.074588 -12.463272)
		(stroke
			(width 0.1016)
			(type default)
		)
		(layer "In6.Cu")
	)
	(gr_line
		(start 170.287188 -12.412472)
		(end 170.287188 -9.796272)
		(stroke
			(width 0.1016)
			(type default)
		)
		(layer "In6.Cu")
	)
	(gr_line
		(start 170.287188 -9.896348)
		(end 170.287188 -12.563348)
		(stroke
			(width 0.1016)
			(type default)
		)
		(layer "In6.Cu")
	)
	(gr_line
		(start 170.287188 -9.896348)
		(end 171.480988 -9.896348)
		(stroke
			(width 0.1016)
			(type default)
		)
		(layer "In6.Cu")
	)
	(gr_line
		(start 170.287188 -9.796272)
		(end 170.287188 -12.463272)
		(stroke
			(width 0.1016)
			(type default)
		)
		(layer "In6.Cu")
	)
	(gr_line
		(start 170.287188 -9.796272)
		(end 171.480988 -9.796272)
		(stroke
			(width 0.1016)
			(type default)
		)
		(layer "In6.Cu")
	)
	(gr_line
		(start 170.287188 -8.363204)
		(end 171.074588 -8.363204)
		(stroke
			(width 0.1016)
			(type default)
		)
		(layer "In6.Cu")
	)
	(gr_line
		(start 170.287188 -8.312404)
		(end 170.287188 -5.696204)
		(stroke
			(width 0.1016)
			(type default)
		)
		(layer "In6.Cu")
	)
	(gr_line
		(start 170.287188 -8.263128)
		(end 171.074588 -8.263128)
		(stroke
			(width 0.1016)
			(type default)
		)
		(layer "In6.Cu")
	)
	(gr_line
		(start 170.287188 -8.212328)
		(end 170.287188 -5.596128)
		(stroke
			(width 0.1016)
			(type default)
		)
		(layer "In6.Cu")
	)
	(gr_line
		(start 170.287188 -5.696204)
		(end 170.287188 -8.363204)
		(stroke
			(width 0.1016)
			(type default)
		)
		(layer "In6.Cu")
	)
	(gr_line
		(start 170.287188 -5.696204)
		(end 171.480988 -5.696204)
		(stroke
			(width 0.1016)
			(type default)
		)
		(layer "In6.Cu")
	)
	(gr_line
		(start 170.287188 -5.596128)
		(end 170.287188 -8.263128)
		(stroke
			(width 0.1016)
			(type default)
		)
		(layer "In6.Cu")
	)
	(gr_line
		(start 170.287188 -5.596128)
		(end 171.480988 -5.596128)
		(stroke
			(width 0.1016)
			(type default)
		)
		(layer "In6.Cu")
	)
	(gr_line
		(start 170.312588 -12.512548)
		(end 170.312588 -9.921748)
		(stroke
			(width 0.1016)
			(type default)
		)
		(layer "In6.Cu")
	)
	(gr_line
		(start 170.312588 -12.412472)
		(end 170.312588 -9.821672)
		(stroke
			(width 0.1016)
			(type default)
		)
		(layer "In6.Cu")
	)
	(gr_line
		(start 170.312588 -9.921748)
		(end 171.455588 -9.921748)
		(stroke
			(width 0.1016)
			(type default)
		)
		(layer "In6.Cu")
	)
	(gr_line
		(start 170.312588 -9.821672)
		(end 171.455588 -9.821672)
		(stroke
			(width 0.1016)
			(type default)
		)
		(layer "In6.Cu")
	)
	(gr_line
		(start 170.312588 -8.312404)
		(end 170.312588 -5.721604)
		(stroke
			(width 0.1016)
			(type default)
		)
		(layer "In6.Cu")
	)
	(gr_line
		(start 170.312588 -8.212328)
		(end 170.312588 -5.621528)
		(stroke
			(width 0.1016)
			(type default)
		)
		(layer "In6.Cu")
	)
	(gr_line
		(start 170.312588 -5.721604)
		(end 171.455588 -5.721604)
		(stroke
			(width 0.1016)
			(type default)
		)
		(layer "In6.Cu")
	)
	(gr_line
		(start 170.312588 -5.621528)
		(end 171.455588 -5.621528)
		(stroke
			(width 0.1016)
			(type default)
		)
		(layer "In6.Cu")
	)
	(gr_line
		(start 170.337988 -12.512548)
		(end 170.337988 -9.947148)
		(stroke
			(width 0.1016)
			(type default)
		)
		(layer "In6.Cu")
	)
	(gr_line
		(start 170.337988 -12.412472)
		(end 170.337988 -9.847072)
		(stroke
			(width 0.1016)
			(type default)
		)
		(layer "In6.Cu")
	)
	(gr_line
		(start 170.337988 -9.947148)
		(end 170.591988 -9.947148)
		(stroke
			(width 0.1016)
			(type default)
		)
		(layer "In6.Cu")
	)
	(gr_line
		(start 170.337988 -9.847072)
		(end 170.591988 -9.847072)
		(stroke
			(width 0.1016)
			(type default)
		)
		(layer "In6.Cu")
	)
	(gr_line
		(start 170.337988 -8.312404)
		(end 170.337988 -5.747004)
		(stroke
			(width 0.1016)
			(type default)
		)
		(layer "In6.Cu")
	)
	(gr_line
		(start 170.337988 -8.212328)
		(end 170.337988 -5.646928)
		(stroke
			(width 0.1016)
			(type default)
		)
		(layer "In6.Cu")
	)
	(gr_line
		(start 170.337988 -5.747004)
		(end 170.591988 -5.747004)
		(stroke
			(width 0.1016)
			(type default)
		)
		(layer "In6.Cu")
	)
	(gr_line
		(start 170.337988 -5.646928)
		(end 170.591988 -5.646928)
		(stroke
			(width 0.1016)
			(type default)
		)
		(layer "In6.Cu")
	)
	(gr_line
		(start 170.363388 -12.512548)
		(end 170.363388 -9.947148)
		(stroke
			(width 0.2032)
			(type default)
		)
		(layer "In6.Cu")
	)
	(gr_line
		(start 170.363388 -12.412472)
		(end 170.363388 -9.847072)
		(stroke
			(width 0.2032)
			(type default)
		)
		(layer "In6.Cu")
	)
	(gr_line
		(start 170.363388 -9.947148)
		(end 171.379388 -9.947148)
		(stroke
			(width 0.2032)
			(type default)
		)
		(layer "In6.Cu")
	)
	(gr_line
		(start 170.363388 -9.847072)
		(end 171.379388 -9.847072)
		(stroke
			(width 0.2032)
			(type default)
		)
		(layer "In6.Cu")
	)
	(gr_line
		(start 170.363388 -8.312404)
		(end 170.363388 -5.747004)
		(stroke
			(width 0.2032)
			(type default)
		)
		(layer "In6.Cu")
	)
	(gr_line
		(start 170.363388 -8.212328)
		(end 170.363388 -5.646928)
		(stroke
			(width 0.2032)
			(type default)
		)
		(layer "In6.Cu")
	)
	(gr_line
		(start 170.363388 -5.747004)
		(end 171.379388 -5.747004)
		(stroke
			(width 0.2032)
			(type default)
		)
		(layer "In6.Cu")
	)
	(gr_line
		(start 170.363388 -5.646928)
		(end 171.379388 -5.646928)
		(stroke
			(width 0.2032)
			(type default)
		)
		(layer "In6.Cu")
	)
	(gr_line
		(start 170.414188 -12.487148)
		(end 170.414188 -9.997948)
		(stroke
			(width 0.2032)
			(type default)
		)
		(layer "In6.Cu")
	)
	(gr_line
		(start 170.414188 -12.487148)
		(end 170.414188 -9.997948)
		(stroke
			(width 0.254)
			(type default)
		)
		(layer "In6.Cu")
	)
	(gr_line
		(start 170.414188 -12.387072)
		(end 170.414188 -9.897872)
		(stroke
			(width 0.2032)
			(type default)
		)
		(layer "In6.Cu")
	)
	(gr_line
		(start 170.414188 -12.387072)
		(end 170.414188 -9.897872)
		(stroke
			(width 0.254)
			(type default)
		)
		(layer "In6.Cu")
	)
	(gr_line
		(start 170.414188 -9.997948)
		(end 170.617388 -9.997948)
		(stroke
			(width 0.2032)
			(type default)
		)
		(layer "In6.Cu")
	)
	(gr_line
		(start 170.414188 -9.997948)
		(end 171.303188 -9.997948)
		(stroke
			(width 0.254)
			(type default)
		)
		(layer "In6.Cu")
	)
	(gr_line
		(start 170.414188 -9.897872)
		(end 170.617388 -9.897872)
		(stroke
			(width 0.2032)
			(type default)
		)
		(layer "In6.Cu")
	)
	(gr_line
		(start 170.414188 -9.897872)
		(end 171.303188 -9.897872)
		(stroke
			(width 0.254)
			(type default)
		)
		(layer "In6.Cu")
	)
	(gr_line
		(start 170.414188 -8.287004)
		(end 170.414188 -5.797804)
		(stroke
			(width 0.2032)
			(type default)
		)
		(layer "In6.Cu")
	)
	(gr_line
		(start 170.414188 -8.287004)
		(end 170.414188 -5.797804)
		(stroke
			(width 0.254)
			(type default)
		)
		(layer "In6.Cu")
	)
	(gr_line
		(start 170.414188 -8.186928)
		(end 170.414188 -5.697728)
		(stroke
			(width 0.2032)
			(type default)
		)
		(layer "In6.Cu")
	)
	(gr_line
		(start 170.414188 -8.186928)
		(end 170.414188 -5.697728)
		(stroke
			(width 0.254)
			(type default)
		)
		(layer "In6.Cu")
	)
	(gr_line
		(start 170.414188 -5.797804)
		(end 170.617388 -5.797804)
		(stroke
			(width 0.2032)
			(type default)
		)
		(layer "In6.Cu")
	)
	(gr_line
		(start 170.414188 -5.797804)
		(end 171.303188 -5.797804)
		(stroke
			(width 0.254)
			(type default)
		)
		(layer "In6.Cu")
	)
	(gr_line
		(start 170.414188 -5.697728)
		(end 170.617388 -5.697728)
		(stroke
			(width 0.2032)
			(type default)
		)
		(layer "In6.Cu")
	)
	(gr_line
		(start 170.414188 -5.697728)
		(end 171.303188 -5.697728)
		(stroke
			(width 0.254)
			(type default)
		)
		(layer "In6.Cu")
	)
	(gr_line
		(start 170.439588 -12.461748)
		(end 170.439588 -10.023348)
		(stroke
			(width 0.254)
			(type default)
		)
		(layer "In6.Cu")
	)
	(gr_line
		(start 170.439588 -12.361672)
		(end 170.439588 -9.923272)
		(stroke
			(width 0.254)
			(type default)
		)
		(layer "In6.Cu")
	)
	(gr_line
		(start 170.439588 -10.023348)
		(end 171.277788 -10.023348)
		(stroke
			(width 0.254)
			(type default)
		)
		(layer "In6.Cu")
	)
	(gr_line
		(start 170.439588 -9.923272)
		(end 171.277788 -9.923272)
		(stroke
			(width 0.254)
			(type default)
		)
		(layer "In6.Cu")
	)
	(gr_line
		(start 170.439588 -8.261604)
		(end 170.439588 -5.823204)
		(stroke
			(width 0.254)
			(type default)
		)
		(layer "In6.Cu")
	)
	(gr_line
		(start 170.439588 -8.161528)
		(end 170.439588 -5.723128)
		(stroke
			(width 0.254)
			(type default)
		)
		(layer "In6.Cu")
	)
	(gr_line
		(start 170.439588 -5.823204)
		(end 171.277788 -5.823204)
		(stroke
			(width 0.254)
			(type default)
		)
		(layer "In6.Cu")
	)
	(gr_line
		(start 170.439588 -5.723128)
		(end 171.277788 -5.723128)
		(stroke
			(width 0.254)
			(type default)
		)
		(layer "In6.Cu")
	)
	(gr_line
		(start 170.464988 -12.436348)
		(end 170.464988 -10.048748)
		(stroke
			(width 0.254)
			(type default)
		)
		(layer "In6.Cu")
	)
	(gr_line
		(start 170.464988 -12.336272)
		(end 170.464988 -9.948672)
		(stroke
			(width 0.254)
			(type default)
		)
		(layer "In6.Cu")
	)
	(gr_line
		(start 170.464988 -10.048748)
		(end 171.252388 -10.048748)
		(stroke
			(width 0.254)
			(type default)
		)
		(layer "In6.Cu")
	)
	(gr_line
		(start 170.464988 -9.948672)
		(end 171.252388 -9.948672)
		(stroke
			(width 0.254)
			(type default)
		)
		(layer "In6.Cu")
	)
	(gr_line
		(start 170.464988 -8.236204)
		(end 170.464988 -5.848604)
		(stroke
			(width 0.254)
			(type default)
		)
		(layer "In6.Cu")
	)
	(gr_line
		(start 170.464988 -8.136128)
		(end 170.464988 -5.748528)
		(stroke
			(width 0.254)
			(type default)
		)
		(layer "In6.Cu")
	)
	(gr_line
		(start 170.464988 -5.848604)
		(end 171.252388 -5.848604)
		(stroke
			(width 0.254)
			(type default)
		)
		(layer "In6.Cu")
	)
	(gr_line
		(start 170.464988 -5.748528)
		(end 171.252388 -5.748528)
		(stroke
			(width 0.254)
			(type default)
		)
		(layer "In6.Cu")
	)
	(gr_line
		(start 170.490388 -12.360148)
		(end 171.125388 -12.360148)
		(stroke
			(width 0.508)
			(type default)
		)
		(layer "In6.Cu")
	)
	(gr_line
		(start 170.490388 -12.260072)
		(end 171.125388 -12.260072)
		(stroke
			(width 0.508)
			(type default)
		)
		(layer "In6.Cu")
	)
	(gr_line
		(start 170.490388 -10.175748)
		(end 171.125388 -10.175748)
		(stroke
			(width 0.508)
			(type default)
		)
		(layer "In6.Cu")
	)
	(gr_line
		(start 170.490388 -10.124948)
		(end 171.125388 -10.124948)
		(stroke
			(width 0.508)
			(type default)
		)
		(layer "In6.Cu")
	)
	(gr_line
		(start 170.490388 -10.075672)
		(end 171.125388 -10.075672)
		(stroke
			(width 0.508)
			(type default)
		)
		(layer "In6.Cu")
	)
	(gr_line
		(start 170.490388 -10.024872)
		(end 171.125388 -10.024872)
		(stroke
			(width 0.508)
			(type default)
		)
		(layer "In6.Cu")
	)
	(gr_line
		(start 170.490388 -8.160004)
		(end 171.125388 -8.160004)
		(stroke
			(width 0.508)
			(type default)
		)
		(layer "In6.Cu")
	)
	(gr_line
		(start 170.490388 -8.059928)
		(end 171.125388 -8.059928)
		(stroke
			(width 0.508)
			(type default)
		)
		(layer "In6.Cu")
	)
	(gr_line
		(start 170.490388 -5.975604)
		(end 171.125388 -5.975604)
		(stroke
			(width 0.508)
			(type default)
		)
		(layer "In6.Cu")
	)
	(gr_line
		(start 170.490388 -5.924804)
		(end 171.125388 -5.924804)
		(stroke
			(width 0.508)
			(type default)
		)
		(layer "In6.Cu")
	)
	(gr_line
		(start 170.490388 -5.875528)
		(end 171.125388 -5.875528)
		(stroke
			(width 0.508)
			(type default)
		)
		(layer "In6.Cu")
	)
	(gr_line
		(start 170.490388 -5.824728)
		(end 171.125388 -5.824728)
		(stroke
			(width 0.508)
			(type default)
		)
		(layer "In6.Cu")
	)
	(gr_line
		(start 170.515788 -10.429748)
		(end 171.150788 -10.429748)
		(stroke
			(width 0.508)
			(type default)
		)
		(layer "In6.Cu")
	)
	(gr_line
		(start 170.515788 -10.329672)
		(end 171.150788 -10.329672)
		(stroke
			(width 0.508)
			(type default)
		)
		(layer "In6.Cu")
	)
	(gr_line
		(start 170.515788 -6.229604)
		(end 171.150788 -6.229604)
		(stroke
			(width 0.508)
			(type default)
		)
		(layer "In6.Cu")
	)
	(gr_line
		(start 170.515788 -6.129528)
		(end 171.150788 -6.129528)
		(stroke
			(width 0.508)
			(type default)
		)
		(layer "In6.Cu")
	)
	(gr_line
		(start 170.541188 -12.385548)
		(end 170.541188 -10.124948)
		(stroke
			(width 0.254)
			(type default)
		)
		(layer "In6.Cu")
	)
	(gr_line
		(start 170.541188 -12.285472)
		(end 170.541188 -10.024872)
		(stroke
			(width 0.254)
			(type default)
		)
		(layer "In6.Cu")
	)
	(gr_line
		(start 170.541188 -12.233148)
		(end 171.176188 -12.233148)
		(stroke
			(width 0.508)
			(type default)
		)
		(layer "In6.Cu")
	)
	(gr_line
		(start 170.541188 -12.133072)
		(end 171.176188 -12.133072)
		(stroke
			(width 0.508)
			(type default)
		)
		(layer "In6.Cu")
	)
	(gr_line
		(start 170.541188 -10.124948)
		(end 171.176188 -10.124948)
		(stroke
			(width 0.254)
			(type default)
		)
		(layer "In6.Cu")
	)
	(gr_line
		(start 170.541188 -10.024872)
		(end 171.176188 -10.024872)
		(stroke
			(width 0.254)
			(type default)
		)
		(layer "In6.Cu")
	)
	(gr_line
		(start 170.541188 -8.185404)
		(end 170.541188 -5.924804)
		(stroke
			(width 0.254)
			(type default)
		)
		(layer "In6.Cu")
	)
	(gr_line
		(start 170.541188 -8.085328)
		(end 170.541188 -5.824728)
		(stroke
			(width 0.254)
			(type default)
		)
		(layer "In6.Cu")
	)
	(gr_line
		(start 170.541188 -8.033004)
		(end 171.176188 -8.033004)
		(stroke
			(width 0.508)
			(type default)
		)
		(layer "In6.Cu")
	)
	(gr_line
		(start 170.541188 -7.932928)
		(end 171.176188 -7.932928)
		(stroke
			(width 0.508)
			(type default)
		)
		(layer "In6.Cu")
	)
	(gr_line
		(start 170.541188 -5.924804)
		(end 171.176188 -5.924804)
		(stroke
			(width 0.254)
			(type default)
		)
		(layer "In6.Cu")
	)
	(gr_line
		(start 170.541188 -5.824728)
		(end 171.176188 -5.824728)
		(stroke
			(width 0.254)
			(type default)
		)
		(layer "In6.Cu")
	)
	(gr_line
		(start 170.566588 -12.080748)
		(end 171.201588 -12.080748)
		(stroke
			(width 0.508)
			(type default)
		)
		(layer "In6.Cu")
	)
	(gr_line
		(start 170.566588 -11.980672)
		(end 171.201588 -11.980672)
		(stroke
			(width 0.508)
			(type default)
		)
		(layer "In6.Cu")
	)
	(gr_line
		(start 170.566588 -7.880604)
		(end 171.201588 -7.880604)
		(stroke
			(width 0.508)
			(type default)
		)
		(layer "In6.Cu")
	)
	(gr_line
		(start 170.566588 -7.780528)
		(end 171.201588 -7.780528)
		(stroke
			(width 0.508)
			(type default)
		)
		(layer "In6.Cu")
	)
	(gr_line
		(start 170.591988 -12.360148)
		(end 171.226988 -12.360148)
		(stroke
			(width 0.508)
			(type default)
		)
		(layer "In6.Cu")
	)
	(gr_line
		(start 170.591988 -12.260072)
		(end 171.226988 -12.260072)
		(stroke
			(width 0.508)
			(type default)
		)
		(layer "In6.Cu")
	)
	(gr_line
		(start 170.591988 -9.947148)
		(end 171.430188 -9.947148)
		(stroke
			(width 0.2032)
			(type default)
		)
		(layer "In6.Cu")
	)
	(gr_line
		(start 170.591988 -9.847072)
		(end 171.430188 -9.847072)
		(stroke
			(width 0.2032)
			(type default)
		)
		(layer "In6.Cu")
	)
	(gr_line
		(start 170.591988 -8.160004)
		(end 171.226988 -8.160004)
		(stroke
			(width 0.508)
			(type default)
		)
		(layer "In6.Cu")
	)
	(gr_line
		(start 170.591988 -8.059928)
		(end 171.226988 -8.059928)
		(stroke
			(width 0.508)
			(type default)
		)
		(layer "In6.Cu")
	)
	(gr_line
		(start 170.591988 -5.747004)
		(end 171.430188 -5.747004)
		(stroke
			(width 0.2032)
			(type default)
		)
		(layer "In6.Cu")
	)
	(gr_line
		(start 170.591988 -5.646928)
		(end 171.430188 -5.646928)
		(stroke
			(width 0.2032)
			(type default)
		)
		(layer "In6.Cu")
	)
	(gr_line
		(start 170.617388 -12.360148)
		(end 170.617388 -10.175748)
		(stroke
			(width 0.254)
			(type default)
		)
		(layer "In6.Cu")
	)
	(gr_line
		(start 170.617388 -12.260072)
		(end 170.617388 -10.075672)
		(stroke
			(width 0.254)
			(type default)
		)
		(layer "In6.Cu")
	)
	(gr_line
		(start 170.617388 -10.175748)
		(end 171.099988 -10.175748)
		(stroke
			(width 0.254)
			(type default)
		)
		(layer "In6.Cu")
	)
	(gr_line
		(start 170.617388 -10.075672)
		(end 171.099988 -10.075672)
		(stroke
			(width 0.254)
			(type default)
		)
		(layer "In6.Cu")
	)
	(gr_line
		(start 170.617388 -9.997948)
		(end 171.353988 -9.997948)
		(stroke
			(width 0.254)
			(type default)
		)
		(layer "In6.Cu")
	)
	(gr_line
		(start 170.617388 -9.897872)
		(end 171.353988 -9.897872)
		(stroke
			(width 0.254)
			(type default)
		)
		(layer "In6.Cu")
	)
	(gr_line
		(start 170.617388 -8.160004)
		(end 170.617388 -5.975604)
		(stroke
			(width 0.254)
			(type default)
		)
		(layer "In6.Cu")
	)
	(gr_line
		(start 170.617388 -8.059928)
		(end 170.617388 -5.875528)
		(stroke
			(width 0.254)
			(type default)
		)
		(layer "In6.Cu")
	)
	(gr_line
		(start 170.617388 -5.975604)
		(end 171.099988 -5.975604)
		(stroke
			(width 0.254)
			(type default)
		)
		(layer "In6.Cu")
	)
	(gr_line
		(start 170.617388 -5.875528)
		(end 171.099988 -5.875528)
		(stroke
			(width 0.254)
			(type default)
		)
		(layer "In6.Cu")
	)
	(gr_line
		(start 170.617388 -5.797804)
		(end 171.353988 -5.797804)
		(stroke
			(width 0.254)
			(type default)
		)
		(layer "In6.Cu")
	)
	(gr_line
		(start 170.617388 -5.697728)
		(end 171.353988 -5.697728)
		(stroke
			(width 0.254)
			(type default)
		)
		(layer "In6.Cu")
	)
	(gr_line
		(start 170.63593 -10.110978)
		(end 171.27093 -10.110978)
		(stroke
			(width 0.508)
			(type default)
		)
		(layer "In6.Cu")
	)
	(gr_line
		(start 170.63593 -10.010902)
		(end 171.27093 -10.010902)
		(stroke
			(width 0.508)
			(type default)
		)
		(layer "In6.Cu")
	)
	(gr_line
		(start 170.63593 -5.910834)
		(end 171.27093 -5.910834)
		(stroke
			(width 0.508)
			(type default)
		)
		(layer "In6.Cu")
	)
	(gr_line
		(start 170.63593 -5.810758)
		(end 171.27093 -5.810758)
		(stroke
			(width 0.508)
			(type default)
		)
		(layer "In6.Cu")
	)
	(gr_line
		(start 170.642788 -12.360148)
		(end 171.277788 -12.360148)
		(stroke
			(width 0.508)
			(type default)
		)
		(layer "In6.Cu")
	)
	(gr_line
		(start 170.642788 -12.260072)
		(end 171.277788 -12.260072)
		(stroke
			(width 0.508)
			(type default)
		)
		(layer "In6.Cu")
	)
	(gr_line
		(start 170.642788 -12.233148)
		(end 170.642788 -10.251948)
		(stroke
			(width 0.762)
			(type default)
		)
		(layer "In6.Cu")
	)
	(gr_line
		(start 170.642788 -12.133072)
		(end 170.642788 -10.151872)
		(stroke
			(width 0.762)
			(type default)
		)
		(layer "In6.Cu")
	)
	(gr_line
		(start 170.642788 -10.251948)
		(end 171.277788 -10.251948)
		(stroke
			(width 0.508)
			(type default)
		)
		(layer "In6.Cu")
	)
	(gr_line
		(start 170.642788 -10.151872)
		(end 171.277788 -10.151872)
		(stroke
			(width 0.508)
			(type default)
		)
		(layer "In6.Cu")
	)
	(gr_line
		(start 170.642788 -8.160004)
		(end 171.277788 -8.160004)
		(stroke
			(width 0.508)
			(type default)
		)
		(layer "In6.Cu")
	)
	(gr_line
		(start 170.642788 -8.059928)
		(end 171.277788 -8.059928)
		(stroke
			(width 0.508)
			(type default)
		)
		(layer "In6.Cu")
	)
	(gr_line
		(start 170.642788 -8.033004)
		(end 170.642788 -6.051804)
		(stroke
			(width 0.762)
			(type default)
		)
		(layer "In6.Cu")
	)
	(gr_line
		(start 170.642788 -7.932928)
		(end 170.642788 -5.951728)
		(stroke
			(width 0.762)
			(type default)
		)
		(layer "In6.Cu")
	)
	(gr_line
		(start 170.642788 -6.051804)
		(end 171.277788 -6.051804)
		(stroke
			(width 0.508)
			(type default)
		)
		(layer "In6.Cu")
	)
	(gr_line
		(start 170.642788 -5.951728)
		(end 171.277788 -5.951728)
		(stroke
			(width 0.508)
			(type default)
		)
		(layer "In6.Cu")
	)
	(gr_line
		(start 170.693588 -12.283948)
		(end 170.693588 -10.251948)
		(stroke
			(width 0.254)
			(type default)
		)
		(layer "In6.Cu")
	)
	(gr_line
		(start 170.693588 -12.183872)
		(end 170.693588 -10.151872)
		(stroke
			(width 0.254)
			(type default)
		)
		(layer "In6.Cu")
	)
	(gr_line
		(start 170.693588 -10.251948)
		(end 171.023788 -10.251948)
		(stroke
			(width 0.254)
			(type default)
		)
		(layer "In6.Cu")
	)
	(gr_line
		(start 170.693588 -10.151872)
		(end 171.023788 -10.151872)
		(stroke
			(width 0.254)
			(type default)
		)
		(layer "In6.Cu")
	)
	(gr_line
		(start 170.693588 -8.083804)
		(end 170.693588 -6.051804)
		(stroke
			(width 0.254)
			(type default)
		)
		(layer "In6.Cu")
	)
	(gr_line
		(start 170.693588 -7.983728)
		(end 170.693588 -5.951728)
		(stroke
			(width 0.254)
			(type default)
		)
		(layer "In6.Cu")
	)
	(gr_line
		(start 170.693588 -6.051804)
		(end 171.023788 -6.051804)
		(stroke
			(width 0.254)
			(type default)
		)
		(layer "In6.Cu")
	)
	(gr_line
		(start 170.693588 -5.951728)
		(end 171.023788 -5.951728)
		(stroke
			(width 0.254)
			(type default)
		)
		(layer "In6.Cu")
	)
	(gr_line
		(start 170.795188 -12.207748)
		(end 170.795188 -10.404348)
		(stroke
			(width 0.254)
			(type default)
		)
		(layer "In6.Cu")
	)
	(gr_line
		(start 170.795188 -12.207748)
		(end 170.795188 -10.226548)
		(stroke
			(width 0.762)
			(type default)
		)
		(layer "In6.Cu")
	)
	(gr_line
		(start 170.795188 -12.107672)
		(end 170.795188 -10.304272)
		(stroke
			(width 0.254)
			(type default)
		)
		(layer "In6.Cu")
	)
	(gr_line
		(start 170.795188 -12.107672)
		(end 170.795188 -10.126472)
		(stroke
			(width 0.762)
			(type default)
		)
		(layer "In6.Cu")
	)
	(gr_line
		(start 170.795188 -10.404348)
		(end 170.896788 -10.404348)
		(stroke
			(width 0.254)
			(type default)
		)
		(layer "In6.Cu")
	)
	(gr_line
		(start 170.795188 -10.304272)
		(end 170.896788 -10.304272)
		(stroke
			(width 0.254)
			(type default)
		)
		(layer "In6.Cu")
	)
	(gr_line
		(start 170.795188 -8.007604)
		(end 170.795188 -6.204204)
		(stroke
			(width 0.254)
			(type default)
		)
		(layer "In6.Cu")
	)
	(gr_line
		(start 170.795188 -8.007604)
		(end 170.795188 -6.026404)
		(stroke
			(width 0.762)
			(type default)
		)
		(layer "In6.Cu")
	)
	(gr_line
		(start 170.795188 -7.907528)
		(end 170.795188 -6.104128)
		(stroke
			(width 0.254)
			(type default)
		)
		(layer "In6.Cu")
	)
	(gr_line
		(start 170.795188 -7.907528)
		(end 170.795188 -5.926328)
		(stroke
			(width 0.762)
			(type default)
		)
		(layer "In6.Cu")
	)
	(gr_line
		(start 170.795188 -6.204204)
		(end 170.896788 -6.204204)
		(stroke
			(width 0.254)
			(type default)
		)
		(layer "In6.Cu")
	)
	(gr_line
		(start 170.795188 -6.104128)
		(end 170.896788 -6.104128)
		(stroke
			(width 0.254)
			(type default)
		)
		(layer "In6.Cu")
	)
	(gr_line
		(start 170.896788 -12.309348)
		(end 170.845988 -12.309348)
		(stroke
			(width 0.254)
			(type default)
		)
		(layer "In6.Cu")
	)
	(gr_line
		(start 170.896788 -12.209272)
		(end 170.845988 -12.209272)
		(stroke
			(width 0.254)
			(type default)
		)
		(layer "In6.Cu")
	)
	(gr_line
		(start 170.896788 -10.404348)
		(end 170.896788 -12.309348)
		(stroke
			(width 0.254)
			(type default)
		)
		(layer "In6.Cu")
	)
	(gr_line
		(start 170.896788 -10.304272)
		(end 170.896788 -12.209272)
		(stroke
			(width 0.254)
			(type default)
		)
		(layer "In6.Cu")
	)
	(gr_line
		(start 170.896788 -8.109204)
		(end 170.845988 -8.109204)
		(stroke
			(width 0.254)
			(type default)
		)
		(layer "In6.Cu")
	)
	(gr_line
		(start 170.896788 -8.009128)
		(end 170.845988 -8.009128)
		(stroke
			(width 0.254)
			(type default)
		)
		(layer "In6.Cu")
	)
	(gr_line
		(start 170.896788 -6.204204)
		(end 170.896788 -8.109204)
		(stroke
			(width 0.254)
			(type default)
		)
		(layer "In6.Cu")
	)
	(gr_line
		(start 170.896788 -6.104128)
		(end 170.896788 -8.009128)
		(stroke
			(width 0.254)
			(type default)
		)
		(layer "In6.Cu")
	)
	(gr_line
		(start 170.947588 -12.233148)
		(end 170.947588 -10.251948)
		(stroke
			(width 0.762)
			(type default)
		)
		(layer "In6.Cu")
	)
	(gr_line
		(start 170.947588 -12.133072)
		(end 170.947588 -10.151872)
		(stroke
			(width 0.762)
			(type default)
		)
		(layer "In6.Cu")
	)
	(gr_line
		(start 170.947588 -8.033004)
		(end 170.947588 -6.051804)
		(stroke
			(width 0.762)
			(type default)
		)
		(layer "In6.Cu")
	)
	(gr_line
		(start 170.947588 -7.932928)
		(end 170.947588 -5.951728)
		(stroke
			(width 0.762)
			(type default)
		)
		(layer "In6.Cu")
	)
	(gr_line
		(start 171.023788 -12.207748)
		(end 170.795188 -12.207748)
		(stroke
			(width 0.254)
			(type default)
		)
		(layer "In6.Cu")
	)
	(gr_line
		(start 171.023788 -12.107672)
		(end 170.795188 -12.107672)
		(stroke
			(width 0.254)
			(type default)
		)
		(layer "In6.Cu")
	)
	(gr_line
		(start 171.023788 -10.251948)
		(end 171.023788 -12.207748)
		(stroke
			(width 0.254)
			(type default)
		)
		(layer "In6.Cu")
	)
	(gr_line
		(start 171.023788 -10.151872)
		(end 171.023788 -12.107672)
		(stroke
			(width 0.254)
			(type default)
		)
		(layer "In6.Cu")
	)
	(gr_line
		(start 171.023788 -8.007604)
		(end 170.795188 -8.007604)
		(stroke
			(width 0.254)
			(type default)
		)
		(layer "In6.Cu")
	)
	(gr_line
		(start 171.023788 -7.907528)
		(end 170.795188 -7.907528)
		(stroke
			(width 0.254)
			(type default)
		)
		(layer "In6.Cu")
	)
	(gr_line
		(start 171.023788 -6.051804)
		(end 171.023788 -8.007604)
		(stroke
			(width 0.254)
			(type default)
		)
		(layer "In6.Cu")
	)
	(gr_line
		(start 171.023788 -5.951728)
		(end 171.023788 -7.907528)
		(stroke
			(width 0.254)
			(type default)
		)
		(layer "In6.Cu")
	)
	(gr_line
		(start 171.074588 -12.563348)
		(end 171.074588 -12.512548)
		(stroke
			(width 0.1016)
			(type default)
		)
		(layer "In6.Cu")
	)
	(gr_line
		(start 171.074588 -12.563348)
		(end 171.480988 -12.563348)
		(stroke
			(width 0.1016)
			(type default)
		)
		(layer "In6.Cu")
	)
	(gr_line
		(start 171.074588 -12.512548)
		(end 170.312588 -12.512548)
		(stroke
			(width 0.1016)
			(type default)
		)
		(layer "In6.Cu")
	)
	(gr_line
		(start 171.074588 -12.463272)
		(end 171.074588 -12.412472)
		(stroke
			(width 0.1016)
			(type default)
		)
		(layer "In6.Cu")
	)
	(gr_line
		(start 171.074588 -12.463272)
		(end 171.480988 -12.463272)
		(stroke
			(width 0.1016)
			(type default)
		)
		(layer "In6.Cu")
	)
	(gr_line
		(start 171.074588 -12.412472)
		(end 170.312588 -12.412472)
		(stroke
			(width 0.1016)
			(type default)
		)
		(layer "In6.Cu")
	)
	(gr_line
		(start 171.074588 -12.233148)
		(end 171.074588 -10.251948)
		(stroke
			(width 0.762)
			(type default)
		)
		(layer "In6.Cu")
	)
	(gr_line
		(start 171.074588 -12.133072)
		(end 171.074588 -10.151872)
		(stroke
			(width 0.762)
			(type default)
		)
		(layer "In6.Cu")
	)
	(gr_line
		(start 171.074588 -8.363204)
		(end 171.074588 -8.312404)
		(stroke
			(width 0.1016)
			(type default)
		)
		(layer "In6.Cu")
	)
	(gr_line
		(start 171.074588 -8.363204)
		(end 171.480988 -8.363204)
		(stroke
			(width 0.1016)
			(type default)
		)
		(layer "In6.Cu")
	)
	(gr_line
		(start 171.074588 -8.312404)
		(end 170.312588 -8.312404)
		(stroke
			(width 0.1016)
			(type default)
		)
		(layer "In6.Cu")
	)
	(gr_line
		(start 171.074588 -8.263128)
		(end 171.074588 -8.212328)
		(stroke
			(width 0.1016)
			(type default)
		)
		(layer "In6.Cu")
	)
	(gr_line
		(start 171.074588 -8.263128)
		(end 171.480988 -8.263128)
		(stroke
			(width 0.1016)
			(type default)
		)
		(layer "In6.Cu")
	)
	(gr_line
		(start 171.074588 -8.212328)
		(end 170.312588 -8.212328)
		(stroke
			(width 0.1016)
			(type default)
		)
		(layer "In6.Cu")
	)
	(gr_line
		(start 171.074588 -8.033004)
		(end 171.074588 -6.051804)
		(stroke
			(width 0.762)
			(type default)
		)
		(layer "In6.Cu")
	)
	(gr_line
		(start 171.074588 -7.932928)
		(end 171.074588 -5.951728)
		(stroke
			(width 0.762)
			(type default)
		)
		(layer "In6.Cu")
	)
	(gr_line
		(start 171.099988 -12.283948)
		(end 170.693588 -12.283948)
		(stroke
			(width 0.254)
			(type default)
		)
		(layer "In6.Cu")
	)
	(gr_line
		(start 171.099988 -12.183872)
		(end 170.693588 -12.183872)
		(stroke
			(width 0.254)
			(type default)
		)
		(layer "In6.Cu")
	)
	(gr_line
		(start 171.099988 -10.175748)
		(end 171.099988 -12.283948)
		(stroke
			(width 0.254)
			(type default)
		)
		(layer "In6.Cu")
	)
	(gr_line
		(start 171.099988 -10.075672)
		(end 171.099988 -12.183872)
		(stroke
			(width 0.254)
			(type default)
		)
		(layer "In6.Cu")
	)
	(gr_line
		(start 171.099988 -8.083804)
		(end 170.693588 -8.083804)
		(stroke
			(width 0.254)
			(type default)
		)
		(layer "In6.Cu")
	)
	(gr_line
		(start 171.099988 -7.983728)
		(end 170.693588 -7.983728)
		(stroke
			(width 0.254)
			(type default)
		)
		(layer "In6.Cu")
	)
	(gr_line
		(start 171.099988 -5.975604)
		(end 171.099988 -8.083804)
		(stroke
			(width 0.254)
			(type default)
		)
		(layer "In6.Cu")
	)
	(gr_line
		(start 171.099988 -5.875528)
		(end 171.099988 -7.983728)
		(stroke
			(width 0.254)
			(type default)
		)
		(layer "In6.Cu")
	)
	(gr_line
		(start 171.150788 -12.233148)
		(end 171.150788 -10.251948)
		(stroke
			(width 0.762)
			(type default)
		)
		(layer "In6.Cu")
	)
	(gr_line
		(start 171.150788 -12.133072)
		(end 171.150788 -10.151872)
		(stroke
			(width 0.762)
			(type default)
		)
		(layer "In6.Cu")
	)
	(gr_line
		(start 171.150788 -8.033004)
		(end 171.150788 -6.051804)
		(stroke
			(width 0.762)
			(type default)
		)
		(layer "In6.Cu")
	)
	(gr_line
		(start 171.150788 -7.932928)
		(end 171.150788 -5.951728)
		(stroke
			(width 0.762)
			(type default)
		)
		(layer "In6.Cu")
	)
	(gr_line
		(start 171.176188 -12.360148)
		(end 170.617388 -12.360148)
		(stroke
			(width 0.254)
			(type default)
		)
		(layer "In6.Cu")
	)
	(gr_line
		(start 171.176188 -12.260072)
		(end 170.617388 -12.260072)
		(stroke
			(width 0.254)
			(type default)
		)
		(layer "In6.Cu")
	)
	(gr_line
		(start 171.176188 -10.124948)
		(end 171.176188 -12.360148)
		(stroke
			(width 0.254)
			(type default)
		)
		(layer "In6.Cu")
	)
	(gr_line
		(start 171.176188 -10.024872)
		(end 171.176188 -12.260072)
		(stroke
			(width 0.254)
			(type default)
		)
		(layer "In6.Cu")
	)
	(gr_line
		(start 171.176188 -8.160004)
		(end 170.617388 -8.160004)
		(stroke
			(width 0.254)
			(type default)
		)
		(layer "In6.Cu")
	)
	(gr_line
		(start 171.176188 -8.059928)
		(end 170.617388 -8.059928)
		(stroke
			(width 0.254)
			(type default)
		)
		(layer "In6.Cu")
	)
	(gr_line
		(start 171.176188 -5.924804)
		(end 171.176188 -8.160004)
		(stroke
			(width 0.254)
			(type default)
		)
		(layer "In6.Cu")
	)
	(gr_line
		(start 171.176188 -5.824728)
		(end 171.176188 -8.059928)
		(stroke
			(width 0.254)
			(type default)
		)
		(layer "In6.Cu")
	)
	(gr_line
		(start 171.252388 -12.385548)
		(end 170.541188 -12.385548)
		(stroke
			(width 0.254)
			(type default)
		)
		(layer "In6.Cu")
	)
	(gr_line
		(start 171.252388 -12.285472)
		(end 170.541188 -12.285472)
		(stroke
			(width 0.254)
			(type default)
		)
		(layer "In6.Cu")
	)
	(gr_line
		(start 171.252388 -10.048748)
		(end 171.252388 -12.385548)
		(stroke
			(width 0.254)
			(type default)
		)
		(layer "In6.Cu")
	)
	(gr_line
		(start 171.252388 -9.948672)
		(end 171.252388 -12.285472)
		(stroke
			(width 0.254)
			(type default)
		)
		(layer "In6.Cu")
	)
	(gr_line
		(start 171.252388 -8.185404)
		(end 170.541188 -8.185404)
		(stroke
			(width 0.254)
			(type default)
		)
		(layer "In6.Cu")
	)
	(gr_line
		(start 171.252388 -8.085328)
		(end 170.541188 -8.085328)
		(stroke
			(width 0.254)
			(type default)
		)
		(layer "In6.Cu")
	)
	(gr_line
		(start 171.252388 -5.848604)
		(end 171.252388 -8.185404)
		(stroke
			(width 0.254)
			(type default)
		)
		(layer "In6.Cu")
	)
	(gr_line
		(start 171.252388 -5.748528)
		(end 171.252388 -8.085328)
		(stroke
			(width 0.254)
			(type default)
		)
		(layer "In6.Cu")
	)
	(gr_line
		(start 171.277788 -12.512548)
		(end 170.287188 -12.512548)
		(stroke
			(width 0.1016)
			(type default)
		)
		(layer "In6.Cu")
	)
	(gr_line
		(start 171.277788 -12.436348)
		(end 170.464988 -12.436348)
		(stroke
			(width 0.254)
			(type default)
		)
		(layer "In6.Cu")
	)
	(gr_line
		(start 171.277788 -12.412472)
		(end 170.287188 -12.412472)
		(stroke
			(width 0.1016)
			(type default)
		)
		(layer "In6.Cu")
	)
	(gr_line
		(start 171.277788 -12.336272)
		(end 170.464988 -12.336272)
		(stroke
			(width 0.254)
			(type default)
		)
		(layer "In6.Cu")
	)
	(gr_line
		(start 171.277788 -10.023348)
		(end 171.277788 -12.436348)
		(stroke
			(width 0.254)
			(type default)
		)
		(layer "In6.Cu")
	)
	(gr_line
		(start 171.277788 -9.923272)
		(end 171.277788 -12.336272)
		(stroke
			(width 0.254)
			(type default)
		)
		(layer "In6.Cu")
	)
	(gr_line
		(start 171.277788 -8.312404)
		(end 170.287188 -8.312404)
		(stroke
			(width 0.1016)
			(type default)
		)
		(layer "In6.Cu")
	)
	(gr_line
		(start 171.277788 -8.236204)
		(end 170.464988 -8.236204)
		(stroke
			(width 0.254)
			(type default)
		)
		(layer "In6.Cu")
	)
	(gr_line
		(start 171.277788 -8.212328)
		(end 170.287188 -8.212328)
		(stroke
			(width 0.1016)
			(type default)
		)
		(layer "In6.Cu")
	)
	(gr_line
		(start 171.277788 -8.136128)
		(end 170.464988 -8.136128)
		(stroke
			(width 0.254)
			(type default)
		)
		(layer "In6.Cu")
	)
	(gr_line
		(start 171.277788 -5.823204)
		(end 171.277788 -8.236204)
		(stroke
			(width 0.254)
			(type default)
		)
		(layer "In6.Cu")
	)
	(gr_line
		(start 171.277788 -5.723128)
		(end 171.277788 -8.136128)
		(stroke
			(width 0.254)
			(type default)
		)
		(layer "In6.Cu")
	)
	(gr_line
		(start 171.303188 -12.461748)
		(end 170.439588 -12.461748)
		(stroke
			(width 0.254)
			(type default)
		)
		(layer "In6.Cu")
	)
	(gr_line
		(start 171.303188 -12.361672)
		(end 170.439588 -12.361672)
		(stroke
			(width 0.254)
			(type default)
		)
		(layer "In6.Cu")
	)
	(gr_line
		(start 171.303188 -9.997948)
		(end 171.303188 -12.461748)
		(stroke
			(width 0.254)
			(type default)
		)
		(layer "In6.Cu")
	)
	(gr_line
		(start 171.303188 -9.897872)
		(end 171.303188 -12.361672)
		(stroke
			(width 0.254)
			(type default)
		)
		(layer "In6.Cu")
	)
	(gr_line
		(start 171.303188 -8.261604)
		(end 170.439588 -8.261604)
		(stroke
			(width 0.254)
			(type default)
		)
		(layer "In6.Cu")
	)
	(gr_line
		(start 171.303188 -8.161528)
		(end 170.439588 -8.161528)
		(stroke
			(width 0.254)
			(type default)
		)
		(layer "In6.Cu")
	)
	(gr_line
		(start 171.303188 -5.797804)
		(end 171.303188 -8.261604)
		(stroke
			(width 0.254)
			(type default)
		)
		(layer "In6.Cu")
	)
	(gr_line
		(start 171.303188 -5.697728)
		(end 171.303188 -8.161528)
		(stroke
			(width 0.254)
			(type default)
		)
		(layer "In6.Cu")
	)
	(gr_line
		(start 171.353988 -12.487148)
		(end 170.414188 -12.487148)
		(stroke
			(width 0.254)
			(type default)
		)
		(layer "In6.Cu")
	)
	(gr_line
		(start 171.353988 -12.387072)
		(end 170.414188 -12.387072)
		(stroke
			(width 0.254)
			(type default)
		)
		(layer "In6.Cu")
	)
	(gr_line
		(start 171.353988 -9.997948)
		(end 171.353988 -12.487148)
		(stroke
			(width 0.254)
			(type default)
		)
		(layer "In6.Cu")
	)
	(gr_line
		(start 171.353988 -9.897872)
		(end 171.353988 -12.387072)
		(stroke
			(width 0.254)
			(type default)
		)
		(layer "In6.Cu")
	)
	(gr_line
		(start 171.353988 -8.287004)
		(end 170.414188 -8.287004)
		(stroke
			(width 0.254)
			(type default)
		)
		(layer "In6.Cu")
	)
	(gr_line
		(start 171.353988 -8.186928)
		(end 170.414188 -8.186928)
		(stroke
			(width 0.254)
			(type default)
		)
		(layer "In6.Cu")
	)
	(gr_line
		(start 171.353988 -5.797804)
		(end 171.353988 -8.287004)
		(stroke
			(width 0.254)
			(type default)
		)
		(layer "In6.Cu")
	)
	(gr_line
		(start 171.353988 -5.697728)
		(end 171.353988 -8.186928)
		(stroke
			(width 0.254)
			(type default)
		)
		(layer "In6.Cu")
	)
	(gr_line
		(start 171.379388 -12.487148)
		(end 170.414188 -12.487148)
		(stroke
			(width 0.2032)
			(type default)
		)
		(layer "In6.Cu")
	)
	(gr_line
		(start 171.379388 -12.387072)
		(end 170.414188 -12.387072)
		(stroke
			(width 0.2032)
			(type default)
		)
		(layer "In6.Cu")
	)
	(gr_line
		(start 171.379388 -9.947148)
		(end 171.379388 -12.487148)
		(stroke
			(width 0.2032)
			(type default)
		)
		(layer "In6.Cu")
	)
	(gr_line
		(start 171.379388 -9.847072)
		(end 171.379388 -12.387072)
		(stroke
			(width 0.2032)
			(type default)
		)
		(layer "In6.Cu")
	)
	(gr_line
		(start 171.379388 -8.287004)
		(end 170.414188 -8.287004)
		(stroke
			(width 0.2032)
			(type default)
		)
		(layer "In6.Cu")
	)
	(gr_line
		(start 171.379388 -8.186928)
		(end 170.414188 -8.186928)
		(stroke
			(width 0.2032)
			(type default)
		)
		(layer "In6.Cu")
	)
	(gr_line
		(start 171.379388 -5.747004)
		(end 171.379388 -8.287004)
		(stroke
			(width 0.2032)
			(type default)
		)
		(layer "In6.Cu")
	)
	(gr_line
		(start 171.379388 -5.646928)
		(end 171.379388 -8.186928)
		(stroke
			(width 0.2032)
			(type default)
		)
		(layer "In6.Cu")
	)
	(gr_line
		(start 171.430188 -12.512548)
		(end 170.363388 -12.512548)
		(stroke
			(width 0.2032)
			(type default)
		)
		(layer "In6.Cu")
	)
	(gr_line
		(start 171.430188 -12.412472)
		(end 170.363388 -12.412472)
		(stroke
			(width 0.2032)
			(type default)
		)
		(layer "In6.Cu")
	)
	(gr_line
		(start 171.430188 -9.947148)
		(end 171.430188 -12.512548)
		(stroke
			(width 0.2032)
			(type default)
		)
		(layer "In6.Cu")
	)
	(gr_line
		(start 171.430188 -9.847072)
		(end 171.430188 -12.412472)
		(stroke
			(width 0.2032)
			(type default)
		)
		(layer "In6.Cu")
	)
	(gr_line
		(start 171.430188 -8.312404)
		(end 170.363388 -8.312404)
		(stroke
			(width 0.2032)
			(type default)
		)
		(layer "In6.Cu")
	)
	(gr_line
		(start 171.430188 -8.212328)
		(end 170.363388 -8.212328)
		(stroke
			(width 0.2032)
			(type default)
		)
		(layer "In6.Cu")
	)
	(gr_line
		(start 171.430188 -5.747004)
		(end 171.430188 -8.312404)
		(stroke
			(width 0.2032)
			(type default)
		)
		(layer "In6.Cu")
	)
	(gr_line
		(start 171.430188 -5.646928)
		(end 171.430188 -8.212328)
		(stroke
			(width 0.2032)
			(type default)
		)
		(layer "In6.Cu")
	)
	(gr_line
		(start 171.455588 -12.512548)
		(end 170.337988 -12.512548)
		(stroke
			(width 0.1016)
			(type default)
		)
		(layer "In6.Cu")
	)
	(gr_line
		(start 171.455588 -12.412472)
		(end 170.337988 -12.412472)
		(stroke
			(width 0.1016)
			(type default)
		)
		(layer "In6.Cu")
	)
	(gr_line
		(start 171.455588 -9.921748)
		(end 171.455588 -12.512548)
		(stroke
			(width 0.1016)
			(type default)
		)
		(layer "In6.Cu")
	)
	(gr_line
		(start 171.455588 -9.821672)
		(end 171.455588 -12.412472)
		(stroke
			(width 0.1016)
			(type default)
		)
		(layer "In6.Cu")
	)
	(gr_line
		(start 171.455588 -8.312404)
		(end 170.337988 -8.312404)
		(stroke
			(width 0.1016)
			(type default)
		)
		(layer "In6.Cu")
	)
	(gr_line
		(start 171.455588 -8.212328)
		(end 170.337988 -8.212328)
		(stroke
			(width 0.1016)
			(type default)
		)
		(layer "In6.Cu")
	)
	(gr_line
		(start 171.455588 -5.721604)
		(end 171.455588 -8.312404)
		(stroke
			(width 0.1016)
			(type default)
		)
		(layer "In6.Cu")
	)
	(gr_line
		(start 171.455588 -5.621528)
		(end 171.455588 -8.212328)
		(stroke
			(width 0.1016)
			(type default)
		)
		(layer "In6.Cu")
	)
	(gr_line
		(start 171.480988 -12.563348)
		(end 171.074588 -12.563348)
		(stroke
			(width 0.1016)
			(type default)
		)
		(layer "In6.Cu")
	)
	(gr_line
		(start 171.480988 -12.563348)
		(end 171.480988 -9.896348)
		(stroke
			(width 0.1016)
			(type default)
		)
		(layer "In6.Cu")
	)
	(gr_line
		(start 171.480988 -12.463272)
		(end 171.074588 -12.463272)
		(stroke
			(width 0.1016)
			(type default)
		)
		(layer "In6.Cu")
	)
	(gr_line
		(start 171.480988 -12.463272)
		(end 171.480988 -9.796272)
		(stroke
			(width 0.1016)
			(type default)
		)
		(layer "In6.Cu")
	)
	(gr_line
		(start 171.480988 -9.896348)
		(end 170.287188 -9.896348)
		(stroke
			(width 0.1016)
			(type default)
		)
		(layer "In6.Cu")
	)
	(gr_line
		(start 171.480988 -9.896348)
		(end 171.480988 -12.563348)
		(stroke
			(width 0.1016)
			(type default)
		)
		(layer "In6.Cu")
	)
	(gr_line
		(start 171.480988 -9.796272)
		(end 170.287188 -9.796272)
		(stroke
			(width 0.1016)
			(type default)
		)
		(layer "In6.Cu")
	)
	(gr_line
		(start 171.480988 -9.796272)
		(end 171.480988 -12.463272)
		(stroke
			(width 0.1016)
			(type default)
		)
		(layer "In6.Cu")
	)
	(gr_line
		(start 171.480988 -8.363204)
		(end 171.074588 -8.363204)
		(stroke
			(width 0.1016)
			(type default)
		)
		(layer "In6.Cu")
	)
	(gr_line
		(start 171.480988 -8.363204)
		(end 171.480988 -5.696204)
		(stroke
			(width 0.1016)
			(type default)
		)
		(layer "In6.Cu")
	)
	(gr_line
		(start 171.480988 -8.263128)
		(end 171.074588 -8.263128)
		(stroke
			(width 0.1016)
			(type default)
		)
		(layer "In6.Cu")
	)
	(gr_line
		(start 171.480988 -8.263128)
		(end 171.480988 -5.596128)
		(stroke
			(width 0.1016)
			(type default)
		)
		(layer "In6.Cu")
	)
	(gr_line
		(start 171.480988 -5.696204)
		(end 170.287188 -5.696204)
		(stroke
			(width 0.1016)
			(type default)
		)
		(layer "In6.Cu")
	)
	(gr_line
		(start 171.480988 -5.696204)
		(end 171.480988 -8.363204)
		(stroke
			(width 0.1016)
			(type default)
		)
		(layer "In6.Cu")
	)
	(gr_line
		(start 171.480988 -5.596128)
		(end 170.287188 -5.596128)
		(stroke
			(width 0.1016)
			(type default)
		)
		(layer "In6.Cu")
	)
	(gr_line
		(start 171.480988 -5.596128)
		(end 171.480988 -8.263128)
		(stroke
			(width 0.1016)
			(type default)
		)
		(layer "In6.Cu")
	)
	(gr_line
		(start 171.720002 -31.98622)
		(end 170.450002 -31.98622)
		(stroke
			(width 0.7874)
			(type default)
		)
		(layer "In6.Cu")
	)
	(gr_line
		(start 172.120052 -23.69566)
		(end 170.850052 -23.69566)
		(stroke
			(width 0.7874)
			(type default)
		)
		(layer "In6.Cu")
	)
	(gr_line
		(start 172.287184 -13.8176)
		(end 173.074584 -13.8176)
		(stroke
			(width 0.1016)
			(type default)
		)
		(layer "In6.Cu")
	)
	(gr_line
		(start 172.287184 -13.7668)
		(end 172.287184 -11.1506)
		(stroke
			(width 0.1016)
			(type default)
		)
		(layer "In6.Cu")
	)
	(gr_line
		(start 172.287184 -11.1506)
		(end 172.287184 -13.8176)
		(stroke
			(width 0.1016)
			(type default)
		)
		(layer "In6.Cu")
	)
	(gr_line
		(start 172.287184 -11.1506)
		(end 173.480984 -11.1506)
		(stroke
			(width 0.1016)
			(type default)
		)
		(layer "In6.Cu")
	)
	(gr_line
		(start 172.287184 -9.617456)
		(end 173.074584 -9.617456)
		(stroke
			(width 0.1016)
			(type default)
		)
		(layer "In6.Cu")
	)
	(gr_line
		(start 172.287184 -9.566656)
		(end 172.287184 -6.950456)
		(stroke
			(width 0.1016)
			(type default)
		)
		(layer "In6.Cu")
	)
	(gr_line
		(start 172.287184 -6.950456)
		(end 172.287184 -9.617456)
		(stroke
			(width 0.1016)
			(type default)
		)
		(layer "In6.Cu")
	)
	(gr_line
		(start 172.287184 -6.950456)
		(end 173.480984 -6.950456)
		(stroke
			(width 0.1016)
			(type default)
		)
		(layer "In6.Cu")
	)
	(gr_line
		(start 172.287184 -5.417312)
		(end 173.074584 -5.417312)
		(stroke
			(width 0.1016)
			(type default)
		)
		(layer "In6.Cu")
	)
	(gr_line
		(start 172.287184 -5.366512)
		(end 172.287184 -2.750312)
		(stroke
			(width 0.1016)
			(type default)
		)
		(layer "In6.Cu")
	)
	(gr_line
		(start 172.287184 -2.750312)
		(end 172.287184 -5.417312)
		(stroke
			(width 0.1016)
			(type default)
		)
		(layer "In6.Cu")
	)
	(gr_line
		(start 172.287184 -2.750312)
		(end 173.480984 -2.750312)
		(stroke
			(width 0.1016)
			(type default)
		)
		(layer "In6.Cu")
	)
	(gr_line
		(start 172.312584 -13.7668)
		(end 172.312584 -11.176)
		(stroke
			(width 0.1016)
			(type default)
		)
		(layer "In6.Cu")
	)
	(gr_line
		(start 172.312584 -11.176)
		(end 173.455584 -11.176)
		(stroke
			(width 0.1016)
			(type default)
		)
		(layer "In6.Cu")
	)
	(gr_line
		(start 172.312584 -9.566656)
		(end 172.312584 -6.975856)
		(stroke
			(width 0.1016)
			(type default)
		)
		(layer "In6.Cu")
	)
	(gr_line
		(start 172.312584 -6.975856)
		(end 173.455584 -6.975856)
		(stroke
			(width 0.1016)
			(type default)
		)
		(layer "In6.Cu")
	)
	(gr_line
		(start 172.312584 -5.366512)
		(end 172.312584 -2.775712)
		(stroke
			(width 0.1016)
			(type default)
		)
		(layer "In6.Cu")
	)
	(gr_line
		(start 172.312584 -2.775712)
		(end 173.455584 -2.775712)
		(stroke
			(width 0.1016)
			(type default)
		)
		(layer "In6.Cu")
	)
	(gr_line
		(start 172.337984 -13.7668)
		(end 172.337984 -11.2014)
		(stroke
			(width 0.1016)
			(type default)
		)
		(layer "In6.Cu")
	)
	(gr_line
		(start 172.337984 -11.2014)
		(end 172.591984 -11.2014)
		(stroke
			(width 0.1016)
			(type default)
		)
		(layer "In6.Cu")
	)
	(gr_line
		(start 172.337984 -9.566656)
		(end 172.337984 -7.001256)
		(stroke
			(width 0.1016)
			(type default)
		)
		(layer "In6.Cu")
	)
	(gr_line
		(start 172.337984 -7.001256)
		(end 172.591984 -7.001256)
		(stroke
			(width 0.1016)
			(type default)
		)
		(layer "In6.Cu")
	)
	(gr_line
		(start 172.337984 -5.366512)
		(end 172.337984 -2.801112)
		(stroke
			(width 0.1016)
			(type default)
		)
		(layer "In6.Cu")
	)
	(gr_line
		(start 172.337984 -2.801112)
		(end 172.591984 -2.801112)
		(stroke
			(width 0.1016)
			(type default)
		)
		(layer "In6.Cu")
	)
	(gr_line
		(start 172.363384 -13.7668)
		(end 172.363384 -11.2014)
		(stroke
			(width 0.2032)
			(type default)
		)
		(layer "In6.Cu")
	)
	(gr_line
		(start 172.363384 -11.2014)
		(end 173.379384 -11.2014)
		(stroke
			(width 0.2032)
			(type default)
		)
		(layer "In6.Cu")
	)
	(gr_line
		(start 172.363384 -9.566656)
		(end 172.363384 -7.001256)
		(stroke
			(width 0.2032)
			(type default)
		)
		(layer "In6.Cu")
	)
	(gr_line
		(start 172.363384 -7.001256)
		(end 173.379384 -7.001256)
		(stroke
			(width 0.2032)
			(type default)
		)
		(layer "In6.Cu")
	)
	(gr_line
		(start 172.363384 -5.366512)
		(end 172.363384 -2.801112)
		(stroke
			(width 0.2032)
			(type default)
		)
		(layer "In6.Cu")
	)
	(gr_line
		(start 172.363384 -2.801112)
		(end 173.379384 -2.801112)
		(stroke
			(width 0.2032)
			(type default)
		)
		(layer "In6.Cu")
	)
	(gr_line
		(start 172.414184 -13.7414)
		(end 172.414184 -11.2522)
		(stroke
			(width 0.2032)
			(type default)
		)
		(layer "In6.Cu")
	)
	(gr_line
		(start 172.414184 -13.7414)
		(end 172.414184 -11.2522)
		(stroke
			(width 0.254)
			(type default)
		)
		(layer "In6.Cu")
	)
	(gr_line
		(start 172.414184 -11.2522)
		(end 172.617384 -11.2522)
		(stroke
			(width 0.2032)
			(type default)
		)
		(layer "In6.Cu")
	)
	(gr_line
		(start 172.414184 -11.2522)
		(end 173.303184 -11.2522)
		(stroke
			(width 0.254)
			(type default)
		)
		(layer "In6.Cu")
	)
	(gr_line
		(start 172.414184 -9.541256)
		(end 172.414184 -7.052056)
		(stroke
			(width 0.2032)
			(type default)
		)
		(layer "In6.Cu")
	)
	(gr_line
		(start 172.414184 -9.541256)
		(end 172.414184 -7.052056)
		(stroke
			(width 0.254)
			(type default)
		)
		(layer "In6.Cu")
	)
	(gr_line
		(start 172.414184 -7.052056)
		(end 172.617384 -7.052056)
		(stroke
			(width 0.2032)
			(type default)
		)
		(layer "In6.Cu")
	)
	(gr_line
		(start 172.414184 -7.052056)
		(end 173.303184 -7.052056)
		(stroke
			(width 0.254)
			(type default)
		)
		(layer "In6.Cu")
	)
	(gr_line
		(start 172.414184 -5.341112)
		(end 172.414184 -2.851912)
		(stroke
			(width 0.2032)
			(type default)
		)
		(layer "In6.Cu")
	)
	(gr_line
		(start 172.414184 -5.341112)
		(end 172.414184 -2.851912)
		(stroke
			(width 0.254)
			(type default)
		)
		(layer "In6.Cu")
	)
	(gr_line
		(start 172.414184 -2.851912)
		(end 172.617384 -2.851912)
		(stroke
			(width 0.2032)
			(type default)
		)
		(layer "In6.Cu")
	)
	(gr_line
		(start 172.414184 -2.851912)
		(end 173.303184 -2.851912)
		(stroke
			(width 0.254)
			(type default)
		)
		(layer "In6.Cu")
	)
	(gr_line
		(start 172.439584 -13.716)
		(end 172.439584 -11.2776)
		(stroke
			(width 0.254)
			(type default)
		)
		(layer "In6.Cu")
	)
	(gr_line
		(start 172.439584 -11.2776)
		(end 173.277784 -11.2776)
		(stroke
			(width 0.254)
			(type default)
		)
		(layer "In6.Cu")
	)
	(gr_line
		(start 172.439584 -9.515856)
		(end 172.439584 -7.077456)
		(stroke
			(width 0.254)
			(type default)
		)
		(layer "In6.Cu")
	)
	(gr_line
		(start 172.439584 -7.077456)
		(end 173.277784 -7.077456)
		(stroke
			(width 0.254)
			(type default)
		)
		(layer "In6.Cu")
	)
	(gr_line
		(start 172.439584 -5.315712)
		(end 172.439584 -2.877312)
		(stroke
			(width 0.254)
			(type default)
		)
		(layer "In6.Cu")
	)
	(gr_line
		(start 172.439584 -2.877312)
		(end 173.277784 -2.877312)
		(stroke
			(width 0.254)
			(type default)
		)
		(layer "In6.Cu")
	)
	(gr_line
		(start 172.464984 -13.6906)
		(end 172.464984 -11.303)
		(stroke
			(width 0.254)
			(type default)
		)
		(layer "In6.Cu")
	)
	(gr_line
		(start 172.464984 -11.303)
		(end 173.252384 -11.303)
		(stroke
			(width 0.254)
			(type default)
		)
		(layer "In6.Cu")
	)
	(gr_line
		(start 172.464984 -9.490456)
		(end 172.464984 -7.102856)
		(stroke
			(width 0.254)
			(type default)
		)
		(layer "In6.Cu")
	)
	(gr_line
		(start 172.464984 -7.102856)
		(end 173.252384 -7.102856)
		(stroke
			(width 0.254)
			(type default)
		)
		(layer "In6.Cu")
	)
	(gr_line
		(start 172.464984 -5.290312)
		(end 172.464984 -2.902712)
		(stroke
			(width 0.254)
			(type default)
		)
		(layer "In6.Cu")
	)
	(gr_line
		(start 172.464984 -2.902712)
		(end 173.252384 -2.902712)
		(stroke
			(width 0.254)
			(type default)
		)
		(layer "In6.Cu")
	)
	(gr_line
		(start 172.490384 -13.6144)
		(end 173.125384 -13.6144)
		(stroke
			(width 0.508)
			(type default)
		)
		(layer "In6.Cu")
	)
	(gr_line
		(start 172.490384 -11.43)
		(end 173.125384 -11.43)
		(stroke
			(width 0.508)
			(type default)
		)
		(layer "In6.Cu")
	)
	(gr_line
		(start 172.490384 -11.3792)
		(end 173.125384 -11.3792)
		(stroke
			(width 0.508)
			(type default)
		)
		(layer "In6.Cu")
	)
	(gr_line
		(start 172.490384 -9.414256)
		(end 173.125384 -9.414256)
		(stroke
			(width 0.508)
			(type default)
		)
		(layer "In6.Cu")
	)
	(gr_line
		(start 172.490384 -7.229856)
		(end 173.125384 -7.229856)
		(stroke
			(width 0.508)
			(type default)
		)
		(layer "In6.Cu")
	)
	(gr_line
		(start 172.490384 -7.179056)
		(end 173.125384 -7.179056)
		(stroke
			(width 0.508)
			(type default)
		)
		(layer "In6.Cu")
	)
	(gr_line
		(start 172.490384 -5.214112)
		(end 173.125384 -5.214112)
		(stroke
			(width 0.508)
			(type default)
		)
		(layer "In6.Cu")
	)
	(gr_line
		(start 172.490384 -3.029712)
		(end 173.125384 -3.029712)
		(stroke
			(width 0.508)
			(type default)
		)
		(layer "In6.Cu")
	)
	(gr_line
		(start 172.490384 -2.978912)
		(end 173.125384 -2.978912)
		(stroke
			(width 0.508)
			(type default)
		)
		(layer "In6.Cu")
	)
	(gr_line
		(start 172.515784 -11.684)
		(end 173.150784 -11.684)
		(stroke
			(width 0.508)
			(type default)
		)
		(layer "In6.Cu")
	)
	(gr_line
		(start 172.515784 -7.483856)
		(end 173.150784 -7.483856)
		(stroke
			(width 0.508)
			(type default)
		)
		(layer "In6.Cu")
	)
	(gr_line
		(start 172.515784 -3.283712)
		(end 173.150784 -3.283712)
		(stroke
			(width 0.508)
			(type default)
		)
		(layer "In6.Cu")
	)
	(gr_line
		(start 172.541184 -13.6398)
		(end 172.541184 -11.3792)
		(stroke
			(width 0.254)
			(type default)
		)
		(layer "In6.Cu")
	)
	(gr_line
		(start 172.541184 -13.4874)
		(end 173.176184 -13.4874)
		(stroke
			(width 0.508)
			(type default)
		)
		(layer "In6.Cu")
	)
	(gr_line
		(start 172.541184 -11.3792)
		(end 173.176184 -11.3792)
		(stroke
			(width 0.254)
			(type default)
		)
		(layer "In6.Cu")
	)
	(gr_line
		(start 172.541184 -9.439656)
		(end 172.541184 -7.179056)
		(stroke
			(width 0.254)
			(type default)
		)
		(layer "In6.Cu")
	)
	(gr_line
		(start 172.541184 -9.287256)
		(end 173.176184 -9.287256)
		(stroke
			(width 0.508)
			(type default)
		)
		(layer "In6.Cu")
	)
	(gr_line
		(start 172.541184 -7.179056)
		(end 173.176184 -7.179056)
		(stroke
			(width 0.254)
			(type default)
		)
		(layer "In6.Cu")
	)
	(gr_line
		(start 172.541184 -5.239512)
		(end 172.541184 -2.978912)
		(stroke
			(width 0.254)
			(type default)
		)
		(layer "In6.Cu")
	)
	(gr_line
		(start 172.541184 -5.087112)
		(end 173.176184 -5.087112)
		(stroke
			(width 0.508)
			(type default)
		)
		(layer "In6.Cu")
	)
	(gr_line
		(start 172.541184 -2.978912)
		(end 173.176184 -2.978912)
		(stroke
			(width 0.254)
			(type default)
		)
		(layer "In6.Cu")
	)
	(gr_line
		(start 172.566584 -13.335)
		(end 173.201584 -13.335)
		(stroke
			(width 0.508)
			(type default)
		)
		(layer "In6.Cu")
	)
	(gr_line
		(start 172.566584 -9.134856)
		(end 173.201584 -9.134856)
		(stroke
			(width 0.508)
			(type default)
		)
		(layer "In6.Cu")
	)
	(gr_line
		(start 172.566584 -4.934712)
		(end 173.201584 -4.934712)
		(stroke
			(width 0.508)
			(type default)
		)
		(layer "In6.Cu")
	)
	(gr_line
		(start 172.591984 -13.6144)
		(end 173.226984 -13.6144)
		(stroke
			(width 0.508)
			(type default)
		)
		(layer "In6.Cu")
	)
	(gr_line
		(start 172.591984 -11.2014)
		(end 173.430184 -11.2014)
		(stroke
			(width 0.2032)
			(type default)
		)
		(layer "In6.Cu")
	)
	(gr_line
		(start 172.591984 -9.414256)
		(end 173.226984 -9.414256)
		(stroke
			(width 0.508)
			(type default)
		)
		(layer "In6.Cu")
	)
	(gr_line
		(start 172.591984 -7.001256)
		(end 173.430184 -7.001256)
		(stroke
			(width 0.2032)
			(type default)
		)
		(layer "In6.Cu")
	)
	(gr_line
		(start 172.591984 -5.214112)
		(end 173.226984 -5.214112)
		(stroke
			(width 0.508)
			(type default)
		)
		(layer "In6.Cu")
	)
	(gr_line
		(start 172.591984 -2.801112)
		(end 173.430184 -2.801112)
		(stroke
			(width 0.2032)
			(type default)
		)
		(layer "In6.Cu")
	)
	(gr_line
		(start 172.617384 -13.6144)
		(end 172.617384 -11.43)
		(stroke
			(width 0.254)
			(type default)
		)
		(layer "In6.Cu")
	)
	(gr_line
		(start 172.617384 -11.43)
		(end 173.099984 -11.43)
		(stroke
			(width 0.254)
			(type default)
		)
		(layer "In6.Cu")
	)
	(gr_line
		(start 172.617384 -11.2522)
		(end 173.353984 -11.2522)
		(stroke
			(width 0.254)
			(type default)
		)
		(layer "In6.Cu")
	)
	(gr_line
		(start 172.617384 -9.414256)
		(end 172.617384 -7.229856)
		(stroke
			(width 0.254)
			(type default)
		)
		(layer "In6.Cu")
	)
	(gr_line
		(start 172.617384 -7.229856)
		(end 173.099984 -7.229856)
		(stroke
			(width 0.254)
			(type default)
		)
		(layer "In6.Cu")
	)
	(gr_line
		(start 172.617384 -7.052056)
		(end 173.353984 -7.052056)
		(stroke
			(width 0.254)
			(type default)
		)
		(layer "In6.Cu")
	)
	(gr_line
		(start 172.617384 -5.214112)
		(end 172.617384 -3.029712)
		(stroke
			(width 0.254)
			(type default)
		)
		(layer "In6.Cu")
	)
	(gr_line
		(start 172.617384 -3.029712)
		(end 173.099984 -3.029712)
		(stroke
			(width 0.254)
			(type default)
		)
		(layer "In6.Cu")
	)
	(gr_line
		(start 172.617384 -2.851912)
		(end 173.353984 -2.851912)
		(stroke
			(width 0.254)
			(type default)
		)
		(layer "In6.Cu")
	)
	(gr_line
		(start 172.635926 -11.36523)
		(end 173.270926 -11.36523)
		(stroke
			(width 0.508)
			(type default)
		)
		(layer "In6.Cu")
	)
	(gr_line
		(start 172.635926 -7.165086)
		(end 173.270926 -7.165086)
		(stroke
			(width 0.508)
			(type default)
		)
		(layer "In6.Cu")
	)
	(gr_line
		(start 172.635926 -2.964942)
		(end 173.270926 -2.964942)
		(stroke
			(width 0.508)
			(type default)
		)
		(layer "In6.Cu")
	)
	(gr_line
		(start 172.642784 -13.6144)
		(end 173.277784 -13.6144)
		(stroke
			(width 0.508)
			(type default)
		)
		(layer "In6.Cu")
	)
	(gr_line
		(start 172.642784 -13.4874)
		(end 172.642784 -11.5062)
		(stroke
			(width 0.762)
			(type default)
		)
		(layer "In6.Cu")
	)
	(gr_line
		(start 172.642784 -11.5062)
		(end 173.277784 -11.5062)
		(stroke
			(width 0.508)
			(type default)
		)
		(layer "In6.Cu")
	)
	(gr_line
		(start 172.642784 -9.414256)
		(end 173.277784 -9.414256)
		(stroke
			(width 0.508)
			(type default)
		)
		(layer "In6.Cu")
	)
	(gr_line
		(start 172.642784 -9.287256)
		(end 172.642784 -7.306056)
		(stroke
			(width 0.762)
			(type default)
		)
		(layer "In6.Cu")
	)
	(gr_line
		(start 172.642784 -7.306056)
		(end 173.277784 -7.306056)
		(stroke
			(width 0.508)
			(type default)
		)
		(layer "In6.Cu")
	)
	(gr_line
		(start 172.642784 -5.214112)
		(end 173.277784 -5.214112)
		(stroke
			(width 0.508)
			(type default)
		)
		(layer "In6.Cu")
	)
	(gr_line
		(start 172.642784 -5.087112)
		(end 172.642784 -3.105912)
		(stroke
			(width 0.762)
			(type default)
		)
		(layer "In6.Cu")
	)
	(gr_line
		(start 172.642784 -3.105912)
		(end 173.277784 -3.105912)
		(stroke
			(width 0.508)
			(type default)
		)
		(layer "In6.Cu")
	)
	(gr_line
		(start 172.693584 -13.5382)
		(end 172.693584 -11.5062)
		(stroke
			(width 0.254)
			(type default)
		)
		(layer "In6.Cu")
	)
	(gr_line
		(start 172.693584 -11.5062)
		(end 173.023784 -11.5062)
		(stroke
			(width 0.254)
			(type default)
		)
		(layer "In6.Cu")
	)
	(gr_line
		(start 172.693584 -9.338056)
		(end 172.693584 -7.306056)
		(stroke
			(width 0.254)
			(type default)
		)
		(layer "In6.Cu")
	)
	(gr_line
		(start 172.693584 -7.306056)
		(end 173.023784 -7.306056)
		(stroke
			(width 0.254)
			(type default)
		)
		(layer "In6.Cu")
	)
	(gr_line
		(start 172.693584 -5.137912)
		(end 172.693584 -3.105912)
		(stroke
			(width 0.254)
			(type default)
		)
		(layer "In6.Cu")
	)
	(gr_line
		(start 172.693584 -3.105912)
		(end 173.023784 -3.105912)
		(stroke
			(width 0.254)
			(type default)
		)
		(layer "In6.Cu")
	)
	(gr_line
		(start 172.795184 -13.462)
		(end 172.795184 -11.6586)
		(stroke
			(width 0.254)
			(type default)
		)
		(layer "In6.Cu")
	)
	(gr_line
		(start 172.795184 -13.462)
		(end 172.795184 -11.4808)
		(stroke
			(width 0.762)
			(type default)
		)
		(layer "In6.Cu")
	)
	(gr_line
		(start 172.795184 -11.6586)
		(end 172.896784 -11.6586)
		(stroke
			(width 0.254)
			(type default)
		)
		(layer "In6.Cu")
	)
	(gr_line
		(start 172.795184 -9.261856)
		(end 172.795184 -7.458456)
		(stroke
			(width 0.254)
			(type default)
		)
		(layer "In6.Cu")
	)
	(gr_line
		(start 172.795184 -9.261856)
		(end 172.795184 -7.280656)
		(stroke
			(width 0.762)
			(type default)
		)
		(layer "In6.Cu")
	)
	(gr_line
		(start 172.795184 -7.458456)
		(end 172.896784 -7.458456)
		(stroke
			(width 0.254)
			(type default)
		)
		(layer "In6.Cu")
	)
	(gr_line
		(start 172.795184 -5.061712)
		(end 172.795184 -3.258312)
		(stroke
			(width 0.254)
			(type default)
		)
		(layer "In6.Cu")
	)
	(gr_line
		(start 172.795184 -5.061712)
		(end 172.795184 -3.080512)
		(stroke
			(width 0.762)
			(type default)
		)
		(layer "In6.Cu")
	)
	(gr_line
		(start 172.795184 -3.258312)
		(end 172.896784 -3.258312)
		(stroke
			(width 0.254)
			(type default)
		)
		(layer "In6.Cu")
	)
	(gr_line
		(start 172.896784 -13.5636)
		(end 172.845984 -13.5636)
		(stroke
			(width 0.254)
			(type default)
		)
		(layer "In6.Cu")
	)
	(gr_line
		(start 172.896784 -11.6586)
		(end 172.896784 -13.5636)
		(stroke
			(width 0.254)
			(type default)
		)
		(layer "In6.Cu")
	)
	(gr_line
		(start 172.896784 -9.363456)
		(end 172.845984 -9.363456)
		(stroke
			(width 0.254)
			(type default)
		)
		(layer "In6.Cu")
	)
	(gr_line
		(start 172.896784 -7.458456)
		(end 172.896784 -9.363456)
		(stroke
			(width 0.254)
			(type default)
		)
		(layer "In6.Cu")
	)
	(gr_line
		(start 172.896784 -5.163312)
		(end 172.845984 -5.163312)
		(stroke
			(width 0.254)
			(type default)
		)
		(layer "In6.Cu")
	)
	(gr_line
		(start 172.896784 -3.258312)
		(end 172.896784 -5.163312)
		(stroke
			(width 0.254)
			(type default)
		)
		(layer "In6.Cu")
	)
	(gr_line
		(start 172.947584 -13.4874)
		(end 172.947584 -11.5062)
		(stroke
			(width 0.762)
			(type default)
		)
		(layer "In6.Cu")
	)
	(gr_line
		(start 172.947584 -9.287256)
		(end 172.947584 -7.306056)
		(stroke
			(width 0.762)
			(type default)
		)
		(layer "In6.Cu")
	)
	(gr_line
		(start 172.947584 -5.087112)
		(end 172.947584 -3.105912)
		(stroke
			(width 0.762)
			(type default)
		)
		(layer "In6.Cu")
	)
	(gr_line
		(start 173.023784 -13.462)
		(end 172.795184 -13.462)
		(stroke
			(width 0.254)
			(type default)
		)
		(layer "In6.Cu")
	)
	(gr_line
		(start 173.023784 -11.5062)
		(end 173.023784 -13.462)
		(stroke
			(width 0.254)
			(type default)
		)
		(layer "In6.Cu")
	)
	(gr_line
		(start 173.023784 -9.261856)
		(end 172.795184 -9.261856)
		(stroke
			(width 0.254)
			(type default)
		)
		(layer "In6.Cu")
	)
	(gr_line
		(start 173.023784 -7.306056)
		(end 173.023784 -9.261856)
		(stroke
			(width 0.254)
			(type default)
		)
		(layer "In6.Cu")
	)
	(gr_line
		(start 173.023784 -5.061712)
		(end 172.795184 -5.061712)
		(stroke
			(width 0.254)
			(type default)
		)
		(layer "In6.Cu")
	)
	(gr_line
		(start 173.023784 -3.105912)
		(end 173.023784 -5.061712)
		(stroke
			(width 0.254)
			(type default)
		)
		(layer "In6.Cu")
	)
	(gr_line
		(start 173.074584 -13.8176)
		(end 173.074584 -13.7668)
		(stroke
			(width 0.1016)
			(type default)
		)
		(layer "In6.Cu")
	)
	(gr_line
		(start 173.074584 -13.8176)
		(end 173.480984 -13.8176)
		(stroke
			(width 0.1016)
			(type default)
		)
		(layer "In6.Cu")
	)
	(gr_line
		(start 173.074584 -13.7668)
		(end 172.312584 -13.7668)
		(stroke
			(width 0.1016)
			(type default)
		)
		(layer "In6.Cu")
	)
	(gr_line
		(start 173.074584 -13.4874)
		(end 173.074584 -11.5062)
		(stroke
			(width 0.762)
			(type default)
		)
		(layer "In6.Cu")
	)
	(gr_line
		(start 173.074584 -9.617456)
		(end 173.074584 -9.566656)
		(stroke
			(width 0.1016)
			(type default)
		)
		(layer "In6.Cu")
	)
	(gr_line
		(start 173.074584 -9.617456)
		(end 173.480984 -9.617456)
		(stroke
			(width 0.1016)
			(type default)
		)
		(layer "In6.Cu")
	)
	(gr_line
		(start 173.074584 -9.566656)
		(end 172.312584 -9.566656)
		(stroke
			(width 0.1016)
			(type default)
		)
		(layer "In6.Cu")
	)
	(gr_line
		(start 173.074584 -9.287256)
		(end 173.074584 -7.306056)
		(stroke
			(width 0.762)
			(type default)
		)
		(layer "In6.Cu")
	)
	(gr_line
		(start 173.074584 -5.417312)
		(end 173.074584 -5.366512)
		(stroke
			(width 0.1016)
			(type default)
		)
		(layer "In6.Cu")
	)
	(gr_line
		(start 173.074584 -5.417312)
		(end 173.480984 -5.417312)
		(stroke
			(width 0.1016)
			(type default)
		)
		(layer "In6.Cu")
	)
	(gr_line
		(start 173.074584 -5.366512)
		(end 172.312584 -5.366512)
		(stroke
			(width 0.1016)
			(type default)
		)
		(layer "In6.Cu")
	)
	(gr_line
		(start 173.074584 -5.087112)
		(end 173.074584 -3.105912)
		(stroke
			(width 0.762)
			(type default)
		)
		(layer "In6.Cu")
	)
	(gr_line
		(start 173.099984 -13.5382)
		(end 172.693584 -13.5382)
		(stroke
			(width 0.254)
			(type default)
		)
		(layer "In6.Cu")
	)
	(gr_line
		(start 173.099984 -11.43)
		(end 173.099984 -13.5382)
		(stroke
			(width 0.254)
			(type default)
		)
		(layer "In6.Cu")
	)
	(gr_line
		(start 173.099984 -9.338056)
		(end 172.693584 -9.338056)
		(stroke
			(width 0.254)
			(type default)
		)
		(layer "In6.Cu")
	)
	(gr_line
		(start 173.099984 -7.229856)
		(end 173.099984 -9.338056)
		(stroke
			(width 0.254)
			(type default)
		)
		(layer "In6.Cu")
	)
	(gr_line
		(start 173.099984 -5.137912)
		(end 172.693584 -5.137912)
		(stroke
			(width 0.254)
			(type default)
		)
		(layer "In6.Cu")
	)
	(gr_line
		(start 173.099984 -3.029712)
		(end 173.099984 -5.137912)
		(stroke
			(width 0.254)
			(type default)
		)
		(layer "In6.Cu")
	)
	(gr_line
		(start 173.150784 -13.4874)
		(end 173.150784 -11.5062)
		(stroke
			(width 0.762)
			(type default)
		)
		(layer "In6.Cu")
	)
	(gr_line
		(start 173.150784 -9.287256)
		(end 173.150784 -7.306056)
		(stroke
			(width 0.762)
			(type default)
		)
		(layer "In6.Cu")
	)
	(gr_line
		(start 173.150784 -5.087112)
		(end 173.150784 -3.105912)
		(stroke
			(width 0.762)
			(type default)
		)
		(layer "In6.Cu")
	)
	(gr_line
		(start 173.176184 -13.6144)
		(end 172.617384 -13.6144)
		(stroke
			(width 0.254)
			(type default)
		)
		(layer "In6.Cu")
	)
	(gr_line
		(start 173.176184 -11.3792)
		(end 173.176184 -13.6144)
		(stroke
			(width 0.254)
			(type default)
		)
		(layer "In6.Cu")
	)
	(gr_line
		(start 173.176184 -9.414256)
		(end 172.617384 -9.414256)
		(stroke
			(width 0.254)
			(type default)
		)
		(layer "In6.Cu")
	)
	(gr_line
		(start 173.176184 -7.179056)
		(end 173.176184 -9.414256)
		(stroke
			(width 0.254)
			(type default)
		)
		(layer "In6.Cu")
	)
	(gr_line
		(start 173.176184 -5.214112)
		(end 172.617384 -5.214112)
		(stroke
			(width 0.254)
			(type default)
		)
		(layer "In6.Cu")
	)
	(gr_line
		(start 173.176184 -2.978912)
		(end 173.176184 -5.214112)
		(stroke
			(width 0.254)
			(type default)
		)
		(layer "In6.Cu")
	)
	(gr_line
		(start 173.252384 -13.6398)
		(end 172.541184 -13.6398)
		(stroke
			(width 0.254)
			(type default)
		)
		(layer "In6.Cu")
	)
	(gr_line
		(start 173.252384 -11.303)
		(end 173.252384 -13.6398)
		(stroke
			(width 0.254)
			(type default)
		)
		(layer "In6.Cu")
	)
	(gr_line
		(start 173.252384 -9.439656)
		(end 172.541184 -9.439656)
		(stroke
			(width 0.254)
			(type default)
		)
		(layer "In6.Cu")
	)
	(gr_line
		(start 173.252384 -7.102856)
		(end 173.252384 -9.439656)
		(stroke
			(width 0.254)
			(type default)
		)
		(layer "In6.Cu")
	)
	(gr_line
		(start 173.252384 -5.239512)
		(end 172.541184 -5.239512)
		(stroke
			(width 0.254)
			(type default)
		)
		(layer "In6.Cu")
	)
	(gr_line
		(start 173.252384 -2.902712)
		(end 173.252384 -5.239512)
		(stroke
			(width 0.254)
			(type default)
		)
		(layer "In6.Cu")
	)
	(gr_line
		(start 173.277784 -13.7668)
		(end 172.287184 -13.7668)
		(stroke
			(width 0.1016)
			(type default)
		)
		(layer "In6.Cu")
	)
	(gr_line
		(start 173.277784 -13.6906)
		(end 172.464984 -13.6906)
		(stroke
			(width 0.254)
			(type default)
		)
		(layer "In6.Cu")
	)
	(gr_line
		(start 173.277784 -11.2776)
		(end 173.277784 -13.6906)
		(stroke
			(width 0.254)
			(type default)
		)
		(layer "In6.Cu")
	)
	(gr_line
		(start 173.277784 -9.566656)
		(end 172.287184 -9.566656)
		(stroke
			(width 0.1016)
			(type default)
		)
		(layer "In6.Cu")
	)
	(gr_line
		(start 173.277784 -9.490456)
		(end 172.464984 -9.490456)
		(stroke
			(width 0.254)
			(type default)
		)
		(layer "In6.Cu")
	)
	(gr_line
		(start 173.277784 -7.077456)
		(end 173.277784 -9.490456)
		(stroke
			(width 0.254)
			(type default)
		)
		(layer "In6.Cu")
	)
	(gr_line
		(start 173.277784 -5.366512)
		(end 172.287184 -5.366512)
		(stroke
			(width 0.1016)
			(type default)
		)
		(layer "In6.Cu")
	)
	(gr_line
		(start 173.277784 -5.290312)
		(end 172.464984 -5.290312)
		(stroke
			(width 0.254)
			(type default)
		)
		(layer "In6.Cu")
	)
	(gr_line
		(start 173.277784 -2.877312)
		(end 173.277784 -5.290312)
		(stroke
			(width 0.254)
			(type default)
		)
		(layer "In6.Cu")
	)
	(gr_line
		(start 173.303184 -13.716)
		(end 172.439584 -13.716)
		(stroke
			(width 0.254)
			(type default)
		)
		(layer "In6.Cu")
	)
	(gr_line
		(start 173.303184 -11.2522)
		(end 173.303184 -13.716)
		(stroke
			(width 0.254)
			(type default)
		)
		(layer "In6.Cu")
	)
	(gr_line
		(start 173.303184 -9.515856)
		(end 172.439584 -9.515856)
		(stroke
			(width 0.254)
			(type default)
		)
		(layer "In6.Cu")
	)
	(gr_line
		(start 173.303184 -7.052056)
		(end 173.303184 -9.515856)
		(stroke
			(width 0.254)
			(type default)
		)
		(layer "In6.Cu")
	)
	(gr_line
		(start 173.303184 -5.315712)
		(end 172.439584 -5.315712)
		(stroke
			(width 0.254)
			(type default)
		)
		(layer "In6.Cu")
	)
	(gr_line
		(start 173.303184 -2.851912)
		(end 173.303184 -5.315712)
		(stroke
			(width 0.254)
			(type default)
		)
		(layer "In6.Cu")
	)
	(gr_line
		(start 173.353984 -13.7414)
		(end 172.414184 -13.7414)
		(stroke
			(width 0.254)
			(type default)
		)
		(layer "In6.Cu")
	)
	(gr_line
		(start 173.353984 -11.2522)
		(end 173.353984 -13.7414)
		(stroke
			(width 0.254)
			(type default)
		)
		(layer "In6.Cu")
	)
	(gr_line
		(start 173.353984 -9.541256)
		(end 172.414184 -9.541256)
		(stroke
			(width 0.254)
			(type default)
		)
		(layer "In6.Cu")
	)
	(gr_line
		(start 173.353984 -7.052056)
		(end 173.353984 -9.541256)
		(stroke
			(width 0.254)
			(type default)
		)
		(layer "In6.Cu")
	)
	(gr_line
		(start 173.353984 -5.341112)
		(end 172.414184 -5.341112)
		(stroke
			(width 0.254)
			(type default)
		)
		(layer "In6.Cu")
	)
	(gr_line
		(start 173.353984 -2.851912)
		(end 173.353984 -5.341112)
		(stroke
			(width 0.254)
			(type default)
		)
		(layer "In6.Cu")
	)
	(gr_line
		(start 173.379384 -13.7414)
		(end 172.414184 -13.7414)
		(stroke
			(width 0.2032)
			(type default)
		)
		(layer "In6.Cu")
	)
	(gr_line
		(start 173.379384 -11.2014)
		(end 173.379384 -13.7414)
		(stroke
			(width 0.2032)
			(type default)
		)
		(layer "In6.Cu")
	)
	(gr_line
		(start 173.379384 -9.541256)
		(end 172.414184 -9.541256)
		(stroke
			(width 0.2032)
			(type default)
		)
		(layer "In6.Cu")
	)
	(gr_line
		(start 173.379384 -7.001256)
		(end 173.379384 -9.541256)
		(stroke
			(width 0.2032)
			(type default)
		)
		(layer "In6.Cu")
	)
	(gr_line
		(start 173.379384 -5.341112)
		(end 172.414184 -5.341112)
		(stroke
			(width 0.2032)
			(type default)
		)
		(layer "In6.Cu")
	)
	(gr_line
		(start 173.379384 -2.801112)
		(end 173.379384 -5.341112)
		(stroke
			(width 0.2032)
			(type default)
		)
		(layer "In6.Cu")
	)
	(gr_line
		(start 173.430184 -13.7668)
		(end 172.363384 -13.7668)
		(stroke
			(width 0.2032)
			(type default)
		)
		(layer "In6.Cu")
	)
	(gr_line
		(start 173.430184 -11.2014)
		(end 173.430184 -13.7668)
		(stroke
			(width 0.2032)
			(type default)
		)
		(layer "In6.Cu")
	)
	(gr_line
		(start 173.430184 -9.566656)
		(end 172.363384 -9.566656)
		(stroke
			(width 0.2032)
			(type default)
		)
		(layer "In6.Cu")
	)
	(gr_line
		(start 173.430184 -7.001256)
		(end 173.430184 -9.566656)
		(stroke
			(width 0.2032)
			(type default)
		)
		(layer "In6.Cu")
	)
	(gr_line
		(start 173.430184 -5.366512)
		(end 172.363384 -5.366512)
		(stroke
			(width 0.2032)
			(type default)
		)
		(layer "In6.Cu")
	)
	(gr_line
		(start 173.430184 -2.801112)
		(end 173.430184 -5.366512)
		(stroke
			(width 0.2032)
			(type default)
		)
		(layer "In6.Cu")
	)
	(gr_line
		(start 173.455584 -13.7668)
		(end 172.337984 -13.7668)
		(stroke
			(width 0.1016)
			(type default)
		)
		(layer "In6.Cu")
	)
	(gr_line
		(start 173.455584 -11.176)
		(end 173.455584 -13.7668)
		(stroke
			(width 0.1016)
			(type default)
		)
		(layer "In6.Cu")
	)
	(gr_line
		(start 173.455584 -9.566656)
		(end 172.337984 -9.566656)
		(stroke
			(width 0.1016)
			(type default)
		)
		(layer "In6.Cu")
	)
	(gr_line
		(start 173.455584 -6.975856)
		(end 173.455584 -9.566656)
		(stroke
			(width 0.1016)
			(type default)
		)
		(layer "In6.Cu")
	)
	(gr_line
		(start 173.455584 -5.366512)
		(end 172.337984 -5.366512)
		(stroke
			(width 0.1016)
			(type default)
		)
		(layer "In6.Cu")
	)
	(gr_line
		(start 173.455584 -2.775712)
		(end 173.455584 -5.366512)
		(stroke
			(width 0.1016)
			(type default)
		)
		(layer "In6.Cu")
	)
	(gr_line
		(start 173.480984 -13.8176)
		(end 173.074584 -13.8176)
		(stroke
			(width 0.1016)
			(type default)
		)
		(layer "In6.Cu")
	)
	(gr_line
		(start 173.480984 -13.8176)
		(end 173.480984 -11.1506)
		(stroke
			(width 0.1016)
			(type default)
		)
		(layer "In6.Cu")
	)
	(gr_line
		(start 173.480984 -11.1506)
		(end 172.287184 -11.1506)
		(stroke
			(width 0.1016)
			(type default)
		)
		(layer "In6.Cu")
	)
	(gr_line
		(start 173.480984 -11.1506)
		(end 173.480984 -13.8176)
		(stroke
			(width 0.1016)
			(type default)
		)
		(layer "In6.Cu")
	)
	(gr_line
		(start 173.480984 -9.617456)
		(end 173.074584 -9.617456)
		(stroke
			(width 0.1016)
			(type default)
		)
		(layer "In6.Cu")
	)
	(gr_line
		(start 173.480984 -9.617456)
		(end 173.480984 -6.950456)
		(stroke
			(width 0.1016)
			(type default)
		)
		(layer "In6.Cu")
	)
	(gr_line
		(start 173.480984 -6.950456)
		(end 172.287184 -6.950456)
		(stroke
			(width 0.1016)
			(type default)
		)
		(layer "In6.Cu")
	)
	(gr_line
		(start 173.480984 -6.950456)
		(end 173.480984 -9.617456)
		(stroke
			(width 0.1016)
			(type default)
		)
		(layer "In6.Cu")
	)
	(gr_line
		(start 173.480984 -5.417312)
		(end 173.074584 -5.417312)
		(stroke
			(width 0.1016)
			(type default)
		)
		(layer "In6.Cu")
	)
	(gr_line
		(start 173.480984 -5.417312)
		(end 173.480984 -2.750312)
		(stroke
			(width 0.1016)
			(type default)
		)
		(layer "In6.Cu")
	)
	(gr_line
		(start 173.480984 -2.750312)
		(end 172.287184 -2.750312)
		(stroke
			(width 0.1016)
			(type default)
		)
		(layer "In6.Cu")
	)
	(gr_line
		(start 173.480984 -2.750312)
		(end 173.480984 -5.417312)
		(stroke
			(width 0.1016)
			(type default)
		)
		(layer "In6.Cu")
	)
	(gr_line
		(start 174.145448 -32.9184)
		(end 172.875448 -32.9184)
		(stroke
			(width 0.7874)
			(type default)
		)
		(layer "In6.Cu")
	)
	(gr_line
		(start 174.28718 -12.563348)
		(end 175.07458 -12.563348)
		(stroke
			(width 0.1016)
			(type default)
		)
		(layer "In6.Cu")
	)
	(gr_line
		(start 174.28718 -12.512548)
		(end 174.28718 -9.896348)
		(stroke
			(width 0.1016)
			(type default)
		)
		(layer "In6.Cu")
	)
	(gr_line
		(start 174.28718 -12.463272)
		(end 175.07458 -12.463272)
		(stroke
			(width 0.1016)
			(type default)
		)
		(layer "In6.Cu")
	)
	(gr_line
		(start 174.28718 -12.412472)
		(end 174.28718 -9.796272)
		(stroke
			(width 0.1016)
			(type default)
		)
		(layer "In6.Cu")
	)
	(gr_line
		(start 174.28718 -9.896348)
		(end 174.28718 -12.563348)
		(stroke
			(width 0.1016)
			(type default)
		)
		(layer "In6.Cu")
	)
	(gr_line
		(start 174.28718 -9.896348)
		(end 175.48098 -9.896348)
		(stroke
			(width 0.1016)
			(type default)
		)
		(layer "In6.Cu")
	)
	(gr_line
		(start 174.28718 -9.796272)
		(end 174.28718 -12.463272)
		(stroke
			(width 0.1016)
			(type default)
		)
		(layer "In6.Cu")
	)
	(gr_line
		(start 174.28718 -9.796272)
		(end 175.48098 -9.796272)
		(stroke
			(width 0.1016)
			(type default)
		)
		(layer "In6.Cu")
	)
	(gr_line
		(start 174.28718 -8.363204)
		(end 175.07458 -8.363204)
		(stroke
			(width 0.1016)
			(type default)
		)
		(layer "In6.Cu")
	)
	(gr_line
		(start 174.28718 -8.312404)
		(end 174.28718 -5.696204)
		(stroke
			(width 0.1016)
			(type default)
		)
		(layer "In6.Cu")
	)
	(gr_line
		(start 174.28718 -8.263128)
		(end 175.07458 -8.263128)
		(stroke
			(width 0.1016)
			(type default)
		)
		(layer "In6.Cu")
	)
	(gr_line
		(start 174.28718 -8.212328)
		(end 174.28718 -5.596128)
		(stroke
			(width 0.1016)
			(type default)
		)
		(layer "In6.Cu")
	)
	(gr_line
		(start 174.28718 -5.696204)
		(end 174.28718 -8.363204)
		(stroke
			(width 0.1016)
			(type default)
		)
		(layer "In6.Cu")
	)
	(gr_line
		(start 174.28718 -5.696204)
		(end 175.48098 -5.696204)
		(stroke
			(width 0.1016)
			(type default)
		)
		(layer "In6.Cu")
	)
	(gr_line
		(start 174.28718 -5.596128)
		(end 174.28718 -8.263128)
		(stroke
			(width 0.1016)
			(type default)
		)
		(layer "In6.Cu")
	)
	(gr_line
		(start 174.28718 -5.596128)
		(end 175.48098 -5.596128)
		(stroke
			(width 0.1016)
			(type default)
		)
		(layer "In6.Cu")
	)
	(gr_line
		(start 174.28718 -4.16306)
		(end 175.07458 -4.16306)
		(stroke
			(width 0.1016)
			(type default)
		)
		(layer "In6.Cu")
	)
	(gr_line
		(start 174.28718 -4.11226)
		(end 174.28718 -1.49606)
		(stroke
			(width 0.1016)
			(type default)
		)
		(layer "In6.Cu")
	)
	(gr_line
		(start 174.28718 -4.062984)
		(end 175.07458 -4.062984)
		(stroke
			(width 0.1016)
			(type default)
		)
		(layer "In6.Cu")
	)
	(gr_line
		(start 174.28718 -4.012184)
		(end 174.28718 -1.395984)
		(stroke
			(width 0.1016)
			(type default)
		)
		(layer "In6.Cu")
	)
	(gr_line
		(start 174.28718 -1.49606)
		(end 174.28718 -4.16306)
		(stroke
			(width 0.1016)
			(type default)
		)
		(layer "In6.Cu")
	)
	(gr_line
		(start 174.28718 -1.49606)
		(end 175.48098 -1.49606)
		(stroke
			(width 0.1016)
			(type default)
		)
		(layer "In6.Cu")
	)
	(gr_line
		(start 174.28718 -1.395984)
		(end 174.28718 -4.062984)
		(stroke
			(width 0.1016)
			(type default)
		)
		(layer "In6.Cu")
	)
	(gr_line
		(start 174.28718 -1.395984)
		(end 175.48098 -1.395984)
		(stroke
			(width 0.1016)
			(type default)
		)
		(layer "In6.Cu")
	)
	(gr_line
		(start 174.31258 -12.512548)
		(end 174.31258 -9.921748)
		(stroke
			(width 0.1016)
			(type default)
		)
		(layer "In6.Cu")
	)
	(gr_line
		(start 174.31258 -12.412472)
		(end 174.31258 -9.821672)
		(stroke
			(width 0.1016)
			(type default)
		)
		(layer "In6.Cu")
	)
	(gr_line
		(start 174.31258 -9.921748)
		(end 175.45558 -9.921748)
		(stroke
			(width 0.1016)
			(type default)
		)
		(layer "In6.Cu")
	)
	(gr_line
		(start 174.31258 -9.821672)
		(end 175.45558 -9.821672)
		(stroke
			(width 0.1016)
			(type default)
		)
		(layer "In6.Cu")
	)
	(gr_line
		(start 174.31258 -8.312404)
		(end 174.31258 -5.721604)
		(stroke
			(width 0.1016)
			(type default)
		)
		(layer "In6.Cu")
	)
	(gr_line
		(start 174.31258 -8.212328)
		(end 174.31258 -5.621528)
		(stroke
			(width 0.1016)
			(type default)
		)
		(layer "In6.Cu")
	)
	(gr_line
		(start 174.31258 -5.721604)
		(end 175.45558 -5.721604)
		(stroke
			(width 0.1016)
			(type default)
		)
		(layer "In6.Cu")
	)
	(gr_line
		(start 174.31258 -5.621528)
		(end 175.45558 -5.621528)
		(stroke
			(width 0.1016)
			(type default)
		)
		(layer "In6.Cu")
	)
	(gr_line
		(start 174.31258 -4.11226)
		(end 174.31258 -1.52146)
		(stroke
			(width 0.1016)
			(type default)
		)
		(layer "In6.Cu")
	)
	(gr_line
		(start 174.31258 -4.012184)
		(end 174.31258 -1.421384)
		(stroke
			(width 0.1016)
			(type default)
		)
		(layer "In6.Cu")
	)
	(gr_line
		(start 174.31258 -1.52146)
		(end 175.45558 -1.52146)
		(stroke
			(width 0.1016)
			(type default)
		)
		(layer "In6.Cu")
	)
	(gr_line
		(start 174.31258 -1.421384)
		(end 175.45558 -1.421384)
		(stroke
			(width 0.1016)
			(type default)
		)
		(layer "In6.Cu")
	)
	(gr_line
		(start 174.33798 -12.512548)
		(end 174.33798 -9.947148)
		(stroke
			(width 0.1016)
			(type default)
		)
		(layer "In6.Cu")
	)
	(gr_line
		(start 174.33798 -12.412472)
		(end 174.33798 -9.847072)
		(stroke
			(width 0.1016)
			(type default)
		)
		(layer "In6.Cu")
	)
	(gr_line
		(start 174.33798 -9.947148)
		(end 174.59198 -9.947148)
		(stroke
			(width 0.1016)
			(type default)
		)
		(layer "In6.Cu")
	)
	(gr_line
		(start 174.33798 -9.847072)
		(end 174.59198 -9.847072)
		(stroke
			(width 0.1016)
			(type default)
		)
		(layer "In6.Cu")
	)
	(gr_line
		(start 174.33798 -8.312404)
		(end 174.33798 -5.747004)
		(stroke
			(width 0.1016)
			(type default)
		)
		(layer "In6.Cu")
	)
	(gr_line
		(start 174.33798 -8.212328)
		(end 174.33798 -5.646928)
		(stroke
			(width 0.1016)
			(type default)
		)
		(layer "In6.Cu")
	)
	(gr_line
		(start 174.33798 -5.747004)
		(end 174.59198 -5.747004)
		(stroke
			(width 0.1016)
			(type default)
		)
		(layer "In6.Cu")
	)
	(gr_line
		(start 174.33798 -5.646928)
		(end 174.59198 -5.646928)
		(stroke
			(width 0.1016)
			(type default)
		)
		(layer "In6.Cu")
	)
	(gr_line
		(start 174.33798 -4.11226)
		(end 174.33798 -1.54686)
		(stroke
			(width 0.1016)
			(type default)
		)
		(layer "In6.Cu")
	)
	(gr_line
		(start 174.33798 -4.012184)
		(end 174.33798 -1.446784)
		(stroke
			(width 0.1016)
			(type default)
		)
		(layer "In6.Cu")
	)
	(gr_line
		(start 174.33798 -1.54686)
		(end 174.59198 -1.54686)
		(stroke
			(width 0.1016)
			(type default)
		)
		(layer "In6.Cu")
	)
	(gr_line
		(start 174.33798 -1.446784)
		(end 174.59198 -1.446784)
		(stroke
			(width 0.1016)
			(type default)
		)
		(layer "In6.Cu")
	)
	(gr_line
		(start 174.36338 -12.512548)
		(end 174.36338 -9.947148)
		(stroke
			(width 0.2032)
			(type default)
		)
		(layer "In6.Cu")
	)
	(gr_line
		(start 174.36338 -12.412472)
		(end 174.36338 -9.847072)
		(stroke
			(width 0.2032)
			(type default)
		)
		(layer "In6.Cu")
	)
	(gr_line
		(start 174.36338 -9.947148)
		(end 175.37938 -9.947148)
		(stroke
			(width 0.2032)
			(type default)
		)
		(layer "In6.Cu")
	)
	(gr_line
		(start 174.36338 -9.847072)
		(end 175.37938 -9.847072)
		(stroke
			(width 0.2032)
			(type default)
		)
		(layer "In6.Cu")
	)
	(gr_line
		(start 174.36338 -8.312404)
		(end 174.36338 -5.747004)
		(stroke
			(width 0.2032)
			(type default)
		)
		(layer "In6.Cu")
	)
	(gr_line
		(start 174.36338 -8.212328)
		(end 174.36338 -5.646928)
		(stroke
			(width 0.2032)
			(type default)
		)
		(layer "In6.Cu")
	)
	(gr_line
		(start 174.36338 -5.747004)
		(end 175.37938 -5.747004)
		(stroke
			(width 0.2032)
			(type default)
		)
		(layer "In6.Cu")
	)
	(gr_line
		(start 174.36338 -5.646928)
		(end 175.37938 -5.646928)
		(stroke
			(width 0.2032)
			(type default)
		)
		(layer "In6.Cu")
	)
	(gr_line
		(start 174.36338 -4.11226)
		(end 174.36338 -1.54686)
		(stroke
			(width 0.2032)
			(type default)
		)
		(layer "In6.Cu")
	)
	(gr_line
		(start 174.36338 -4.012184)
		(end 174.36338 -1.446784)
		(stroke
			(width 0.2032)
			(type default)
		)
		(layer "In6.Cu")
	)
	(gr_line
		(start 174.36338 -1.54686)
		(end 175.37938 -1.54686)
		(stroke
			(width 0.2032)
			(type default)
		)
		(layer "In6.Cu")
	)
	(gr_line
		(start 174.36338 -1.446784)
		(end 175.37938 -1.446784)
		(stroke
			(width 0.2032)
			(type default)
		)
		(layer "In6.Cu")
	)
	(gr_line
		(start 174.41418 -12.487148)
		(end 174.41418 -9.997948)
		(stroke
			(width 0.2032)
			(type default)
		)
		(layer "In6.Cu")
	)
	(gr_line
		(start 174.41418 -12.487148)
		(end 174.41418 -9.997948)
		(stroke
			(width 0.254)
			(type default)
		)
		(layer "In6.Cu")
	)
	(gr_line
		(start 174.41418 -12.387072)
		(end 174.41418 -9.897872)
		(stroke
			(width 0.2032)
			(type default)
		)
		(layer "In6.Cu")
	)
	(gr_line
		(start 174.41418 -12.387072)
		(end 174.41418 -9.897872)
		(stroke
			(width 0.254)
			(type default)
		)
		(layer "In6.Cu")
	)
	(gr_line
		(start 174.41418 -9.997948)
		(end 174.61738 -9.997948)
		(stroke
			(width 0.2032)
			(type default)
		)
		(layer "In6.Cu")
	)
	(gr_line
		(start 174.41418 -9.997948)
		(end 175.30318 -9.997948)
		(stroke
			(width 0.254)
			(type default)
		)
		(layer "In6.Cu")
	)
	(gr_line
		(start 174.41418 -9.897872)
		(end 174.61738 -9.897872)
		(stroke
			(width 0.2032)
			(type default)
		)
		(layer "In6.Cu")
	)
	(gr_line
		(start 174.41418 -9.897872)
		(end 175.30318 -9.897872)
		(stroke
			(width 0.254)
			(type default)
		)
		(layer "In6.Cu")
	)
	(gr_line
		(start 174.41418 -8.287004)
		(end 174.41418 -5.797804)
		(stroke
			(width 0.2032)
			(type default)
		)
		(layer "In6.Cu")
	)
	(gr_line
		(start 174.41418 -8.287004)
		(end 174.41418 -5.797804)
		(stroke
			(width 0.254)
			(type default)
		)
		(layer "In6.Cu")
	)
	(gr_line
		(start 174.41418 -8.186928)
		(end 174.41418 -5.697728)
		(stroke
			(width 0.2032)
			(type default)
		)
		(layer "In6.Cu")
	)
	(gr_line
		(start 174.41418 -8.186928)
		(end 174.41418 -5.697728)
		(stroke
			(width 0.254)
			(type default)
		)
		(layer "In6.Cu")
	)
	(gr_line
		(start 174.41418 -5.797804)
		(end 174.61738 -5.797804)
		(stroke
			(width 0.2032)
			(type default)
		)
		(layer "In6.Cu")
	)
	(gr_line
		(start 174.41418 -5.797804)
		(end 175.30318 -5.797804)
		(stroke
			(width 0.254)
			(type default)
		)
		(layer "In6.Cu")
	)
	(gr_line
		(start 174.41418 -5.697728)
		(end 174.61738 -5.697728)
		(stroke
			(width 0.2032)
			(type default)
		)
		(layer "In6.Cu")
	)
	(gr_line
		(start 174.41418 -5.697728)
		(end 175.30318 -5.697728)
		(stroke
			(width 0.254)
			(type default)
		)
		(layer "In6.Cu")
	)
	(gr_line
		(start 174.41418 -4.08686)
		(end 174.41418 -1.59766)
		(stroke
			(width 0.2032)
			(type default)
		)
		(layer "In6.Cu")
	)
	(gr_line
		(start 174.41418 -4.08686)
		(end 174.41418 -1.59766)
		(stroke
			(width 0.254)
			(type default)
		)
		(layer "In6.Cu")
	)
	(gr_line
		(start 174.41418 -3.986784)
		(end 174.41418 -1.497584)
		(stroke
			(width 0.2032)
			(type default)
		)
		(layer "In6.Cu")
	)
	(gr_line
		(start 174.41418 -3.986784)
		(end 174.41418 -1.497584)
		(stroke
			(width 0.254)
			(type default)
		)
		(layer "In6.Cu")
	)
	(gr_line
		(start 174.41418 -1.59766)
		(end 174.61738 -1.59766)
		(stroke
			(width 0.2032)
			(type default)
		)
		(layer "In6.Cu")
	)
	(gr_line
		(start 174.41418 -1.59766)
		(end 175.30318 -1.59766)
		(stroke
			(width 0.254)
			(type default)
		)
		(layer "In6.Cu")
	)
	(gr_line
		(start 174.41418 -1.497584)
		(end 174.61738 -1.497584)
		(stroke
			(width 0.2032)
			(type default)
		)
		(layer "In6.Cu")
	)
	(gr_line
		(start 174.41418 -1.497584)
		(end 175.30318 -1.497584)
		(stroke
			(width 0.254)
			(type default)
		)
		(layer "In6.Cu")
	)
	(gr_line
		(start 174.43958 -12.461748)
		(end 174.43958 -10.023348)
		(stroke
			(width 0.254)
			(type default)
		)
		(layer "In6.Cu")
	)
	(gr_line
		(start 174.43958 -12.361672)
		(end 174.43958 -9.923272)
		(stroke
			(width 0.254)
			(type default)
		)
		(layer "In6.Cu")
	)
	(gr_line
		(start 174.43958 -10.023348)
		(end 175.27778 -10.023348)
		(stroke
			(width 0.254)
			(type default)
		)
		(layer "In6.Cu")
	)
	(gr_line
		(start 174.43958 -9.923272)
		(end 175.27778 -9.923272)
		(stroke
			(width 0.254)
			(type default)
		)
		(layer "In6.Cu")
	)
	(gr_line
		(start 174.43958 -8.261604)
		(end 174.43958 -5.823204)
		(stroke
			(width 0.254)
			(type default)
		)
		(layer "In6.Cu")
	)
	(gr_line
		(start 174.43958 -8.161528)
		(end 174.43958 -5.723128)
		(stroke
			(width 0.254)
			(type default)
		)
		(layer "In6.Cu")
	)
	(gr_line
		(start 174.43958 -5.823204)
		(end 175.27778 -5.823204)
		(stroke
			(width 0.254)
			(type default)
		)
		(layer "In6.Cu")
	)
	(gr_line
		(start 174.43958 -5.723128)
		(end 175.27778 -5.723128)
		(stroke
			(width 0.254)
			(type default)
		)
		(layer "In6.Cu")
	)
	(gr_line
		(start 174.43958 -4.06146)
		(end 174.43958 -1.62306)
		(stroke
			(width 0.254)
			(type default)
		)
		(layer "In6.Cu")
	)
	(gr_line
		(start 174.43958 -3.961384)
		(end 174.43958 -1.522984)
		(stroke
			(width 0.254)
			(type default)
		)
		(layer "In6.Cu")
	)
	(gr_line
		(start 174.43958 -1.62306)
		(end 175.27778 -1.62306)
		(stroke
			(width 0.254)
			(type default)
		)
		(layer "In6.Cu")
	)
	(gr_line
		(start 174.43958 -1.522984)
		(end 175.27778 -1.522984)
		(stroke
			(width 0.254)
			(type default)
		)
		(layer "In6.Cu")
	)
	(gr_line
		(start 174.46498 -12.436348)
		(end 174.46498 -10.048748)
		(stroke
			(width 0.254)
			(type default)
		)
		(layer "In6.Cu")
	)
	(gr_line
		(start 174.46498 -12.336272)
		(end 174.46498 -9.948672)
		(stroke
			(width 0.254)
			(type default)
		)
		(layer "In6.Cu")
	)
	(gr_line
		(start 174.46498 -10.048748)
		(end 175.25238 -10.048748)
		(stroke
			(width 0.254)
			(type default)
		)
		(layer "In6.Cu")
	)
	(gr_line
		(start 174.46498 -9.948672)
		(end 175.25238 -9.948672)
		(stroke
			(width 0.254)
			(type default)
		)
		(layer "In6.Cu")
	)
	(gr_line
		(start 174.46498 -8.236204)
		(end 174.46498 -5.848604)
		(stroke
			(width 0.254)
			(type default)
		)
		(layer "In6.Cu")
	)
	(gr_line
		(start 174.46498 -8.136128)
		(end 174.46498 -5.748528)
		(stroke
			(width 0.254)
			(type default)
		)
		(layer "In6.Cu")
	)
	(gr_line
		(start 174.46498 -5.848604)
		(end 175.25238 -5.848604)
		(stroke
			(width 0.254)
			(type default)
		)
		(layer "In6.Cu")
	)
	(gr_line
		(start 174.46498 -5.748528)
		(end 175.25238 -5.748528)
		(stroke
			(width 0.254)
			(type default)
		)
		(layer "In6.Cu")
	)
	(gr_line
		(start 174.46498 -4.03606)
		(end 174.46498 -1.64846)
		(stroke
			(width 0.254)
			(type default)
		)
		(layer "In6.Cu")
	)
	(gr_line
		(start 174.46498 -3.935984)
		(end 174.46498 -1.548384)
		(stroke
			(width 0.254)
			(type default)
		)
		(layer "In6.Cu")
	)
	(gr_line
		(start 174.46498 -1.64846)
		(end 175.25238 -1.64846)
		(stroke
			(width 0.254)
			(type default)
		)
		(layer "In6.Cu")
	)
	(gr_line
		(start 174.46498 -1.548384)
		(end 175.25238 -1.548384)
		(stroke
			(width 0.254)
			(type default)
		)
		(layer "In6.Cu")
	)
	(gr_line
		(start 174.49038 -12.360148)
		(end 175.12538 -12.360148)
		(stroke
			(width 0.508)
			(type default)
		)
		(layer "In6.Cu")
	)
	(gr_line
		(start 174.49038 -12.260072)
		(end 175.12538 -12.260072)
		(stroke
			(width 0.508)
			(type default)
		)
		(layer "In6.Cu")
	)
	(gr_line
		(start 174.49038 -10.175748)
		(end 175.12538 -10.175748)
		(stroke
			(width 0.508)
			(type default)
		)
		(layer "In6.Cu")
	)
	(gr_line
		(start 174.49038 -10.124948)
		(end 175.12538 -10.124948)
		(stroke
			(width 0.508)
			(type default)
		)
		(layer "In6.Cu")
	)
	(gr_line
		(start 174.49038 -10.075672)
		(end 175.12538 -10.075672)
		(stroke
			(width 0.508)
			(type default)
		)
		(layer "In6.Cu")
	)
	(gr_line
		(start 174.49038 -10.024872)
		(end 175.12538 -10.024872)
		(stroke
			(width 0.508)
			(type default)
		)
		(layer "In6.Cu")
	)
	(gr_line
		(start 174.49038 -8.160004)
		(end 175.12538 -8.160004)
		(stroke
			(width 0.508)
			(type default)
		)
		(layer "In6.Cu")
	)
	(gr_line
		(start 174.49038 -8.059928)
		(end 175.12538 -8.059928)
		(stroke
			(width 0.508)
			(type default)
		)
		(layer "In6.Cu")
	)
	(gr_line
		(start 174.49038 -5.975604)
		(end 175.12538 -5.975604)
		(stroke
			(width 0.508)
			(type default)
		)
		(layer "In6.Cu")
	)
	(gr_line
		(start 174.49038 -5.924804)
		(end 175.12538 -5.924804)
		(stroke
			(width 0.508)
			(type default)
		)
		(layer "In6.Cu")
	)
	(gr_line
		(start 174.49038 -5.875528)
		(end 175.12538 -5.875528)
		(stroke
			(width 0.508)
			(type default)
		)
		(layer "In6.Cu")
	)
	(gr_line
		(start 174.49038 -5.824728)
		(end 175.12538 -5.824728)
		(stroke
			(width 0.508)
			(type default)
		)
		(layer "In6.Cu")
	)
	(gr_line
		(start 174.49038 -3.95986)
		(end 175.12538 -3.95986)
		(stroke
			(width 0.508)
			(type default)
		)
		(layer "In6.Cu")
	)
	(gr_line
		(start 174.49038 -3.859784)
		(end 175.12538 -3.859784)
		(stroke
			(width 0.508)
			(type default)
		)
		(layer "In6.Cu")
	)
	(gr_line
		(start 174.49038 -1.77546)
		(end 175.12538 -1.77546)
		(stroke
			(width 0.508)
			(type default)
		)
		(layer "In6.Cu")
	)
	(gr_line
		(start 174.49038 -1.72466)
		(end 175.12538 -1.72466)
		(stroke
			(width 0.508)
			(type default)
		)
		(layer "In6.Cu")
	)
	(gr_line
		(start 174.49038 -1.675384)
		(end 175.12538 -1.675384)
		(stroke
			(width 0.508)
			(type default)
		)
		(layer "In6.Cu")
	)
	(gr_line
		(start 174.49038 -1.624584)
		(end 175.12538 -1.624584)
		(stroke
			(width 0.508)
			(type default)
		)
		(layer "In6.Cu")
	)
	(gr_line
		(start 174.51578 -10.429748)
		(end 175.15078 -10.429748)
		(stroke
			(width 0.508)
			(type default)
		)
		(layer "In6.Cu")
	)
	(gr_line
		(start 174.51578 -10.329672)
		(end 175.15078 -10.329672)
		(stroke
			(width 0.508)
			(type default)
		)
		(layer "In6.Cu")
	)
	(gr_line
		(start 174.51578 -6.229604)
		(end 175.15078 -6.229604)
		(stroke
			(width 0.508)
			(type default)
		)
		(layer "In6.Cu")
	)
	(gr_line
		(start 174.51578 -6.129528)
		(end 175.15078 -6.129528)
		(stroke
			(width 0.508)
			(type default)
		)
		(layer "In6.Cu")
	)
	(gr_line
		(start 174.51578 -2.02946)
		(end 175.15078 -2.02946)
		(stroke
			(width 0.508)
			(type default)
		)
		(layer "In6.Cu")
	)
	(gr_line
		(start 174.51578 -1.929384)
		(end 175.15078 -1.929384)
		(stroke
			(width 0.508)
			(type default)
		)
		(layer "In6.Cu")
	)
	(gr_line
		(start 174.54118 -12.385548)
		(end 174.54118 -10.124948)
		(stroke
			(width 0.254)
			(type default)
		)
		(layer "In6.Cu")
	)
	(gr_line
		(start 174.54118 -12.285472)
		(end 174.54118 -10.024872)
		(stroke
			(width 0.254)
			(type default)
		)
		(layer "In6.Cu")
	)
	(gr_line
		(start 174.54118 -12.233148)
		(end 175.17618 -12.233148)
		(stroke
			(width 0.508)
			(type default)
		)
		(layer "In6.Cu")
	)
	(gr_line
		(start 174.54118 -12.133072)
		(end 175.17618 -12.133072)
		(stroke
			(width 0.508)
			(type default)
		)
		(layer "In6.Cu")
	)
	(gr_line
		(start 174.54118 -10.124948)
		(end 175.17618 -10.124948)
		(stroke
			(width 0.254)
			(type default)
		)
		(layer "In6.Cu")
	)
	(gr_line
		(start 174.54118 -10.024872)
		(end 175.17618 -10.024872)
		(stroke
			(width 0.254)
			(type default)
		)
		(layer "In6.Cu")
	)
	(gr_line
		(start 174.54118 -8.185404)
		(end 174.54118 -5.924804)
		(stroke
			(width 0.254)
			(type default)
		)
		(layer "In6.Cu")
	)
	(gr_line
		(start 174.54118 -8.085328)
		(end 174.54118 -5.824728)
		(stroke
			(width 0.254)
			(type default)
		)
		(layer "In6.Cu")
	)
	(gr_line
		(start 174.54118 -8.033004)
		(end 175.17618 -8.033004)
		(stroke
			(width 0.508)
			(type default)
		)
		(layer "In6.Cu")
	)
	(gr_line
		(start 174.54118 -7.932928)
		(end 175.17618 -7.932928)
		(stroke
			(width 0.508)
			(type default)
		)
		(layer "In6.Cu")
	)
	(gr_line
		(start 174.54118 -5.924804)
		(end 175.17618 -5.924804)
		(stroke
			(width 0.254)
			(type default)
		)
		(layer "In6.Cu")
	)
	(gr_line
		(start 174.54118 -5.824728)
		(end 175.17618 -5.824728)
		(stroke
			(width 0.254)
			(type default)
		)
		(layer "In6.Cu")
	)
	(gr_line
		(start 174.54118 -3.98526)
		(end 174.54118 -1.72466)
		(stroke
			(width 0.254)
			(type default)
		)
		(layer "In6.Cu")
	)
	(gr_line
		(start 174.54118 -3.885184)
		(end 174.54118 -1.624584)
		(stroke
			(width 0.254)
			(type default)
		)
		(layer "In6.Cu")
	)
	(gr_line
		(start 174.54118 -3.83286)
		(end 175.17618 -3.83286)
		(stroke
			(width 0.508)
			(type default)
		)
		(layer "In6.Cu")
	)
	(gr_line
		(start 174.54118 -3.732784)
		(end 175.17618 -3.732784)
		(stroke
			(width 0.508)
			(type default)
		)
		(layer "In6.Cu")
	)
	(gr_line
		(start 174.54118 -1.72466)
		(end 175.17618 -1.72466)
		(stroke
			(width 0.254)
			(type default)
		)
		(layer "In6.Cu")
	)
	(gr_line
		(start 174.54118 -1.624584)
		(end 175.17618 -1.624584)
		(stroke
			(width 0.254)
			(type default)
		)
		(layer "In6.Cu")
	)
	(gr_line
		(start 174.56658 -12.080748)
		(end 175.20158 -12.080748)
		(stroke
			(width 0.508)
			(type default)
		)
		(layer "In6.Cu")
	)
	(gr_line
		(start 174.56658 -11.980672)
		(end 175.20158 -11.980672)
		(stroke
			(width 0.508)
			(type default)
		)
		(layer "In6.Cu")
	)
	(gr_line
		(start 174.56658 -7.880604)
		(end 175.20158 -7.880604)
		(stroke
			(width 0.508)
			(type default)
		)
		(layer "In6.Cu")
	)
	(gr_line
		(start 174.56658 -7.780528)
		(end 175.20158 -7.780528)
		(stroke
			(width 0.508)
			(type default)
		)
		(layer "In6.Cu")
	)
	(gr_line
		(start 174.56658 -3.68046)
		(end 175.20158 -3.68046)
		(stroke
			(width 0.508)
			(type default)
		)
		(layer "In6.Cu")
	)
	(gr_line
		(start 174.56658 -3.580384)
		(end 175.20158 -3.580384)
		(stroke
			(width 0.508)
			(type default)
		)
		(layer "In6.Cu")
	)
	(gr_line
		(start 174.59198 -12.360148)
		(end 175.22698 -12.360148)
		(stroke
			(width 0.508)
			(type default)
		)
		(layer "In6.Cu")
	)
	(gr_line
		(start 174.59198 -12.260072)
		(end 175.22698 -12.260072)
		(stroke
			(width 0.508)
			(type default)
		)
		(layer "In6.Cu")
	)
	(gr_line
		(start 174.59198 -9.947148)
		(end 175.43018 -9.947148)
		(stroke
			(width 0.2032)
			(type default)
		)
		(layer "In6.Cu")
	)
	(gr_line
		(start 174.59198 -9.847072)
		(end 175.43018 -9.847072)
		(stroke
			(width 0.2032)
			(type default)
		)
		(layer "In6.Cu")
	)
	(gr_line
		(start 174.59198 -8.160004)
		(end 175.22698 -8.160004)
		(stroke
			(width 0.508)
			(type default)
		)
		(layer "In6.Cu")
	)
	(gr_line
		(start 174.59198 -8.059928)
		(end 175.22698 -8.059928)
		(stroke
			(width 0.508)
			(type default)
		)
		(layer "In6.Cu")
	)
	(gr_line
		(start 174.59198 -5.747004)
		(end 175.43018 -5.747004)
		(stroke
			(width 0.2032)
			(type default)
		)
		(layer "In6.Cu")
	)
	(gr_line
		(start 174.59198 -5.646928)
		(end 175.43018 -5.646928)
		(stroke
			(width 0.2032)
			(type default)
		)
		(layer "In6.Cu")
	)
	(gr_line
		(start 174.59198 -3.95986)
		(end 175.22698 -3.95986)
		(stroke
			(width 0.508)
			(type default)
		)
		(layer "In6.Cu")
	)
	(gr_line
		(start 174.59198 -3.859784)
		(end 175.22698 -3.859784)
		(stroke
			(width 0.508)
			(type default)
		)
		(layer "In6.Cu")
	)
	(gr_line
		(start 174.59198 -1.54686)
		(end 175.43018 -1.54686)
		(stroke
			(width 0.2032)
			(type default)
		)
		(layer "In6.Cu")
	)
	(gr_line
		(start 174.59198 -1.446784)
		(end 175.43018 -1.446784)
		(stroke
			(width 0.2032)
			(type default)
		)
		(layer "In6.Cu")
	)
	(gr_line
		(start 174.61738 -12.360148)
		(end 174.61738 -10.175748)
		(stroke
			(width 0.254)
			(type default)
		)
		(layer "In6.Cu")
	)
	(gr_line
		(start 174.61738 -12.260072)
		(end 174.61738 -10.075672)
		(stroke
			(width 0.254)
			(type default)
		)
		(layer "In6.Cu")
	)
	(gr_line
		(start 174.61738 -10.175748)
		(end 175.09998 -10.175748)
		(stroke
			(width 0.254)
			(type default)
		)
		(layer "In6.Cu")
	)
	(gr_line
		(start 174.61738 -10.075672)
		(end 175.09998 -10.075672)
		(stroke
			(width 0.254)
			(type default)
		)
		(layer "In6.Cu")
	)
	(gr_line
		(start 174.61738 -9.997948)
		(end 175.35398 -9.997948)
		(stroke
			(width 0.254)
			(type default)
		)
		(layer "In6.Cu")
	)
	(gr_line
		(start 174.61738 -9.897872)
		(end 175.35398 -9.897872)
		(stroke
			(width 0.254)
			(type default)
		)
		(layer "In6.Cu")
	)
	(gr_line
		(start 174.61738 -8.160004)
		(end 174.61738 -5.975604)
		(stroke
			(width 0.254)
			(type default)
		)
		(layer "In6.Cu")
	)
	(gr_line
		(start 174.61738 -8.059928)
		(end 174.61738 -5.875528)
		(stroke
			(width 0.254)
			(type default)
		)
		(layer "In6.Cu")
	)
	(gr_line
		(start 174.61738 -5.975604)
		(end 175.09998 -5.975604)
		(stroke
			(width 0.254)
			(type default)
		)
		(layer "In6.Cu")
	)
	(gr_line
		(start 174.61738 -5.875528)
		(end 175.09998 -5.875528)
		(stroke
			(width 0.254)
			(type default)
		)
		(layer "In6.Cu")
	)
	(gr_line
		(start 174.61738 -5.797804)
		(end 175.35398 -5.797804)
		(stroke
			(width 0.254)
			(type default)
		)
		(layer "In6.Cu")
	)
	(gr_line
		(start 174.61738 -5.697728)
		(end 175.35398 -5.697728)
		(stroke
			(width 0.254)
			(type default)
		)
		(layer "In6.Cu")
	)
	(gr_line
		(start 174.61738 -3.95986)
		(end 174.61738 -1.77546)
		(stroke
			(width 0.254)
			(type default)
		)
		(layer "In6.Cu")
	)
	(gr_line
		(start 174.61738 -3.859784)
		(end 174.61738 -1.675384)
		(stroke
			(width 0.254)
			(type default)
		)
		(layer "In6.Cu")
	)
	(gr_line
		(start 174.61738 -1.77546)
		(end 175.09998 -1.77546)
		(stroke
			(width 0.254)
			(type default)
		)
		(layer "In6.Cu")
	)
	(gr_line
		(start 174.61738 -1.675384)
		(end 175.09998 -1.675384)
		(stroke
			(width 0.254)
			(type default)
		)
		(layer "In6.Cu")
	)
	(gr_line
		(start 174.61738 -1.59766)
		(end 175.35398 -1.59766)
		(stroke
			(width 0.254)
			(type default)
		)
		(layer "In6.Cu")
	)
	(gr_line
		(start 174.61738 -1.497584)
		(end 175.35398 -1.497584)
		(stroke
			(width 0.254)
			(type default)
		)
		(layer "In6.Cu")
	)
	(gr_line
		(start 174.635922 -10.110978)
		(end 175.270922 -10.110978)
		(stroke
			(width 0.508)
			(type default)
		)
		(layer "In6.Cu")
	)
	(gr_line
		(start 174.635922 -10.010902)
		(end 175.270922 -10.010902)
		(stroke
			(width 0.508)
			(type default)
		)
		(layer "In6.Cu")
	)
	(gr_line
		(start 174.635922 -5.910834)
		(end 175.270922 -5.910834)
		(stroke
			(width 0.508)
			(type default)
		)
		(layer "In6.Cu")
	)
	(gr_line
		(start 174.635922 -5.810758)
		(end 175.270922 -5.810758)
		(stroke
			(width 0.508)
			(type default)
		)
		(layer "In6.Cu")
	)
	(gr_line
		(start 174.635922 -1.71069)
		(end 175.270922 -1.71069)
		(stroke
			(width 0.508)
			(type default)
		)
		(layer "In6.Cu")
	)
	(gr_line
		(start 174.635922 -1.610614)
		(end 175.270922 -1.610614)
		(stroke
			(width 0.508)
			(type default)
		)
		(layer "In6.Cu")
	)
	(gr_line
		(start 174.64278 -12.360148)
		(end 175.27778 -12.360148)
		(stroke
			(width 0.508)
			(type default)
		)
		(layer "In6.Cu")
	)
	(gr_line
		(start 174.64278 -12.260072)
		(end 175.27778 -12.260072)
		(stroke
			(width 0.508)
			(type default)
		)
		(layer "In6.Cu")
	)
	(gr_line
		(start 174.64278 -12.233148)
		(end 174.64278 -10.251948)
		(stroke
			(width 0.762)
			(type default)
		)
		(layer "In6.Cu")
	)
	(gr_line
		(start 174.64278 -12.133072)
		(end 174.64278 -10.151872)
		(stroke
			(width 0.762)
			(type default)
		)
		(layer "In6.Cu")
	)
	(gr_line
		(start 174.64278 -10.251948)
		(end 175.27778 -10.251948)
		(stroke
			(width 0.508)
			(type default)
		)
		(layer "In6.Cu")
	)
	(gr_line
		(start 174.64278 -10.151872)
		(end 175.27778 -10.151872)
		(stroke
			(width 0.508)
			(type default)
		)
		(layer "In6.Cu")
	)
	(gr_line
		(start 174.64278 -8.160004)
		(end 175.27778 -8.160004)
		(stroke
			(width 0.508)
			(type default)
		)
		(layer "In6.Cu")
	)
	(gr_line
		(start 174.64278 -8.059928)
		(end 175.27778 -8.059928)
		(stroke
			(width 0.508)
			(type default)
		)
		(layer "In6.Cu")
	)
	(gr_line
		(start 174.64278 -8.033004)
		(end 174.64278 -6.051804)
		(stroke
			(width 0.762)
			(type default)
		)
		(layer "In6.Cu")
	)
	(gr_line
		(start 174.64278 -7.932928)
		(end 174.64278 -5.951728)
		(stroke
			(width 0.762)
			(type default)
		)
		(layer "In6.Cu")
	)
	(gr_line
		(start 174.64278 -6.051804)
		(end 175.27778 -6.051804)
		(stroke
			(width 0.508)
			(type default)
		)
		(layer "In6.Cu")
	)
	(gr_line
		(start 174.64278 -5.951728)
		(end 175.27778 -5.951728)
		(stroke
			(width 0.508)
			(type default)
		)
		(layer "In6.Cu")
	)
	(gr_line
		(start 174.64278 -3.95986)
		(end 175.27778 -3.95986)
		(stroke
			(width 0.508)
			(type default)
		)
		(layer "In6.Cu")
	)
	(gr_line
		(start 174.64278 -3.859784)
		(end 175.27778 -3.859784)
		(stroke
			(width 0.508)
			(type default)
		)
		(layer "In6.Cu")
	)
	(gr_line
		(start 174.64278 -3.83286)
		(end 174.64278 -1.85166)
		(stroke
			(width 0.762)
			(type default)
		)
		(layer "In6.Cu")
	)
	(gr_line
		(start 174.64278 -3.732784)
		(end 174.64278 -1.751584)
		(stroke
			(width 0.762)
			(type default)
		)
		(layer "In6.Cu")
	)
	(gr_line
		(start 174.64278 -1.85166)
		(end 175.27778 -1.85166)
		(stroke
			(width 0.508)
			(type default)
		)
		(layer "In6.Cu")
	)
	(gr_line
		(start 174.64278 -1.751584)
		(end 175.27778 -1.751584)
		(stroke
			(width 0.508)
			(type default)
		)
		(layer "In6.Cu")
	)
	(gr_line
		(start 174.69358 -12.283948)
		(end 174.69358 -10.251948)
		(stroke
			(width 0.254)
			(type default)
		)
		(layer "In6.Cu")
	)
	(gr_line
		(start 174.69358 -12.183872)
		(end 174.69358 -10.151872)
		(stroke
			(width 0.254)
			(type default)
		)
		(layer "In6.Cu")
	)
	(gr_line
		(start 174.69358 -10.251948)
		(end 175.02378 -10.251948)
		(stroke
			(width 0.254)
			(type default)
		)
		(layer "In6.Cu")
	)
	(gr_line
		(start 174.69358 -10.151872)
		(end 175.02378 -10.151872)
		(stroke
			(width 0.254)
			(type default)
		)
		(layer "In6.Cu")
	)
	(gr_line
		(start 174.69358 -8.083804)
		(end 174.69358 -6.051804)
		(stroke
			(width 0.254)
			(type default)
		)
		(layer "In6.Cu")
	)
	(gr_line
		(start 174.69358 -7.983728)
		(end 174.69358 -5.951728)
		(stroke
			(width 0.254)
			(type default)
		)
		(layer "In6.Cu")
	)
	(gr_line
		(start 174.69358 -6.051804)
		(end 175.02378 -6.051804)
		(stroke
			(width 0.254)
			(type default)
		)
		(layer "In6.Cu")
	)
	(gr_line
		(start 174.69358 -5.951728)
		(end 175.02378 -5.951728)
		(stroke
			(width 0.254)
			(type default)
		)
		(layer "In6.Cu")
	)
	(gr_line
		(start 174.69358 -3.88366)
		(end 174.69358 -1.85166)
		(stroke
			(width 0.254)
			(type default)
		)
		(layer "In6.Cu")
	)
	(gr_line
		(start 174.69358 -3.783584)
		(end 174.69358 -1.751584)
		(stroke
			(width 0.254)
			(type default)
		)
		(layer "In6.Cu")
	)
	(gr_line
		(start 174.69358 -1.85166)
		(end 175.02378 -1.85166)
		(stroke
			(width 0.254)
			(type default)
		)
		(layer "In6.Cu")
	)
	(gr_line
		(start 174.69358 -1.751584)
		(end 175.02378 -1.751584)
		(stroke
			(width 0.254)
			(type default)
		)
		(layer "In6.Cu")
	)
	(gr_line
		(start 174.79518 -12.207748)
		(end 174.79518 -10.404348)
		(stroke
			(width 0.254)
			(type default)
		)
		(layer "In6.Cu")
	)
	(gr_line
		(start 174.79518 -12.207748)
		(end 174.79518 -10.226548)
		(stroke
			(width 0.762)
			(type default)
		)
		(layer "In6.Cu")
	)
	(gr_line
		(start 174.79518 -12.107672)
		(end 174.79518 -10.304272)
		(stroke
			(width 0.254)
			(type default)
		)
		(layer "In6.Cu")
	)
	(gr_line
		(start 174.79518 -12.107672)
		(end 174.79518 -10.126472)
		(stroke
			(width 0.762)
			(type default)
		)
		(layer "In6.Cu")
	)
	(gr_line
		(start 174.79518 -10.404348)
		(end 174.89678 -10.404348)
		(stroke
			(width 0.254)
			(type default)
		)
		(layer "In6.Cu")
	)
	(gr_line
		(start 174.79518 -10.304272)
		(end 174.89678 -10.304272)
		(stroke
			(width 0.254)
			(type default)
		)
		(layer "In6.Cu")
	)
	(gr_line
		(start 174.79518 -8.007604)
		(end 174.79518 -6.204204)
		(stroke
			(width 0.254)
			(type default)
		)
		(layer "In6.Cu")
	)
	(gr_line
		(start 174.79518 -8.007604)
		(end 174.79518 -6.026404)
		(stroke
			(width 0.762)
			(type default)
		)
		(layer "In6.Cu")
	)
	(gr_line
		(start 174.79518 -7.907528)
		(end 174.79518 -6.104128)
		(stroke
			(width 0.254)
			(type default)
		)
		(layer "In6.Cu")
	)
	(gr_line
		(start 174.79518 -7.907528)
		(end 174.79518 -5.926328)
		(stroke
			(width 0.762)
			(type default)
		)
		(layer "In6.Cu")
	)
	(gr_line
		(start 174.79518 -6.204204)
		(end 174.89678 -6.204204)
		(stroke
			(width 0.254)
			(type default)
		)
		(layer "In6.Cu")
	)
	(gr_line
		(start 174.79518 -6.104128)
		(end 174.89678 -6.104128)
		(stroke
			(width 0.254)
			(type default)
		)
		(layer "In6.Cu")
	)
	(gr_line
		(start 174.79518 -3.80746)
		(end 174.79518 -2.00406)
		(stroke
			(width 0.254)
			(type default)
		)
		(layer "In6.Cu")
	)
	(gr_line
		(start 174.79518 -3.80746)
		(end 174.79518 -1.82626)
		(stroke
			(width 0.762)
			(type default)
		)
		(layer "In6.Cu")
	)
	(gr_line
		(start 174.79518 -3.707384)
		(end 174.79518 -1.903984)
		(stroke
			(width 0.254)
			(type default)
		)
		(layer "In6.Cu")
	)
	(gr_line
		(start 174.79518 -3.707384)
		(end 174.79518 -1.726184)
		(stroke
			(width 0.762)
			(type default)
		)
		(layer "In6.Cu")
	)
	(gr_line
		(start 174.79518 -2.00406)
		(end 174.89678 -2.00406)
		(stroke
			(width 0.254)
			(type default)
		)
		(layer "In6.Cu")
	)
	(gr_line
		(start 174.79518 -1.903984)
		(end 174.89678 -1.903984)
		(stroke
			(width 0.254)
			(type default)
		)
		(layer "In6.Cu")
	)
	(gr_line
		(start 174.89678 -12.309348)
		(end 174.84598 -12.309348)
		(stroke
			(width 0.254)
			(type default)
		)
		(layer "In6.Cu")
	)
	(gr_line
		(start 174.89678 -12.209272)
		(end 174.84598 -12.209272)
		(stroke
			(width 0.254)
			(type default)
		)
		(layer "In6.Cu")
	)
	(gr_line
		(start 174.89678 -10.404348)
		(end 174.89678 -12.309348)
		(stroke
			(width 0.254)
			(type default)
		)
		(layer "In6.Cu")
	)
	(gr_line
		(start 174.89678 -10.304272)
		(end 174.89678 -12.209272)
		(stroke
			(width 0.254)
			(type default)
		)
		(layer "In6.Cu")
	)
	(gr_line
		(start 174.89678 -8.109204)
		(end 174.84598 -8.109204)
		(stroke
			(width 0.254)
			(type default)
		)
		(layer "In6.Cu")
	)
	(gr_line
		(start 174.89678 -8.009128)
		(end 174.84598 -8.009128)
		(stroke
			(width 0.254)
			(type default)
		)
		(layer "In6.Cu")
	)
	(gr_line
		(start 174.89678 -6.204204)
		(end 174.89678 -8.109204)
		(stroke
			(width 0.254)
			(type default)
		)
		(layer "In6.Cu")
	)
	(gr_line
		(start 174.89678 -6.104128)
		(end 174.89678 -8.009128)
		(stroke
			(width 0.254)
			(type default)
		)
		(layer "In6.Cu")
	)
	(gr_line
		(start 174.89678 -3.90906)
		(end 174.84598 -3.90906)
		(stroke
			(width 0.254)
			(type default)
		)
		(layer "In6.Cu")
	)
	(gr_line
		(start 174.89678 -3.808984)
		(end 174.84598 -3.808984)
		(stroke
			(width 0.254)
			(type default)
		)
		(layer "In6.Cu")
	)
	(gr_line
		(start 174.89678 -2.00406)
		(end 174.89678 -3.90906)
		(stroke
			(width 0.254)
			(type default)
		)
		(layer "In6.Cu")
	)
	(gr_line
		(start 174.89678 -1.903984)
		(end 174.89678 -3.808984)
		(stroke
			(width 0.254)
			(type default)
		)
		(layer "In6.Cu")
	)
	(gr_line
		(start 174.94758 -12.233148)
		(end 174.94758 -10.251948)
		(stroke
			(width 0.762)
			(type default)
		)
		(layer "In6.Cu")
	)
	(gr_line
		(start 174.94758 -12.133072)
		(end 174.94758 -10.151872)
		(stroke
			(width 0.762)
			(type default)
		)
		(layer "In6.Cu")
	)
	(gr_line
		(start 174.94758 -8.033004)
		(end 174.94758 -6.051804)
		(stroke
			(width 0.762)
			(type default)
		)
		(layer "In6.Cu")
	)
	(gr_line
		(start 174.94758 -7.932928)
		(end 174.94758 -5.951728)
		(stroke
			(width 0.762)
			(type default)
		)
		(layer "In6.Cu")
	)
	(gr_line
		(start 174.94758 -3.83286)
		(end 174.94758 -1.85166)
		(stroke
			(width 0.762)
			(type default)
		)
		(layer "In6.Cu")
	)
	(gr_line
		(start 174.94758 -3.732784)
		(end 174.94758 -1.751584)
		(stroke
			(width 0.762)
			(type default)
		)
		(layer "In6.Cu")
	)
	(gr_line
		(start 175.02378 -12.207748)
		(end 174.79518 -12.207748)
		(stroke
			(width 0.254)
			(type default)
		)
		(layer "In6.Cu")
	)
	(gr_line
		(start 175.02378 -12.107672)
		(end 174.79518 -12.107672)
		(stroke
			(width 0.254)
			(type default)
		)
		(layer "In6.Cu")
	)
	(gr_line
		(start 175.02378 -10.251948)
		(end 175.02378 -12.207748)
		(stroke
			(width 0.254)
			(type default)
		)
		(layer "In6.Cu")
	)
	(gr_line
		(start 175.02378 -10.151872)
		(end 175.02378 -12.107672)
		(stroke
			(width 0.254)
			(type default)
		)
		(layer "In6.Cu")
	)
	(gr_line
		(start 175.02378 -8.007604)
		(end 174.79518 -8.007604)
		(stroke
			(width 0.254)
			(type default)
		)
		(layer "In6.Cu")
	)
	(gr_line
		(start 175.02378 -7.907528)
		(end 174.79518 -7.907528)
		(stroke
			(width 0.254)
			(type default)
		)
		(layer "In6.Cu")
	)
	(gr_line
		(start 175.02378 -6.051804)
		(end 175.02378 -8.007604)
		(stroke
			(width 0.254)
			(type default)
		)
		(layer "In6.Cu")
	)
	(gr_line
		(start 175.02378 -5.951728)
		(end 175.02378 -7.907528)
		(stroke
			(width 0.254)
			(type default)
		)
		(layer "In6.Cu")
	)
	(gr_line
		(start 175.02378 -3.80746)
		(end 174.79518 -3.80746)
		(stroke
			(width 0.254)
			(type default)
		)
		(layer "In6.Cu")
	)
	(gr_line
		(start 175.02378 -3.707384)
		(end 174.79518 -3.707384)
		(stroke
			(width 0.254)
			(type default)
		)
		(layer "In6.Cu")
	)
	(gr_line
		(start 175.02378 -1.85166)
		(end 175.02378 -3.80746)
		(stroke
			(width 0.254)
			(type default)
		)
		(layer "In6.Cu")
	)
	(gr_line
		(start 175.02378 -1.751584)
		(end 175.02378 -3.707384)
		(stroke
			(width 0.254)
			(type default)
		)
		(layer "In6.Cu")
	)
	(gr_line
		(start 175.07458 -12.563348)
		(end 175.07458 -12.512548)
		(stroke
			(width 0.1016)
			(type default)
		)
		(layer "In6.Cu")
	)
	(gr_line
		(start 175.07458 -12.563348)
		(end 175.48098 -12.563348)
		(stroke
			(width 0.1016)
			(type default)
		)
		(layer "In6.Cu")
	)
	(gr_line
		(start 175.07458 -12.512548)
		(end 174.31258 -12.512548)
		(stroke
			(width 0.1016)
			(type default)
		)
		(layer "In6.Cu")
	)
	(gr_line
		(start 175.07458 -12.463272)
		(end 175.07458 -12.412472)
		(stroke
			(width 0.1016)
			(type default)
		)
		(layer "In6.Cu")
	)
	(gr_line
		(start 175.07458 -12.463272)
		(end 175.48098 -12.463272)
		(stroke
			(width 0.1016)
			(type default)
		)
		(layer "In6.Cu")
	)
	(gr_line
		(start 175.07458 -12.412472)
		(end 174.31258 -12.412472)
		(stroke
			(width 0.1016)
			(type default)
		)
		(layer "In6.Cu")
	)
	(gr_line
		(start 175.07458 -12.233148)
		(end 175.07458 -10.251948)
		(stroke
			(width 0.762)
			(type default)
		)
		(layer "In6.Cu")
	)
	(gr_line
		(start 175.07458 -12.133072)
		(end 175.07458 -10.151872)
		(stroke
			(width 0.762)
			(type default)
		)
		(layer "In6.Cu")
	)
	(gr_line
		(start 175.07458 -8.363204)
		(end 175.07458 -8.312404)
		(stroke
			(width 0.1016)
			(type default)
		)
		(layer "In6.Cu")
	)
	(gr_line
		(start 175.07458 -8.363204)
		(end 175.48098 -8.363204)
		(stroke
			(width 0.1016)
			(type default)
		)
		(layer "In6.Cu")
	)
	(gr_line
		(start 175.07458 -8.312404)
		(end 174.31258 -8.312404)
		(stroke
			(width 0.1016)
			(type default)
		)
		(layer "In6.Cu")
	)
	(gr_line
		(start 175.07458 -8.263128)
		(end 175.07458 -8.212328)
		(stroke
			(width 0.1016)
			(type default)
		)
		(layer "In6.Cu")
	)
	(gr_line
		(start 175.07458 -8.263128)
		(end 175.48098 -8.263128)
		(stroke
			(width 0.1016)
			(type default)
		)
		(layer "In6.Cu")
	)
	(gr_line
		(start 175.07458 -8.212328)
		(end 174.31258 -8.212328)
		(stroke
			(width 0.1016)
			(type default)
		)
		(layer "In6.Cu")
	)
	(gr_line
		(start 175.07458 -8.033004)
		(end 175.07458 -6.051804)
		(stroke
			(width 0.762)
			(type default)
		)
		(layer "In6.Cu")
	)
	(gr_line
		(start 175.07458 -7.932928)
		(end 175.07458 -5.951728)
		(stroke
			(width 0.762)
			(type default)
		)
		(layer "In6.Cu")
	)
	(gr_line
		(start 175.07458 -4.16306)
		(end 175.07458 -4.11226)
		(stroke
			(width 0.1016)
			(type default)
		)
		(layer "In6.Cu")
	)
	(gr_line
		(start 175.07458 -4.16306)
		(end 175.48098 -4.16306)
		(stroke
			(width 0.1016)
			(type default)
		)
		(layer "In6.Cu")
	)
	(gr_line
		(start 175.07458 -4.11226)
		(end 174.31258 -4.11226)
		(stroke
			(width 0.1016)
			(type default)
		)
		(layer "In6.Cu")
	)
	(gr_line
		(start 175.07458 -4.062984)
		(end 175.07458 -4.012184)
		(stroke
			(width 0.1016)
			(type default)
		)
		(layer "In6.Cu")
	)
	(gr_line
		(start 175.07458 -4.062984)
		(end 175.48098 -4.062984)
		(stroke
			(width 0.1016)
			(type default)
		)
		(layer "In6.Cu")
	)
	(gr_line
		(start 175.07458 -4.012184)
		(end 174.31258 -4.012184)
		(stroke
			(width 0.1016)
			(type default)
		)
		(layer "In6.Cu")
	)
	(gr_line
		(start 175.07458 -3.83286)
		(end 175.07458 -1.85166)
		(stroke
			(width 0.762)
			(type default)
		)
		(layer "In6.Cu")
	)
	(gr_line
		(start 175.07458 -3.732784)
		(end 175.07458 -1.751584)
		(stroke
			(width 0.762)
			(type default)
		)
		(layer "In6.Cu")
	)
	(gr_line
		(start 175.09998 -12.283948)
		(end 174.69358 -12.283948)
		(stroke
			(width 0.254)
			(type default)
		)
		(layer "In6.Cu")
	)
	(gr_line
		(start 175.09998 -12.183872)
		(end 174.69358 -12.183872)
		(stroke
			(width 0.254)
			(type default)
		)
		(layer "In6.Cu")
	)
	(gr_line
		(start 175.09998 -10.175748)
		(end 175.09998 -12.283948)
		(stroke
			(width 0.254)
			(type default)
		)
		(layer "In6.Cu")
	)
	(gr_line
		(start 175.09998 -10.075672)
		(end 175.09998 -12.183872)
		(stroke
			(width 0.254)
			(type default)
		)
		(layer "In6.Cu")
	)
	(gr_line
		(start 175.09998 -8.083804)
		(end 174.69358 -8.083804)
		(stroke
			(width 0.254)
			(type default)
		)
		(layer "In6.Cu")
	)
	(gr_line
		(start 175.09998 -7.983728)
		(end 174.69358 -7.983728)
		(stroke
			(width 0.254)
			(type default)
		)
		(layer "In6.Cu")
	)
	(gr_line
		(start 175.09998 -5.975604)
		(end 175.09998 -8.083804)
		(stroke
			(width 0.254)
			(type default)
		)
		(layer "In6.Cu")
	)
	(gr_line
		(start 175.09998 -5.875528)
		(end 175.09998 -7.983728)
		(stroke
			(width 0.254)
			(type default)
		)
		(layer "In6.Cu")
	)
	(gr_line
		(start 175.09998 -3.88366)
		(end 174.69358 -3.88366)
		(stroke
			(width 0.254)
			(type default)
		)
		(layer "In6.Cu")
	)
	(gr_line
		(start 175.09998 -3.783584)
		(end 174.69358 -3.783584)
		(stroke
			(width 0.254)
			(type default)
		)
		(layer "In6.Cu")
	)
	(gr_line
		(start 175.09998 -1.77546)
		(end 175.09998 -3.88366)
		(stroke
			(width 0.254)
			(type default)
		)
		(layer "In6.Cu")
	)
	(gr_line
		(start 175.09998 -1.675384)
		(end 175.09998 -3.783584)
		(stroke
			(width 0.254)
			(type default)
		)
		(layer "In6.Cu")
	)
	(gr_line
		(start 175.15078 -12.233148)
		(end 175.15078 -10.251948)
		(stroke
			(width 0.762)
			(type default)
		)
		(layer "In6.Cu")
	)
	(gr_line
		(start 175.15078 -12.133072)
		(end 175.15078 -10.151872)
		(stroke
			(width 0.762)
			(type default)
		)
		(layer "In6.Cu")
	)
	(gr_line
		(start 175.15078 -8.033004)
		(end 175.15078 -6.051804)
		(stroke
			(width 0.762)
			(type default)
		)
		(layer "In6.Cu")
	)
	(gr_line
		(start 175.15078 -7.932928)
		(end 175.15078 -5.951728)
		(stroke
			(width 0.762)
			(type default)
		)
		(layer "In6.Cu")
	)
	(gr_line
		(start 175.15078 -3.83286)
		(end 175.15078 -1.85166)
		(stroke
			(width 0.762)
			(type default)
		)
		(layer "In6.Cu")
	)
	(gr_line
		(start 175.15078 -3.732784)
		(end 175.15078 -1.751584)
		(stroke
			(width 0.762)
			(type default)
		)
		(layer "In6.Cu")
	)
	(gr_line
		(start 175.17618 -12.360148)
		(end 174.61738 -12.360148)
		(stroke
			(width 0.254)
			(type default)
		)
		(layer "In6.Cu")
	)
	(gr_line
		(start 175.17618 -12.260072)
		(end 174.61738 -12.260072)
		(stroke
			(width 0.254)
			(type default)
		)
		(layer "In6.Cu")
	)
	(gr_line
		(start 175.17618 -10.124948)
		(end 175.17618 -12.360148)
		(stroke
			(width 0.254)
			(type default)
		)
		(layer "In6.Cu")
	)
	(gr_line
		(start 175.17618 -10.024872)
		(end 175.17618 -12.260072)
		(stroke
			(width 0.254)
			(type default)
		)
		(layer "In6.Cu")
	)
	(gr_line
		(start 175.17618 -8.160004)
		(end 174.61738 -8.160004)
		(stroke
			(width 0.254)
			(type default)
		)
		(layer "In6.Cu")
	)
	(gr_line
		(start 175.17618 -8.059928)
		(end 174.61738 -8.059928)
		(stroke
			(width 0.254)
			(type default)
		)
		(layer "In6.Cu")
	)
	(gr_line
		(start 175.17618 -5.924804)
		(end 175.17618 -8.160004)
		(stroke
			(width 0.254)
			(type default)
		)
		(layer "In6.Cu")
	)
	(gr_line
		(start 175.17618 -5.824728)
		(end 175.17618 -8.059928)
		(stroke
			(width 0.254)
			(type default)
		)
		(layer "In6.Cu")
	)
	(gr_line
		(start 175.17618 -3.95986)
		(end 174.61738 -3.95986)
		(stroke
			(width 0.254)
			(type default)
		)
		(layer "In6.Cu")
	)
	(gr_line
		(start 175.17618 -3.859784)
		(end 174.61738 -3.859784)
		(stroke
			(width 0.254)
			(type default)
		)
		(layer "In6.Cu")
	)
	(gr_line
		(start 175.17618 -1.72466)
		(end 175.17618 -3.95986)
		(stroke
			(width 0.254)
			(type default)
		)
		(layer "In6.Cu")
	)
	(gr_line
		(start 175.17618 -1.624584)
		(end 175.17618 -3.859784)
		(stroke
			(width 0.254)
			(type default)
		)
		(layer "In6.Cu")
	)
	(gr_line
		(start 175.25238 -12.385548)
		(end 174.54118 -12.385548)
		(stroke
			(width 0.254)
			(type default)
		)
		(layer "In6.Cu")
	)
	(gr_line
		(start 175.25238 -12.285472)
		(end 174.54118 -12.285472)
		(stroke
			(width 0.254)
			(type default)
		)
		(layer "In6.Cu")
	)
	(gr_line
		(start 175.25238 -10.048748)
		(end 175.25238 -12.385548)
		(stroke
			(width 0.254)
			(type default)
		)
		(layer "In6.Cu")
	)
	(gr_line
		(start 175.25238 -9.948672)
		(end 175.25238 -12.285472)
		(stroke
			(width 0.254)
			(type default)
		)
		(layer "In6.Cu")
	)
	(gr_line
		(start 175.25238 -8.185404)
		(end 174.54118 -8.185404)
		(stroke
			(width 0.254)
			(type default)
		)
		(layer "In6.Cu")
	)
	(gr_line
		(start 175.25238 -8.085328)
		(end 174.54118 -8.085328)
		(stroke
			(width 0.254)
			(type default)
		)
		(layer "In6.Cu")
	)
	(gr_line
		(start 175.25238 -5.848604)
		(end 175.25238 -8.185404)
		(stroke
			(width 0.254)
			(type default)
		)
		(layer "In6.Cu")
	)
	(gr_line
		(start 175.25238 -5.748528)
		(end 175.25238 -8.085328)
		(stroke
			(width 0.254)
			(type default)
		)
		(layer "In6.Cu")
	)
	(gr_line
		(start 175.25238 -3.98526)
		(end 174.54118 -3.98526)
		(stroke
			(width 0.254)
			(type default)
		)
		(layer "In6.Cu")
	)
	(gr_line
		(start 175.25238 -3.885184)
		(end 174.54118 -3.885184)
		(stroke
			(width 0.254)
			(type default)
		)
		(layer "In6.Cu")
	)
	(gr_line
		(start 175.25238 -1.64846)
		(end 175.25238 -3.98526)
		(stroke
			(width 0.254)
			(type default)
		)
		(layer "In6.Cu")
	)
	(gr_line
		(start 175.25238 -1.548384)
		(end 175.25238 -3.885184)
		(stroke
			(width 0.254)
			(type default)
		)
		(layer "In6.Cu")
	)
	(gr_line
		(start 175.27778 -12.512548)
		(end 174.28718 -12.512548)
		(stroke
			(width 0.1016)
			(type default)
		)
		(layer "In6.Cu")
	)
	(gr_line
		(start 175.27778 -12.436348)
		(end 174.46498 -12.436348)
		(stroke
			(width 0.254)
			(type default)
		)
		(layer "In6.Cu")
	)
	(gr_line
		(start 175.27778 -12.412472)
		(end 174.28718 -12.412472)
		(stroke
			(width 0.1016)
			(type default)
		)
		(layer "In6.Cu")
	)
	(gr_line
		(start 175.27778 -12.336272)
		(end 174.46498 -12.336272)
		(stroke
			(width 0.254)
			(type default)
		)
		(layer "In6.Cu")
	)
	(gr_line
		(start 175.27778 -10.023348)
		(end 175.27778 -12.436348)
		(stroke
			(width 0.254)
			(type default)
		)
		(layer "In6.Cu")
	)
	(gr_line
		(start 175.27778 -9.923272)
		(end 175.27778 -12.336272)
		(stroke
			(width 0.254)
			(type default)
		)
		(layer "In6.Cu")
	)
	(gr_line
		(start 175.27778 -8.312404)
		(end 174.28718 -8.312404)
		(stroke
			(width 0.1016)
			(type default)
		)
		(layer "In6.Cu")
	)
	(gr_line
		(start 175.27778 -8.236204)
		(end 174.46498 -8.236204)
		(stroke
			(width 0.254)
			(type default)
		)
		(layer "In6.Cu")
	)
	(gr_line
		(start 175.27778 -8.212328)
		(end 174.28718 -8.212328)
		(stroke
			(width 0.1016)
			(type default)
		)
		(layer "In6.Cu")
	)
	(gr_line
		(start 175.27778 -8.136128)
		(end 174.46498 -8.136128)
		(stroke
			(width 0.254)
			(type default)
		)
		(layer "In6.Cu")
	)
	(gr_line
		(start 175.27778 -5.823204)
		(end 175.27778 -8.236204)
		(stroke
			(width 0.254)
			(type default)
		)
		(layer "In6.Cu")
	)
	(gr_line
		(start 175.27778 -5.723128)
		(end 175.27778 -8.136128)
		(stroke
			(width 0.254)
			(type default)
		)
		(layer "In6.Cu")
	)
	(gr_line
		(start 175.27778 -4.11226)
		(end 174.28718 -4.11226)
		(stroke
			(width 0.1016)
			(type default)
		)
		(layer "In6.Cu")
	)
	(gr_line
		(start 175.27778 -4.03606)
		(end 174.46498 -4.03606)
		(stroke
			(width 0.254)
			(type default)
		)
		(layer "In6.Cu")
	)
	(gr_line
		(start 175.27778 -4.012184)
		(end 174.28718 -4.012184)
		(stroke
			(width 0.1016)
			(type default)
		)
		(layer "In6.Cu")
	)
	(gr_line
		(start 175.27778 -3.935984)
		(end 174.46498 -3.935984)
		(stroke
			(width 0.254)
			(type default)
		)
		(layer "In6.Cu")
	)
	(gr_line
		(start 175.27778 -1.62306)
		(end 175.27778 -4.03606)
		(stroke
			(width 0.254)
			(type default)
		)
		(layer "In6.Cu")
	)
	(gr_line
		(start 175.27778 -1.522984)
		(end 175.27778 -3.935984)
		(stroke
			(width 0.254)
			(type default)
		)
		(layer "In6.Cu")
	)
	(gr_line
		(start 175.30318 -12.461748)
		(end 174.43958 -12.461748)
		(stroke
			(width 0.254)
			(type default)
		)
		(layer "In6.Cu")
	)
	(gr_line
		(start 175.30318 -12.361672)
		(end 174.43958 -12.361672)
		(stroke
			(width 0.254)
			(type default)
		)
		(layer "In6.Cu")
	)
	(gr_line
		(start 175.30318 -9.997948)
		(end 175.30318 -12.461748)
		(stroke
			(width 0.254)
			(type default)
		)
		(layer "In6.Cu")
	)
	(gr_line
		(start 175.30318 -9.897872)
		(end 175.30318 -12.361672)
		(stroke
			(width 0.254)
			(type default)
		)
		(layer "In6.Cu")
	)
	(gr_line
		(start 175.30318 -8.261604)
		(end 174.43958 -8.261604)
		(stroke
			(width 0.254)
			(type default)
		)
		(layer "In6.Cu")
	)
	(gr_line
		(start 175.30318 -8.161528)
		(end 174.43958 -8.161528)
		(stroke
			(width 0.254)
			(type default)
		)
		(layer "In6.Cu")
	)
	(gr_line
		(start 175.30318 -5.797804)
		(end 175.30318 -8.261604)
		(stroke
			(width 0.254)
			(type default)
		)
		(layer "In6.Cu")
	)
	(gr_line
		(start 175.30318 -5.697728)
		(end 175.30318 -8.161528)
		(stroke
			(width 0.254)
			(type default)
		)
		(layer "In6.Cu")
	)
	(gr_line
		(start 175.30318 -4.06146)
		(end 174.43958 -4.06146)
		(stroke
			(width 0.254)
			(type default)
		)
		(layer "In6.Cu")
	)
	(gr_line
		(start 175.30318 -3.961384)
		(end 174.43958 -3.961384)
		(stroke
			(width 0.254)
			(type default)
		)
		(layer "In6.Cu")
	)
	(gr_line
		(start 175.30318 -1.59766)
		(end 175.30318 -4.06146)
		(stroke
			(width 0.254)
			(type default)
		)
		(layer "In6.Cu")
	)
	(gr_line
		(start 175.30318 -1.497584)
		(end 175.30318 -3.961384)
		(stroke
			(width 0.254)
			(type default)
		)
		(layer "In6.Cu")
	)
	(gr_line
		(start 175.35398 -12.487148)
		(end 174.41418 -12.487148)
		(stroke
			(width 0.254)
			(type default)
		)
		(layer "In6.Cu")
	)
	(gr_line
		(start 175.35398 -12.387072)
		(end 174.41418 -12.387072)
		(stroke
			(width 0.254)
			(type default)
		)
		(layer "In6.Cu")
	)
	(gr_line
		(start 175.35398 -9.997948)
		(end 175.35398 -12.487148)
		(stroke
			(width 0.254)
			(type default)
		)
		(layer "In6.Cu")
	)
	(gr_line
		(start 175.35398 -9.897872)
		(end 175.35398 -12.387072)
		(stroke
			(width 0.254)
			(type default)
		)
		(layer "In6.Cu")
	)
	(gr_line
		(start 175.35398 -8.287004)
		(end 174.41418 -8.287004)
		(stroke
			(width 0.254)
			(type default)
		)
		(layer "In6.Cu")
	)
	(gr_line
		(start 175.35398 -8.186928)
		(end 174.41418 -8.186928)
		(stroke
			(width 0.254)
			(type default)
		)
		(layer "In6.Cu")
	)
	(gr_line
		(start 175.35398 -5.797804)
		(end 175.35398 -8.287004)
		(stroke
			(width 0.254)
			(type default)
		)
		(layer "In6.Cu")
	)
	(gr_line
		(start 175.35398 -5.697728)
		(end 175.35398 -8.186928)
		(stroke
			(width 0.254)
			(type default)
		)
		(layer "In6.Cu")
	)
	(gr_line
		(start 175.35398 -4.08686)
		(end 174.41418 -4.08686)
		(stroke
			(width 0.254)
			(type default)
		)
		(layer "In6.Cu")
	)
	(gr_line
		(start 175.35398 -3.986784)
		(end 174.41418 -3.986784)
		(stroke
			(width 0.254)
			(type default)
		)
		(layer "In6.Cu")
	)
	(gr_line
		(start 175.35398 -1.59766)
		(end 175.35398 -4.08686)
		(stroke
			(width 0.254)
			(type default)
		)
		(layer "In6.Cu")
	)
	(gr_line
		(start 175.35398 -1.497584)
		(end 175.35398 -3.986784)
		(stroke
			(width 0.254)
			(type default)
		)
		(layer "In6.Cu")
	)
	(gr_line
		(start 175.37938 -12.487148)
		(end 174.41418 -12.487148)
		(stroke
			(width 0.2032)
			(type default)
		)
		(layer "In6.Cu")
	)
	(gr_line
		(start 175.37938 -12.387072)
		(end 174.41418 -12.387072)
		(stroke
			(width 0.2032)
			(type default)
		)
		(layer "In6.Cu")
	)
	(gr_line
		(start 175.37938 -9.947148)
		(end 175.37938 -12.487148)
		(stroke
			(width 0.2032)
			(type default)
		)
		(layer "In6.Cu")
	)
	(gr_line
		(start 175.37938 -9.847072)
		(end 175.37938 -12.387072)
		(stroke
			(width 0.2032)
			(type default)
		)
		(layer "In6.Cu")
	)
	(gr_line
		(start 175.37938 -8.287004)
		(end 174.41418 -8.287004)
		(stroke
			(width 0.2032)
			(type default)
		)
		(layer "In6.Cu")
	)
	(gr_line
		(start 175.37938 -8.186928)
		(end 174.41418 -8.186928)
		(stroke
			(width 0.2032)
			(type default)
		)
		(layer "In6.Cu")
	)
	(gr_line
		(start 175.37938 -5.747004)
		(end 175.37938 -8.287004)
		(stroke
			(width 0.2032)
			(type default)
		)
		(layer "In6.Cu")
	)
	(gr_line
		(start 175.37938 -5.646928)
		(end 175.37938 -8.186928)
		(stroke
			(width 0.2032)
			(type default)
		)
		(layer "In6.Cu")
	)
	(gr_line
		(start 175.37938 -4.08686)
		(end 174.41418 -4.08686)
		(stroke
			(width 0.2032)
			(type default)
		)
		(layer "In6.Cu")
	)
	(gr_line
		(start 175.37938 -3.986784)
		(end 174.41418 -3.986784)
		(stroke
			(width 0.2032)
			(type default)
		)
		(layer "In6.Cu")
	)
	(gr_line
		(start 175.37938 -1.54686)
		(end 175.37938 -4.08686)
		(stroke
			(width 0.2032)
			(type default)
		)
		(layer "In6.Cu")
	)
	(gr_line
		(start 175.37938 -1.446784)
		(end 175.37938 -3.986784)
		(stroke
			(width 0.2032)
			(type default)
		)
		(layer "In6.Cu")
	)
	(gr_line
		(start 175.43018 -12.512548)
		(end 174.36338 -12.512548)
		(stroke
			(width 0.2032)
			(type default)
		)
		(layer "In6.Cu")
	)
	(gr_line
		(start 175.43018 -12.412472)
		(end 174.36338 -12.412472)
		(stroke
			(width 0.2032)
			(type default)
		)
		(layer "In6.Cu")
	)
	(gr_line
		(start 175.43018 -9.947148)
		(end 175.43018 -12.512548)
		(stroke
			(width 0.2032)
			(type default)
		)
		(layer "In6.Cu")
	)
	(gr_line
		(start 175.43018 -9.847072)
		(end 175.43018 -12.412472)
		(stroke
			(width 0.2032)
			(type default)
		)
		(layer "In6.Cu")
	)
	(gr_line
		(start 175.43018 -8.312404)
		(end 174.36338 -8.312404)
		(stroke
			(width 0.2032)
			(type default)
		)
		(layer "In6.Cu")
	)
	(gr_line
		(start 175.43018 -8.212328)
		(end 174.36338 -8.212328)
		(stroke
			(width 0.2032)
			(type default)
		)
		(layer "In6.Cu")
	)
	(gr_line
		(start 175.43018 -5.747004)
		(end 175.43018 -8.312404)
		(stroke
			(width 0.2032)
			(type default)
		)
		(layer "In6.Cu")
	)
	(gr_line
		(start 175.43018 -5.646928)
		(end 175.43018 -8.212328)
		(stroke
			(width 0.2032)
			(type default)
		)
		(layer "In6.Cu")
	)
	(gr_line
		(start 175.43018 -4.11226)
		(end 174.36338 -4.11226)
		(stroke
			(width 0.2032)
			(type default)
		)
		(layer "In6.Cu")
	)
	(gr_line
		(start 175.43018 -4.012184)
		(end 174.36338 -4.012184)
		(stroke
			(width 0.2032)
			(type default)
		)
		(layer "In6.Cu")
	)
	(gr_line
		(start 175.43018 -1.54686)
		(end 175.43018 -4.11226)
		(stroke
			(width 0.2032)
			(type default)
		)
		(layer "In6.Cu")
	)
	(gr_line
		(start 175.43018 -1.446784)
		(end 175.43018 -4.012184)
		(stroke
			(width 0.2032)
			(type default)
		)
		(layer "In6.Cu")
	)
	(gr_line
		(start 175.45558 -12.512548)
		(end 174.33798 -12.512548)
		(stroke
			(width 0.1016)
			(type default)
		)
		(layer "In6.Cu")
	)
	(gr_line
		(start 175.45558 -12.412472)
		(end 174.33798 -12.412472)
		(stroke
			(width 0.1016)
			(type default)
		)
		(layer "In6.Cu")
	)
	(gr_line
		(start 175.45558 -9.921748)
		(end 175.45558 -12.512548)
		(stroke
			(width 0.1016)
			(type default)
		)
		(layer "In6.Cu")
	)
	(gr_line
		(start 175.45558 -9.821672)
		(end 175.45558 -12.412472)
		(stroke
			(width 0.1016)
			(type default)
		)
		(layer "In6.Cu")
	)
	(gr_line
		(start 175.45558 -8.312404)
		(end 174.33798 -8.312404)
		(stroke
			(width 0.1016)
			(type default)
		)
		(layer "In6.Cu")
	)
	(gr_line
		(start 175.45558 -8.212328)
		(end 174.33798 -8.212328)
		(stroke
			(width 0.1016)
			(type default)
		)
		(layer "In6.Cu")
	)
	(gr_line
		(start 175.45558 -5.721604)
		(end 175.45558 -8.312404)
		(stroke
			(width 0.1016)
			(type default)
		)
		(layer "In6.Cu")
	)
	(gr_line
		(start 175.45558 -5.621528)
		(end 175.45558 -8.212328)
		(stroke
			(width 0.1016)
			(type default)
		)
		(layer "In6.Cu")
	)
	(gr_line
		(start 175.45558 -4.11226)
		(end 174.33798 -4.11226)
		(stroke
			(width 0.1016)
			(type default)
		)
		(layer "In6.Cu")
	)
	(gr_line
		(start 175.45558 -4.012184)
		(end 174.33798 -4.012184)
		(stroke
			(width 0.1016)
			(type default)
		)
		(layer "In6.Cu")
	)
	(gr_line
		(start 175.45558 -1.52146)
		(end 175.45558 -4.11226)
		(stroke
			(width 0.1016)
			(type default)
		)
		(layer "In6.Cu")
	)
	(gr_line
		(start 175.45558 -1.421384)
		(end 175.45558 -4.012184)
		(stroke
			(width 0.1016)
			(type default)
		)
		(layer "In6.Cu")
	)
	(gr_line
		(start 175.48098 -12.563348)
		(end 175.07458 -12.563348)
		(stroke
			(width 0.1016)
			(type default)
		)
		(layer "In6.Cu")
	)
	(gr_line
		(start 175.48098 -12.563348)
		(end 175.48098 -9.896348)
		(stroke
			(width 0.1016)
			(type default)
		)
		(layer "In6.Cu")
	)
	(gr_line
		(start 175.48098 -12.463272)
		(end 175.07458 -12.463272)
		(stroke
			(width 0.1016)
			(type default)
		)
		(layer "In6.Cu")
	)
	(gr_line
		(start 175.48098 -12.463272)
		(end 175.48098 -9.796272)
		(stroke
			(width 0.1016)
			(type default)
		)
		(layer "In6.Cu")
	)
	(gr_line
		(start 175.48098 -9.896348)
		(end 174.28718 -9.896348)
		(stroke
			(width 0.1016)
			(type default)
		)
		(layer "In6.Cu")
	)
	(gr_line
		(start 175.48098 -9.896348)
		(end 175.48098 -12.563348)
		(stroke
			(width 0.1016)
			(type default)
		)
		(layer "In6.Cu")
	)
	(gr_line
		(start 175.48098 -9.796272)
		(end 174.28718 -9.796272)
		(stroke
			(width 0.1016)
			(type default)
		)
		(layer "In6.Cu")
	)
	(gr_line
		(start 175.48098 -9.796272)
		(end 175.48098 -12.463272)
		(stroke
			(width 0.1016)
			(type default)
		)
		(layer "In6.Cu")
	)
	(gr_line
		(start 175.48098 -8.363204)
		(end 175.07458 -8.363204)
		(stroke
			(width 0.1016)
			(type default)
		)
		(layer "In6.Cu")
	)
	(gr_line
		(start 175.48098 -8.363204)
		(end 175.48098 -5.696204)
		(stroke
			(width 0.1016)
			(type default)
		)
		(layer "In6.Cu")
	)
	(gr_line
		(start 175.48098 -8.263128)
		(end 175.07458 -8.263128)
		(stroke
			(width 0.1016)
			(type default)
		)
		(layer "In6.Cu")
	)
	(gr_line
		(start 175.48098 -8.263128)
		(end 175.48098 -5.596128)
		(stroke
			(width 0.1016)
			(type default)
		)
		(layer "In6.Cu")
	)
	(gr_line
		(start 175.48098 -5.696204)
		(end 174.28718 -5.696204)
		(stroke
			(width 0.1016)
			(type default)
		)
		(layer "In6.Cu")
	)
	(gr_line
		(start 175.48098 -5.696204)
		(end 175.48098 -8.363204)
		(stroke
			(width 0.1016)
			(type default)
		)
		(layer "In6.Cu")
	)
	(gr_line
		(start 175.48098 -5.596128)
		(end 174.28718 -5.596128)
		(stroke
			(width 0.1016)
			(type default)
		)
		(layer "In6.Cu")
	)
	(gr_line
		(start 175.48098 -5.596128)
		(end 175.48098 -8.263128)
		(stroke
			(width 0.1016)
			(type default)
		)
		(layer "In6.Cu")
	)
	(gr_line
		(start 175.48098 -4.16306)
		(end 175.07458 -4.16306)
		(stroke
			(width 0.1016)
			(type default)
		)
		(layer "In6.Cu")
	)
	(gr_line
		(start 175.48098 -4.16306)
		(end 175.48098 -1.49606)
		(stroke
			(width 0.1016)
			(type default)
		)
		(layer "In6.Cu")
	)
	(gr_line
		(start 175.48098 -4.062984)
		(end 175.07458 -4.062984)
		(stroke
			(width 0.1016)
			(type default)
		)
		(layer "In6.Cu")
	)
	(gr_line
		(start 175.48098 -4.062984)
		(end 175.48098 -1.395984)
		(stroke
			(width 0.1016)
			(type default)
		)
		(layer "In6.Cu")
	)
	(gr_line
		(start 175.48098 -1.49606)
		(end 174.28718 -1.49606)
		(stroke
			(width 0.1016)
			(type default)
		)
		(layer "In6.Cu")
	)
	(gr_line
		(start 175.48098 -1.49606)
		(end 175.48098 -4.16306)
		(stroke
			(width 0.1016)
			(type default)
		)
		(layer "In6.Cu")
	)
	(gr_line
		(start 175.48098 -1.395984)
		(end 174.28718 -1.395984)
		(stroke
			(width 0.1016)
			(type default)
		)
		(layer "In6.Cu")
	)
	(gr_line
		(start 175.48098 -1.395984)
		(end 175.48098 -4.062984)
		(stroke
			(width 0.1016)
			(type default)
		)
		(layer "In6.Cu")
	)
	(gr_line
		(start 176.520094 -30.99562)
		(end 175.250094 -30.99562)
		(stroke
			(width 0.7874)
			(type default)
		)
		(layer "In6.Cu")
	)
	(gr_line
		(start 178.22418 -24.6634)
		(end 178.22418 -23.3934)
		(stroke
			(width 0.7874)
			(type default)
		)
		(layer "In6.Cu")
	)
	(gr_line
		(start 183.9976 -26.8224)
		(end 185.2676 -26.8224)
		(stroke
			(width 0.7874)
			(type default)
		)
		(layer "In6.Cu")
	)
	(gr_line
		(start 184.22874 -29.30906)
		(end 185.49874 -29.30906)
		(stroke
			(width 0.7874)
			(type default)
		)
		(layer "In6.Cu")
	)
	(gr_line
		(start 189.45987 -30.594808)
		(end 190.72987 -30.594808)
		(stroke
			(width 0.7874)
			(type default)
		)
		(layer "In6.Cu")
	)
	(gr_line
		(start 191.12992 -23.57882)
		(end 189.85992 -23.57882)
		(stroke
			(width 0.7874)
			(type default)
		)
		(layer "In6.Cu")
	)
	(gr_line
		(start 191.87414 -31.68142)
		(end 193.14414 -31.68142)
		(stroke
			(width 0.7874)
			(type default)
		)
		(layer "In6.Cu")
	)
	(gr_line
		(start 193.529966 -18.5166)
		(end 192.259966 -18.5166)
		(stroke
			(width 0.7874)
			(type default)
		)
		(layer "In6.Cu")
	)
	(gr_line
		(start 194.259962 -30.56382)
		(end 195.529962 -30.56382)
		(stroke
			(width 0.7874)
			(type default)
		)
		(layer "In6.Cu")
	)
	(gr_arc
		(start 197.300088 -8.263382)
		(mid 198.922885 -13.697276)
		(end 201.00036 -8.420608)
		(stroke
			(width 1.016)
			(type default)
		)
		(layer "In6.Cu")
	)
	(gr_line
		(start 197.300088 -4.907788)
		(end 197.300088 -8.263382)
		(stroke
			(width 1.016)
			(type default)
		)
		(layer "In6.Cu")
	)
	(gr_line
		(start 197.310756 -4.89712)
		(end 197.300088 -4.907788)
		(stroke
			(width 1.016)
			(type default)
		)
		(layer "In6.Cu")
	)
	(gr_line
		(start 197.6628 -24.67102)
		(end 197.6628 -23.40102)
		(stroke
			(width 0.7874)
			(type default)
		)
		(layer "In6.Cu")
	)
	(gr_line
		(start 199.04964 -10.700004)
		(end 199.049894 -10.700258)
		(stroke
			(width 4.064)
			(type default)
		)
		(layer "In6.Cu")
	)
	(gr_line
		(start 199.04964 -4.699762)
		(end 199.04964 -10.700004)
		(stroke
			(width 4.064)
			(type default)
		)
		(layer "In6.Cu")
	)
	(gr_line
		(start 199.049894 -10.700258)
		(end 199.049894 -10.700004)
		(stroke
			(width 6.604)
			(type default)
		)
		(layer "In6.Cu")
	)
	(gr_line
		(start 200.799954 -8.220202)
		(end 200.799954 -4.700016)
		(stroke
			(width 1.016)
			(type default)
		)
		(layer "In6.Cu")
	)
	(gr_arc
		(start 200.799954 -4.700016)
		(mid 198.951198 -2.952487)
		(end 197.310756 -4.89712)
		(stroke
			(width 1.016)
			(type default)
		)
		(layer "In6.Cu")
	)
	(gr_line
		(start 201.00036 -8.420608)
		(end 200.799954 -8.220202)
		(stroke
			(width 1.016)
			(type default)
		)
		(layer "In6.Cu")
	)
	(gr_line
		(start 202.989942 -50.390044)
		(end 203.36891 -50.464466)
		(stroke
			(width 1.016)
			(type default)
		)
		(layer "In6.Cu")
	)
	(gr_line
		(start 203.36891 -50.464466)
		(end 203.691236 -50.677064)
		(stroke
			(width 1.016)
			(type default)
		)
		(layer "In6.Cu")
	)
	(gr_line
		(start 203.691236 -50.677064)
		(end 203.909168 -50.996088)
		(stroke
			(width 1.016)
			(type default)
		)
		(layer "In6.Cu")
	)
	(gr_line
		(start 203.909168 -50.996088)
		(end 203.997814 -51.376072)
		(stroke
			(width 1.016)
			(type default)
		)
		(layer "In6.Cu")
	)
	(gr_line
		(start 203.997814 -51.376072)
		(end 204.06614 -51.702716)
		(stroke
			(width 1.016)
			(type default)
		)
		(layer "In6.Cu")
	)
	(gr_line
		(start 204.06614 -51.702716)
		(end 204.282802 -52.027074)
		(stroke
			(width 1.016)
			(type default)
		)
		(layer "In6.Cu")
	)
	(gr_line
		(start 204.282802 -52.027074)
		(end 204.607414 -52.24399)
		(stroke
			(width 1.016)
			(type default)
		)
		(layer "In6.Cu")
	)
	(gr_line
		(start 204.68336 -52.319936)
		(end 204.607414 -52.24399)
		(stroke
			(width 1.016)
			(type default)
		)
		(layer "In6.Cu")
	)
	(gr_arc
		(start 208.060036 -45.06341)
		(mid 209.682833 -50.497304)
		(end 211.760308 -45.220636)
		(stroke
			(width 1.016)
			(type default)
		)
		(layer "In6.Cu")
	)
	(gr_line
		(start 208.060036 -41.707816)
		(end 208.060036 -45.06341)
		(stroke
			(width 1.016)
			(type default)
		)
		(layer "In6.Cu")
	)
	(gr_line
		(start 208.070704 -41.697148)
		(end 208.060036 -41.707816)
		(stroke
			(width 1.016)
			(type default)
		)
		(layer "In6.Cu")
	)
	(gr_line
		(start 209.809588 -47.500032)
		(end 209.809842 -47.500286)
		(stroke
			(width 4.064)
			(type default)
		)
		(layer "In6.Cu")
	)
	(gr_line
		(start 209.809588 -41.49979)
		(end 209.809588 -47.500032)
		(stroke
			(width 4.064)
			(type default)
		)
		(layer "In6.Cu")
	)
	(gr_line
		(start 209.809842 -47.500286)
		(end 209.809842 -47.500032)
		(stroke
			(width 6.604)
			(type default)
		)
		(layer "In6.Cu")
	)
	(gr_line
		(start 211.559902 -45.02023)
		(end 211.559902 -41.500044)
		(stroke
			(width 1.016)
			(type default)
		)
		(layer "In6.Cu")
	)
	(gr_arc
		(start 211.559902 -41.500044)
		(mid 209.711146 -39.752515)
		(end 208.070704 -41.697148)
		(stroke
			(width 1.016)
			(type default)
		)
		(layer "In6.Cu")
	)
	(gr_line
		(start 211.760308 -45.220636)
		(end 211.559902 -45.02023)
		(stroke
			(width 1.016)
			(type default)
		)
		(layer "In6.Cu")
	)
	(gr_arc
		(start 278.06015 -8.263128)
		(mid 279.682947 -13.697022)
		(end 281.760422 -8.420354)
		(stroke
			(width 1.016)
			(type default)
		)
		(layer "In6.Cu")
	)
	(gr_line
		(start 278.06015 -4.907534)
		(end 278.06015 -8.263128)
		(stroke
			(width 1.016)
			(type default)
		)
		(layer "In6.Cu")
	)
	(gr_line
		(start 278.070818 -4.896866)
		(end 278.06015 -4.907534)
		(stroke
			(width 1.016)
			(type default)
		)
		(layer "In6.Cu")
	)
	(gr_line
		(start 279.809702 -10.69975)
		(end 279.809956 -10.700004)
		(stroke
			(width 4.064)
			(type default)
		)
		(layer "In6.Cu")
	)
	(gr_line
		(start 279.809702 -4.699508)
		(end 279.809702 -10.69975)
		(stroke
			(width 4.064)
			(type default)
		)
		(layer "In6.Cu")
	)
	(gr_line
		(start 279.809956 -10.700004)
		(end 279.809956 -10.69975)
		(stroke
			(width 6.604)
			(type default)
		)
		(layer "In6.Cu")
	)
	(gr_line
		(start 281.560016 -8.219948)
		(end 281.560016 -4.699762)
		(stroke
			(width 1.016)
			(type default)
		)
		(layer "In6.Cu")
	)
	(gr_arc
		(start 281.560016 -4.699762)
		(mid 279.71126 -2.952233)
		(end 278.070818 -4.896866)
		(stroke
			(width 1.016)
			(type default)
		)
		(layer "In6.Cu")
	)
	(gr_line
		(start 281.760422 -8.420354)
		(end 281.560016 -8.219948)
		(stroke
			(width 1.016)
			(type default)
		)
		(layer "In6.Cu")
	)
	(gr_arc
		(start 299.060108 -45.06341)
		(mid 300.682905 -50.497304)
		(end 302.76038 -45.220636)
		(stroke
			(width 1.016)
			(type default)
		)
		(layer "In6.Cu")
	)
	(gr_line
		(start 299.060108 -41.707816)
		(end 299.060108 -45.06341)
		(stroke
			(width 1.016)
			(type default)
		)
		(layer "In6.Cu")
	)
	(gr_line
		(start 299.070776 -41.697148)
		(end 299.060108 -41.707816)
		(stroke
			(width 1.016)
			(type default)
		)
		(layer "In6.Cu")
	)
	(gr_line
		(start 300.80966 -47.500032)
		(end 300.809914 -47.500286)
		(stroke
			(width 4.064)
			(type default)
		)
		(layer "In6.Cu")
	)
	(gr_line
		(start 300.80966 -41.49979)
		(end 300.80966 -47.500032)
		(stroke
			(width 4.064)
			(type default)
		)
		(layer "In6.Cu")
	)
	(gr_line
		(start 300.809914 -47.500286)
		(end 300.809914 -47.500032)
		(stroke
			(width 6.604)
			(type default)
		)
		(layer "In6.Cu")
	)
	(gr_line
		(start 302.559974 -45.02023)
		(end 302.559974 -41.500044)
		(stroke
			(width 1.016)
			(type default)
		)
		(layer "In6.Cu")
	)
	(gr_arc
		(start 302.559974 -41.500044)
		(mid 300.711218 -39.752515)
		(end 299.070776 -41.697148)
		(stroke
			(width 1.016)
			(type default)
		)
		(layer "In6.Cu")
	)
	(gr_line
		(start 302.76038 -45.220636)
		(end 302.559974 -45.02023)
		(stroke
			(width 1.016)
			(type default)
		)
		(layer "In6.Cu")
	)
	(gr_line
		(start 316.06998 -52.319936)
		(end 204.68336 -52.319936)
		(stroke
			(width 1.016)
			(type default)
		)
		(layer "In6.Cu")
	)
	(gr_arc
		(start 316.06998 -52.319936)
		(mid 316.777112 -52.027053)
		(end 317.069978 -51.319938)
		(stroke
			(width 1.016)
			(type default)
		)
		(layer "In6.Cu")
	)
	(gr_line
		(start 317.069978 -50.8)
		(end 317.069978 -51.319938)
		(stroke
			(width 1.016)
			(type default)
		)
		(layer "In6.Cu")
	)
	(gr_arc
		(start 318.069976 -49.800002)
		(mid 317.362871 -50.092895)
		(end 317.069978 -50.8)
		(stroke
			(width 1.016)
			(type default)
		)
		(layer "In6.Cu")
	)
	(gr_line
		(start 322.576698 -11.3792)
		(end 322.576698 -9.1948)
		(stroke
			(width 0.254)
			(type default)
		)
		(layer "In6.Cu")
	)
	(gr_line
		(start 322.576698 -9.1948)
		(end 324.151498 -9.1948)
		(stroke
			(width 0.254)
			(type default)
		)
		(layer "In6.Cu")
	)
	(gr_line
		(start 322.602098 -11.3792)
		(end 322.602098 -9.2456)
		(stroke
			(width 0.254)
			(type default)
		)
		(layer "In6.Cu")
	)
	(gr_line
		(start 322.602098 -9.2456)
		(end 324.126098 -9.2456)
		(stroke
			(width 0.254)
			(type default)
		)
		(layer "In6.Cu")
	)
	(gr_line
		(start 322.652898 -11.3538)
		(end 322.652898 -9.3726)
		(stroke
			(width 0.254)
			(type default)
		)
		(layer "In6.Cu")
	)
	(gr_line
		(start 322.652898 -9.3726)
		(end 324.100698 -9.3726)
		(stroke
			(width 0.254)
			(type default)
		)
		(layer "In6.Cu")
	)
	(gr_line
		(start 322.707 -11.303)
		(end 323.0118 -11.303)
		(stroke
			(width 0.1016)
			(type default)
		)
		(layer "In6.Cu")
	)
	(gr_line
		(start 322.707 -9.2964)
		(end 322.707 -11.303)
		(stroke
			(width 0.1016)
			(type default)
		)
		(layer "In6.Cu")
	)
	(gr_line
		(start 322.73494 -5.57784)
		(end 324.00494 -5.57784)
		(stroke
			(width 1.016)
			(type default)
		)
		(layer "In6.Cu")
	)
	(gr_line
		(start 322.7578 -11.2268)
		(end 323.85 -11.2268)
		(stroke
			(width 0.2032)
			(type default)
		)
		(layer "In6.Cu")
	)
	(gr_line
		(start 322.7578 -9.3726)
		(end 322.7578 -11.2268)
		(stroke
			(width 0.2032)
			(type default)
		)
		(layer "In6.Cu")
	)
	(gr_line
		(start 322.7832 -11.2268)
		(end 323.9516 -11.2268)
		(stroke
			(width 0.2032)
			(type default)
		)
		(layer "In6.Cu")
	)
	(gr_line
		(start 322.7832 -9.4234)
		(end 322.7832 -11.2268)
		(stroke
			(width 0.2032)
			(type default)
		)
		(layer "In6.Cu")
	)
	(gr_line
		(start 322.830698 -11.1252)
		(end 322.830698 -9.5758)
		(stroke
			(width 0.762)
			(type default)
		)
		(layer "In6.Cu")
	)
	(gr_line
		(start 322.830698 -11.1252)
		(end 323.745098 -11.1252)
		(stroke
			(width 0.762)
			(type default)
		)
		(layer "In6.Cu")
	)
	(gr_line
		(start 322.830698 -11.0998)
		(end 322.830698 -9.5504)
		(stroke
			(width 0.762)
			(type default)
		)
		(layer "In6.Cu")
	)
	(gr_line
		(start 322.830698 -10.9982)
		(end 322.830698 -9.4488)
		(stroke
			(width 0.762)
			(type default)
		)
		(layer "In6.Cu")
	)
	(gr_line
		(start 322.830698 -9.4488)
		(end 323.745098 -9.4488)
		(stroke
			(width 0.762)
			(type default)
		)
		(layer "In6.Cu")
	)
	(gr_line
		(start 322.834 -11.176)
		(end 323.9262 -11.176)
		(stroke
			(width 0.2032)
			(type default)
		)
		(layer "In6.Cu")
	)
	(gr_line
		(start 322.834 -9.4742)
		(end 322.834 -11.176)
		(stroke
			(width 0.2032)
			(type default)
		)
		(layer "In6.Cu")
	)
	(gr_line
		(start 322.856098 -10.9982)
		(end 323.770498 -10.9982)
		(stroke
			(width 0.762)
			(type default)
		)
		(layer "In6.Cu")
	)
	(gr_line
		(start 322.856098 -9.5758)
		(end 323.770498 -9.5758)
		(stroke
			(width 0.762)
			(type default)
		)
		(layer "In6.Cu")
	)
	(gr_line
		(start 322.9356 -11.0744)
		(end 323.723 -11.0744)
		(stroke
			(width 0.508)
			(type default)
		)
		(layer "In6.Cu")
	)
	(gr_line
		(start 322.9356 -11.049)
		(end 322.9356 -9.525)
		(stroke
			(width 0.508)
			(type default)
		)
		(layer "In6.Cu")
	)
	(gr_line
		(start 322.961 -11.0744)
		(end 322.961 -9.5504)
		(stroke
			(width 0.508)
			(type default)
		)
		(layer "In6.Cu")
	)
	(gr_line
		(start 322.983098 -11.1252)
		(end 323.897498 -11.1252)
		(stroke
			(width 0.762)
			(type default)
		)
		(layer "In6.Cu")
	)
	(gr_line
		(start 322.983098 -9.4488)
		(end 323.897498 -9.4488)
		(stroke
			(width 0.762)
			(type default)
		)
		(layer "In6.Cu")
	)
	(gr_line
		(start 322.9864 -9.525)
		(end 323.723 -9.525)
		(stroke
			(width 0.508)
			(type default)
		)
		(layer "In6.Cu")
	)
	(gr_line
		(start 323.0118 -11.303)
		(end 324.0024 -11.303)
		(stroke
			(width 0.1016)
			(type default)
		)
		(layer "In6.Cu")
	)
	(gr_line
		(start 323.0118 -11.0744)
		(end 323.0118 -9.5504)
		(stroke
			(width 0.508)
			(type default)
		)
		(layer "In6.Cu")
	)
	(gr_line
		(start 323.0372 -11.0744)
		(end 323.0372 -9.5504)
		(stroke
			(width 0.508)
			(type default)
		)
		(layer "In6.Cu")
	)
	(gr_line
		(start 323.0626 -11.0744)
		(end 323.0626 -9.5504)
		(stroke
			(width 0.508)
			(type default)
		)
		(layer "In6.Cu")
	)
	(gr_line
		(start 323.088 -11.0744)
		(end 323.088 -9.5504)
		(stroke
			(width 0.508)
			(type default)
		)
		(layer "In6.Cu")
	)
	(gr_line
		(start 323.088 -11.049)
		(end 323.088 -9.525)
		(stroke
			(width 0.508)
			(type default)
		)
		(layer "In6.Cu")
	)
	(gr_line
		(start 323.1134 -11.0744)
		(end 323.1134 -9.5504)
		(stroke
			(width 0.508)
			(type default)
		)
		(layer "In6.Cu")
	)
	(gr_line
		(start 323.1388 -11.0744)
		(end 323.1388 -9.5504)
		(stroke
			(width 0.508)
			(type default)
		)
		(layer "In6.Cu")
	)
	(gr_line
		(start 323.1896 -11.0744)
		(end 323.1896 -9.5504)
		(stroke
			(width 0.508)
			(type default)
		)
		(layer "In6.Cu")
	)
	(gr_line
		(start 323.1896 -11.049)
		(end 323.1896 -9.525)
		(stroke
			(width 0.508)
			(type default)
		)
		(layer "In6.Cu")
	)
	(gr_line
		(start 323.215 -11.0744)
		(end 323.215 -9.5504)
		(stroke
			(width 0.508)
			(type default)
		)
		(layer "In6.Cu")
	)
	(gr_line
		(start 323.2404 -11.0744)
		(end 323.2404 -9.5504)
		(stroke
			(width 0.508)
			(type default)
		)
		(layer "In6.Cu")
	)
	(gr_line
		(start 323.2658 -11.0744)
		(end 323.2658 -9.5504)
		(stroke
			(width 0.508)
			(type default)
		)
		(layer "In6.Cu")
	)
	(gr_line
		(start 323.3166 -11.0744)
		(end 323.3166 -9.5504)
		(stroke
			(width 0.508)
			(type default)
		)
		(layer "In6.Cu")
	)
	(gr_line
		(start 323.342 -11.0744)
		(end 323.342 -9.5504)
		(stroke
			(width 0.508)
			(type default)
		)
		(layer "In6.Cu")
	)
	(gr_line
		(start 323.342 -11.049)
		(end 323.342 -9.525)
		(stroke
			(width 0.508)
			(type default)
		)
		(layer "In6.Cu")
	)
	(gr_line
		(start 323.3674 -11.0744)
		(end 323.3674 -9.5504)
		(stroke
			(width 0.508)
			(type default)
		)
		(layer "In6.Cu")
	)
	(gr_line
		(start 323.3928 -11.0744)
		(end 323.3928 -9.5504)
		(stroke
			(width 0.508)
			(type default)
		)
		(layer "In6.Cu")
	)
	(gr_line
		(start 323.4182 -11.0744)
		(end 323.4182 -9.5504)
		(stroke
			(width 0.508)
			(type default)
		)
		(layer "In6.Cu")
	)
	(gr_line
		(start 323.4182 -11.049)
		(end 323.4182 -9.525)
		(stroke
			(width 0.508)
			(type default)
		)
		(layer "In6.Cu")
	)
	(gr_line
		(start 323.4436 -11.0744)
		(end 323.4436 -9.5504)
		(stroke
			(width 0.508)
			(type default)
		)
		(layer "In6.Cu")
	)
	(gr_line
		(start 323.469 -11.0744)
		(end 323.469 -9.5504)
		(stroke
			(width 0.508)
			(type default)
		)
		(layer "In6.Cu")
	)
	(gr_line
		(start 323.469 -11.049)
		(end 323.469 -9.525)
		(stroke
			(width 0.508)
			(type default)
		)
		(layer "In6.Cu")
	)
	(gr_line
		(start 323.4944 -11.0744)
		(end 323.4944 -9.5504)
		(stroke
			(width 0.508)
			(type default)
		)
		(layer "In6.Cu")
	)
	(gr_line
		(start 323.4944 -11.049)
		(end 323.4944 -9.525)
		(stroke
			(width 0.508)
			(type default)
		)
		(layer "In6.Cu")
	)
	(gr_line
		(start 323.5198 -11.049)
		(end 323.5198 -9.525)
		(stroke
			(width 0.508)
			(type default)
		)
		(layer "In6.Cu")
	)
	(gr_line
		(start 323.5452 -11.0744)
		(end 323.5452 -9.5504)
		(stroke
			(width 0.508)
			(type default)
		)
		(layer "In6.Cu")
	)
	(gr_line
		(start 323.567298 -11.3792)
		(end 322.576698 -11.3792)
		(stroke
			(width 0.254)
			(type default)
		)
		(layer "In6.Cu")
	)
	(gr_line
		(start 323.5706 -11.049)
		(end 323.5706 -9.525)
		(stroke
			(width 0.508)
			(type default)
		)
		(layer "In6.Cu")
	)
	(gr_line
		(start 323.596 -11.049)
		(end 323.596 -9.525)
		(stroke
			(width 0.508)
			(type default)
		)
		(layer "In6.Cu")
	)
	(gr_line
		(start 323.6214 -11.0744)
		(end 323.6214 -9.5504)
		(stroke
			(width 0.508)
			(type default)
		)
		(layer "In6.Cu")
	)
	(gr_line
		(start 323.6468 -11.0744)
		(end 323.6468 -9.5504)
		(stroke
			(width 0.508)
			(type default)
		)
		(layer "In6.Cu")
	)
	(gr_line
		(start 323.6468 -11.049)
		(end 323.6468 -9.525)
		(stroke
			(width 0.508)
			(type default)
		)
		(layer "In6.Cu")
	)
	(gr_line
		(start 323.6976 -11.0744)
		(end 323.6976 -9.5504)
		(stroke
			(width 0.508)
			(type default)
		)
		(layer "In6.Cu")
	)
	(gr_line
		(start 323.6976 -11.049)
		(end 323.6976 -9.525)
		(stroke
			(width 0.508)
			(type default)
		)
		(layer "In6.Cu")
	)
	(gr_line
		(start 323.7484 -11.0744)
		(end 323.7484 -9.5504)
		(stroke
			(width 0.508)
			(type default)
		)
		(layer "In6.Cu")
	)
	(gr_line
		(start 323.7484 -11.049)
		(end 323.7484 -9.525)
		(stroke
			(width 0.508)
			(type default)
		)
		(layer "In6.Cu")
	)
	(gr_line
		(start 323.770498 -11.0998)
		(end 323.770498 -9.5504)
		(stroke
			(width 0.762)
			(type default)
		)
		(layer "In6.Cu")
	)
	(gr_line
		(start 323.7738 -11.0744)
		(end 323.7738 -9.5504)
		(stroke
			(width 0.508)
			(type default)
		)
		(layer "In6.Cu")
	)
	(gr_line
		(start 323.7992 -11.0744)
		(end 323.7992 -9.5504)
		(stroke
			(width 0.508)
			(type default)
		)
		(layer "In6.Cu")
	)
	(gr_line
		(start 323.85 -11.2268)
		(end 323.8754 -11.2268)
		(stroke
			(width 0.2032)
			(type default)
		)
		(layer "In6.Cu")
	)
	(gr_line
		(start 323.8754 -11.2268)
		(end 323.8754 -9.4742)
		(stroke
			(width 0.2032)
			(type default)
		)
		(layer "In6.Cu")
	)
	(gr_line
		(start 323.8754 -9.4742)
		(end 322.834 -9.4742)
		(stroke
			(width 0.2032)
			(type default)
		)
		(layer "In6.Cu")
	)
	(gr_line
		(start 323.897498 -11.1252)
		(end 323.897498 -9.5758)
		(stroke
			(width 0.762)
			(type default)
		)
		(layer "In6.Cu")
	)
	(gr_line
		(start 323.897498 -11.0998)
		(end 323.897498 -9.6012)
		(stroke
			(width 0.762)
			(type default)
		)
		(layer "In6.Cu")
	)
	(gr_line
		(start 323.897498 -10.9982)
		(end 323.897498 -9.4488)
		(stroke
			(width 0.762)
			(type default)
		)
		(layer "In6.Cu")
	)
	(gr_line
		(start 323.9262 -11.176)
		(end 323.9262 -9.4234)
		(stroke
			(width 0.2032)
			(type default)
		)
		(layer "In6.Cu")
	)
	(gr_line
		(start 323.9262 -9.4234)
		(end 322.7832 -9.4234)
		(stroke
			(width 0.2032)
			(type default)
		)
		(layer "In6.Cu")
	)
	(gr_line
		(start 323.9516 -11.2268)
		(end 323.9516 -9.3726)
		(stroke
			(width 0.2032)
			(type default)
		)
		(layer "In6.Cu")
	)
	(gr_line
		(start 323.9516 -9.3726)
		(end 322.7578 -9.3726)
		(stroke
			(width 0.2032)
			(type default)
		)
		(layer "In6.Cu")
	)
	(gr_line
		(start 324.0024 -11.303)
		(end 324.0024 -9.2964)
		(stroke
			(width 0.1016)
			(type default)
		)
		(layer "In6.Cu")
	)
	(gr_line
		(start 324.0024 -9.2964)
		(end 322.707 -9.2964)
		(stroke
			(width 0.1016)
			(type default)
		)
		(layer "In6.Cu")
	)
	(gr_line
		(start 324.100698 -11.2268)
		(end 323.85 -11.2268)
		(stroke
			(width 0.254)
			(type default)
		)
		(layer "In6.Cu")
	)
	(gr_line
		(start 324.100698 -9.3726)
		(end 324.100698 -11.2268)
		(stroke
			(width 0.254)
			(type default)
		)
		(layer "In6.Cu")
	)
	(gr_line
		(start 324.126098 -11.3538)
		(end 322.652898 -11.3538)
		(stroke
			(width 0.254)
			(type default)
		)
		(layer "In6.Cu")
	)
	(gr_line
		(start 324.126098 -9.2456)
		(end 324.126098 -11.3538)
		(stroke
			(width 0.254)
			(type default)
		)
		(layer "In6.Cu")
	)
	(gr_line
		(start 324.151498 -11.3792)
		(end 322.602098 -11.3792)
		(stroke
			(width 0.254)
			(type default)
		)
		(layer "In6.Cu")
	)
	(gr_line
		(start 324.151498 -9.1948)
		(end 324.151498 -11.3792)
		(stroke
			(width 0.254)
			(type default)
		)
		(layer "In6.Cu")
	)
	(gr_line
		(start 327.37679 -11.3792)
		(end 327.37679 -9.1948)
		(stroke
			(width 0.254)
			(type default)
		)
		(layer "In6.Cu")
	)
	(gr_line
		(start 327.37679 -9.1948)
		(end 328.95159 -9.1948)
		(stroke
			(width 0.254)
			(type default)
		)
		(layer "In6.Cu")
	)
	(gr_line
		(start 327.40219 -11.3792)
		(end 327.40219 -9.2456)
		(stroke
			(width 0.254)
			(type default)
		)
		(layer "In6.Cu")
	)
	(gr_line
		(start 327.40219 -9.2456)
		(end 328.92619 -9.2456)
		(stroke
			(width 0.254)
			(type default)
		)
		(layer "In6.Cu")
	)
	(gr_line
		(start 327.45299 -11.3538)
		(end 327.45299 -9.3726)
		(stroke
			(width 0.254)
			(type default)
		)
		(layer "In6.Cu")
	)
	(gr_line
		(start 327.45299 -9.3726)
		(end 328.90079 -9.3726)
		(stroke
			(width 0.254)
			(type default)
		)
		(layer "In6.Cu")
	)
	(gr_line
		(start 327.507092 -11.303)
		(end 327.811892 -11.303)
		(stroke
			(width 0.1016)
			(type default)
		)
		(layer "In6.Cu")
	)
	(gr_line
		(start 327.507092 -9.2964)
		(end 327.507092 -11.303)
		(stroke
			(width 0.1016)
			(type default)
		)
		(layer "In6.Cu")
	)
	(gr_line
		(start 327.557892 -11.2268)
		(end 328.650092 -11.2268)
		(stroke
			(width 0.2032)
			(type default)
		)
		(layer "In6.Cu")
	)
	(gr_line
		(start 327.557892 -9.3726)
		(end 327.557892 -11.2268)
		(stroke
			(width 0.2032)
			(type default)
		)
		(layer "In6.Cu")
	)
	(gr_line
		(start 327.583292 -11.2268)
		(end 328.751692 -11.2268)
		(stroke
			(width 0.2032)
			(type default)
		)
		(layer "In6.Cu")
	)
	(gr_line
		(start 327.583292 -9.4234)
		(end 327.583292 -11.2268)
		(stroke
			(width 0.2032)
			(type default)
		)
		(layer "In6.Cu")
	)
	(gr_line
		(start 327.63079 -11.1252)
		(end 327.63079 -9.5758)
		(stroke
			(width 0.762)
			(type default)
		)
		(layer "In6.Cu")
	)
	(gr_line
		(start 327.63079 -11.1252)
		(end 328.54519 -11.1252)
		(stroke
			(width 0.762)
			(type default)
		)
		(layer "In6.Cu")
	)
	(gr_line
		(start 327.63079 -11.0998)
		(end 327.63079 -9.5504)
		(stroke
			(width 0.762)
			(type default)
		)
		(layer "In6.Cu")
	)
	(gr_line
		(start 327.63079 -10.9982)
		(end 327.63079 -9.4488)
		(stroke
			(width 0.762)
			(type default)
		)
		(layer "In6.Cu")
	)
	(gr_line
		(start 327.63079 -9.4488)
		(end 328.54519 -9.4488)
		(stroke
			(width 0.762)
			(type default)
		)
		(layer "In6.Cu")
	)
	(gr_line
		(start 327.634092 -11.176)
		(end 328.726292 -11.176)
		(stroke
			(width 0.2032)
			(type default)
		)
		(layer "In6.Cu")
	)
	(gr_line
		(start 327.634092 -9.4742)
		(end 327.634092 -11.176)
		(stroke
			(width 0.2032)
			(type default)
		)
		(layer "In6.Cu")
	)
	(gr_line
		(start 327.65619 -10.9982)
		(end 328.57059 -10.9982)
		(stroke
			(width 0.762)
			(type default)
		)
		(layer "In6.Cu")
	)
	(gr_line
		(start 327.65619 -9.5758)
		(end 328.57059 -9.5758)
		(stroke
			(width 0.762)
			(type default)
		)
		(layer "In6.Cu")
	)
	(gr_line
		(start 327.735692 -11.0744)
		(end 328.523092 -11.0744)
		(stroke
			(width 0.508)
			(type default)
		)
		(layer "In6.Cu")
	)
	(gr_line
		(start 327.735692 -11.049)
		(end 327.735692 -9.525)
		(stroke
			(width 0.508)
			(type default)
		)
		(layer "In6.Cu")
	)
	(gr_line
		(start 327.761092 -11.0744)
		(end 327.761092 -9.5504)
		(stroke
			(width 0.508)
			(type default)
		)
		(layer "In6.Cu")
	)
	(gr_line
		(start 327.78319 -11.1252)
		(end 328.69759 -11.1252)
		(stroke
			(width 0.762)
			(type default)
		)
		(layer "In6.Cu")
	)
	(gr_line
		(start 327.78319 -9.4488)
		(end 328.69759 -9.4488)
		(stroke
			(width 0.762)
			(type default)
		)
		(layer "In6.Cu")
	)
	(gr_line
		(start 327.786492 -9.525)
		(end 328.523092 -9.525)
		(stroke
			(width 0.508)
			(type default)
		)
		(layer "In6.Cu")
	)
	(gr_line
		(start 327.811892 -11.303)
		(end 328.802492 -11.303)
		(stroke
			(width 0.1016)
			(type default)
		)
		(layer "In6.Cu")
	)
	(gr_line
		(start 327.811892 -11.0744)
		(end 327.811892 -9.5504)
		(stroke
			(width 0.508)
			(type default)
		)
		(layer "In6.Cu")
	)
	(gr_line
		(start 327.837292 -11.0744)
		(end 327.837292 -9.5504)
		(stroke
			(width 0.508)
			(type default)
		)
		(layer "In6.Cu")
	)
	(gr_line
		(start 327.862692 -11.0744)
		(end 327.862692 -9.5504)
		(stroke
			(width 0.508)
			(type default)
		)
		(layer "In6.Cu")
	)
	(gr_line
		(start 327.888092 -11.0744)
		(end 327.888092 -9.5504)
		(stroke
			(width 0.508)
			(type default)
		)
		(layer "In6.Cu")
	)
	(gr_line
		(start 327.888092 -11.049)
		(end 327.888092 -9.525)
		(stroke
			(width 0.508)
			(type default)
		)
		(layer "In6.Cu")
	)
	(gr_line
		(start 327.913492 -11.0744)
		(end 327.913492 -9.5504)
		(stroke
			(width 0.508)
			(type default)
		)
		(layer "In6.Cu")
	)
	(gr_line
		(start 327.938892 -11.0744)
		(end 327.938892 -9.5504)
		(stroke
			(width 0.508)
			(type default)
		)
		(layer "In6.Cu")
	)
	(gr_line
		(start 327.989692 -11.0744)
		(end 327.989692 -9.5504)
		(stroke
			(width 0.508)
			(type default)
		)
		(layer "In6.Cu")
	)
	(gr_line
		(start 327.989692 -11.049)
		(end 327.989692 -9.525)
		(stroke
			(width 0.508)
			(type default)
		)
		(layer "In6.Cu")
	)
	(gr_line
		(start 328.015092 -11.0744)
		(end 328.015092 -9.5504)
		(stroke
			(width 0.508)
			(type default)
		)
		(layer "In6.Cu")
	)
	(gr_line
		(start 328.040492 -11.0744)
		(end 328.040492 -9.5504)
		(stroke
			(width 0.508)
			(type default)
		)
		(layer "In6.Cu")
	)
	(gr_line
		(start 328.065892 -11.0744)
		(end 328.065892 -9.5504)
		(stroke
			(width 0.508)
			(type default)
		)
		(layer "In6.Cu")
	)
	(gr_line
		(start 328.116692 -11.0744)
		(end 328.116692 -9.5504)
		(stroke
			(width 0.508)
			(type default)
		)
		(layer "In6.Cu")
	)
	(gr_line
		(start 328.142092 -11.0744)
		(end 328.142092 -9.5504)
		(stroke
			(width 0.508)
			(type default)
		)
		(layer "In6.Cu")
	)
	(gr_line
		(start 328.142092 -11.049)
		(end 328.142092 -9.525)
		(stroke
			(width 0.508)
			(type default)
		)
		(layer "In6.Cu")
	)
	(gr_line
		(start 328.167492 -11.0744)
		(end 328.167492 -9.5504)
		(stroke
			(width 0.508)
			(type default)
		)
		(layer "In6.Cu")
	)
	(gr_line
		(start 328.192892 -11.0744)
		(end 328.192892 -9.5504)
		(stroke
			(width 0.508)
			(type default)
		)
		(layer "In6.Cu")
	)
	(gr_line
		(start 328.218292 -11.0744)
		(end 328.218292 -9.5504)
		(stroke
			(width 0.508)
			(type default)
		)
		(layer "In6.Cu")
	)
	(gr_line
		(start 328.218292 -11.049)
		(end 328.218292 -9.525)
		(stroke
			(width 0.508)
			(type default)
		)
		(layer "In6.Cu")
	)
	(gr_line
		(start 328.243692 -11.0744)
		(end 328.243692 -9.5504)
		(stroke
			(width 0.508)
			(type default)
		)
		(layer "In6.Cu")
	)
	(gr_line
		(start 328.269092 -11.0744)
		(end 328.269092 -9.5504)
		(stroke
			(width 0.508)
			(type default)
		)
		(layer "In6.Cu")
	)
	(gr_line
		(start 328.269092 -11.049)
		(end 328.269092 -9.525)
		(stroke
			(width 0.508)
			(type default)
		)
		(layer "In6.Cu")
	)
	(gr_line
		(start 328.294492 -11.0744)
		(end 328.294492 -9.5504)
		(stroke
			(width 0.508)
			(type default)
		)
		(layer "In6.Cu")
	)
	(gr_line
		(start 328.294492 -11.049)
		(end 328.294492 -9.525)
		(stroke
			(width 0.508)
			(type default)
		)
		(layer "In6.Cu")
	)
	(gr_line
		(start 328.319892 -11.049)
		(end 328.319892 -9.525)
		(stroke
			(width 0.508)
			(type default)
		)
		(layer "In6.Cu")
	)
	(gr_line
		(start 328.345292 -11.0744)
		(end 328.345292 -9.5504)
		(stroke
			(width 0.508)
			(type default)
		)
		(layer "In6.Cu")
	)
	(gr_line
		(start 328.36739 -11.3792)
		(end 327.37679 -11.3792)
		(stroke
			(width 0.254)
			(type default)
		)
		(layer "In6.Cu")
	)
	(gr_line
		(start 328.370692 -11.049)
		(end 328.370692 -9.525)
		(stroke
			(width 0.508)
			(type default)
		)
		(layer "In6.Cu")
	)
	(gr_line
		(start 328.396092 -11.049)
		(end 328.396092 -9.525)
		(stroke
			(width 0.508)
			(type default)
		)
		(layer "In6.Cu")
	)
	(gr_line
		(start 328.421492 -11.0744)
		(end 328.421492 -9.5504)
		(stroke
			(width 0.508)
			(type default)
		)
		(layer "In6.Cu")
	)
	(gr_line
		(start 328.446892 -11.0744)
		(end 328.446892 -9.5504)
		(stroke
			(width 0.508)
			(type default)
		)
		(layer "In6.Cu")
	)
	(gr_line
		(start 328.446892 -11.049)
		(end 328.446892 -9.525)
		(stroke
			(width 0.508)
			(type default)
		)
		(layer "In6.Cu")
	)
	(gr_line
		(start 328.497692 -11.0744)
		(end 328.497692 -9.5504)
		(stroke
			(width 0.508)
			(type default)
		)
		(layer "In6.Cu")
	)
	(gr_line
		(start 328.497692 -11.049)
		(end 328.497692 -9.525)
		(stroke
			(width 0.508)
			(type default)
		)
		(layer "In6.Cu")
	)
	(gr_line
		(start 328.548492 -11.0744)
		(end 328.548492 -9.5504)
		(stroke
			(width 0.508)
			(type default)
		)
		(layer "In6.Cu")
	)
	(gr_line
		(start 328.548492 -11.049)
		(end 328.548492 -9.525)
		(stroke
			(width 0.508)
			(type default)
		)
		(layer "In6.Cu")
	)
	(gr_line
		(start 328.57059 -11.0998)
		(end 328.57059 -9.5504)
		(stroke
			(width 0.762)
			(type default)
		)
		(layer "In6.Cu")
	)
	(gr_line
		(start 328.573892 -11.0744)
		(end 328.573892 -9.5504)
		(stroke
			(width 0.508)
			(type default)
		)
		(layer "In6.Cu")
	)
	(gr_line
		(start 328.599292 -11.0744)
		(end 328.599292 -9.5504)
		(stroke
			(width 0.508)
			(type default)
		)
		(layer "In6.Cu")
	)
	(gr_line
		(start 328.650092 -11.2268)
		(end 328.675492 -11.2268)
		(stroke
			(width 0.2032)
			(type default)
		)
		(layer "In6.Cu")
	)
	(gr_line
		(start 328.675492 -11.2268)
		(end 328.675492 -9.4742)
		(stroke
			(width 0.2032)
			(type default)
		)
		(layer "In6.Cu")
	)
	(gr_line
		(start 328.675492 -9.4742)
		(end 327.634092 -9.4742)
		(stroke
			(width 0.2032)
			(type default)
		)
		(layer "In6.Cu")
	)
	(gr_line
		(start 328.69759 -11.1252)
		(end 328.69759 -9.5758)
		(stroke
			(width 0.762)
			(type default)
		)
		(layer "In6.Cu")
	)
	(gr_line
		(start 328.69759 -11.0998)
		(end 328.69759 -9.6012)
		(stroke
			(width 0.762)
			(type default)
		)
		(layer "In6.Cu")
	)
	(gr_line
		(start 328.69759 -10.9982)
		(end 328.69759 -9.4488)
		(stroke
			(width 0.762)
			(type default)
		)
		(layer "In6.Cu")
	)
	(gr_line
		(start 328.726292 -11.176)
		(end 328.726292 -9.4234)
		(stroke
			(width 0.2032)
			(type default)
		)
		(layer "In6.Cu")
	)
	(gr_line
		(start 328.726292 -9.4234)
		(end 327.583292 -9.4234)
		(stroke
			(width 0.2032)
			(type default)
		)
		(layer "In6.Cu")
	)
	(gr_line
		(start 328.751692 -11.2268)
		(end 328.751692 -9.3726)
		(stroke
			(width 0.2032)
			(type default)
		)
		(layer "In6.Cu")
	)
	(gr_line
		(start 328.751692 -9.3726)
		(end 327.557892 -9.3726)
		(stroke
			(width 0.2032)
			(type default)
		)
		(layer "In6.Cu")
	)
	(gr_line
		(start 328.802492 -11.303)
		(end 328.802492 -9.2964)
		(stroke
			(width 0.1016)
			(type default)
		)
		(layer "In6.Cu")
	)
	(gr_line
		(start 328.802492 -9.2964)
		(end 327.507092 -9.2964)
		(stroke
			(width 0.1016)
			(type default)
		)
		(layer "In6.Cu")
	)
	(gr_line
		(start 328.90079 -11.2268)
		(end 328.650092 -11.2268)
		(stroke
			(width 0.254)
			(type default)
		)
		(layer "In6.Cu")
	)
	(gr_line
		(start 328.90079 -9.3726)
		(end 328.90079 -11.2268)
		(stroke
			(width 0.254)
			(type default)
		)
		(layer "In6.Cu")
	)
	(gr_line
		(start 328.92619 -11.3538)
		(end 327.45299 -11.3538)
		(stroke
			(width 0.254)
			(type default)
		)
		(layer "In6.Cu")
	)
	(gr_line
		(start 328.92619 -9.2456)
		(end 328.92619 -11.3538)
		(stroke
			(width 0.254)
			(type default)
		)
		(layer "In6.Cu")
	)
	(gr_line
		(start 328.95159 -11.3792)
		(end 327.40219 -11.3792)
		(stroke
			(width 0.254)
			(type default)
		)
		(layer "In6.Cu")
	)
	(gr_line
		(start 328.95159 -9.1948)
		(end 328.95159 -11.3792)
		(stroke
			(width 0.254)
			(type default)
		)
		(layer "In6.Cu")
	)
	(gr_line
		(start 333.069946 -49.800002)
		(end 318.069976 -49.800002)
		(stroke
			(width 1.016)
			(type default)
		)
		(layer "In6.Cu")
	)
	(gr_line
		(start 334.069944 -51.319938)
		(end 334.069944 -50.8)
		(stroke
			(width 1.016)
			(type default)
		)
		(layer "In6.Cu")
	)
	(gr_arc
		(start 334.069944 -51.319938)
		(mid 334.362853 -52.027004)
		(end 335.069942 -52.319936)
		(stroke
			(width 1.016)
			(type default)
		)
		(layer "In6.Cu")
	)
	(gr_arc
		(start 334.069944 -50.8)
		(mid 333.777051 -50.092895)
		(end 333.069946 -49.800002)
		(stroke
			(width 1.016)
			(type default)
		)
		(layer "In6.Cu")
	)
	(gr_line
		(start 334.761586 -9.1948)
		(end 336.183986 -9.1948)
		(stroke
			(width 1.016)
			(type default)
		)
		(layer "In6.Cu")
	)
	(gr_line
		(start 338.856066 -13.843)
		(end 339.694266 -13.843)
		(stroke
			(width 0.1016)
			(type default)
		)
		(layer "In6.Cu")
	)
	(gr_line
		(start 338.856066 -11.1252)
		(end 338.856066 -13.843)
		(stroke
			(width 0.1016)
			(type default)
		)
		(layer "In6.Cu")
	)
	(gr_line
		(start 338.856066 -9.64311)
		(end 339.694266 -9.64311)
		(stroke
			(width 0.1016)
			(type default)
		)
		(layer "In6.Cu")
	)
	(gr_line
		(start 338.856066 -6.92531)
		(end 338.856066 -9.64311)
		(stroke
			(width 0.1016)
			(type default)
		)
		(layer "In6.Cu")
	)
	(gr_line
		(start 338.881466 -13.8176)
		(end 338.881466 -11.1506)
		(stroke
			(width 0.127)
			(type default)
		)
		(layer "In6.Cu")
	)
	(gr_line
		(start 338.881466 -11.1506)
		(end 340.176866 -11.1506)
		(stroke
			(width 0.127)
			(type default)
		)
		(layer "In6.Cu")
	)
	(gr_line
		(start 338.881466 -9.61771)
		(end 338.881466 -6.95071)
		(stroke
			(width 0.127)
			(type default)
		)
		(layer "In6.Cu")
	)
	(gr_line
		(start 338.881466 -6.95071)
		(end 340.176866 -6.95071)
		(stroke
			(width 0.127)
			(type default)
		)
		(layer "In6.Cu")
	)
	(gr_line
		(start 338.906866 -13.8176)
		(end 338.906866 -11.176)
		(stroke
			(width 0.127)
			(type default)
		)
		(layer "In6.Cu")
	)
	(gr_line
		(start 338.906866 -13.7922)
		(end 338.906866 -11.176)
		(stroke
			(width 0.1778)
			(type default)
		)
		(layer "In6.Cu")
	)
	(gr_line
		(start 338.906866 -11.176)
		(end 340.151466 -11.176)
		(stroke
			(width 0.127)
			(type default)
		)
		(layer "In6.Cu")
	)
	(gr_line
		(start 338.906866 -11.176)
		(end 340.151466 -11.176)
		(stroke
			(width 0.1778)
			(type default)
		)
		(layer "In6.Cu")
	)
	(gr_line
		(start 338.906866 -9.61771)
		(end 338.906866 -6.97611)
		(stroke
			(width 0.127)
			(type default)
		)
		(layer "In6.Cu")
	)
	(gr_line
		(start 338.906866 -9.59231)
		(end 338.906866 -6.97611)
		(stroke
			(width 0.1778)
			(type default)
		)
		(layer "In6.Cu")
	)
	(gr_line
		(start 338.906866 -6.97611)
		(end 340.151466 -6.97611)
		(stroke
			(width 0.127)
			(type default)
		)
		(layer "In6.Cu")
	)
	(gr_line
		(start 338.906866 -6.97611)
		(end 340.151466 -6.97611)
		(stroke
			(width 0.1778)
			(type default)
		)
		(layer "In6.Cu")
	)
	(gr_line
		(start 338.932266 -13.7922)
		(end 338.932266 -11.2014)
		(stroke
			(width 0.1778)
			(type default)
		)
		(layer "In6.Cu")
	)
	(gr_line
		(start 338.932266 -11.2014)
		(end 340.126066 -11.2014)
		(stroke
			(width 0.1778)
			(type default)
		)
		(layer "In6.Cu")
	)
	(gr_line
		(start 338.932266 -9.59231)
		(end 338.932266 -7.00151)
		(stroke
			(width 0.1778)
			(type default)
		)
		(layer "In6.Cu")
	)
	(gr_line
		(start 338.932266 -7.00151)
		(end 340.126066 -7.00151)
		(stroke
			(width 0.1778)
			(type default)
		)
		(layer "In6.Cu")
	)
	(gr_line
		(start 338.957666 -13.7668)
		(end 338.957666 -11.2268)
		(stroke
			(width 0.254)
			(type default)
		)
		(layer "In6.Cu")
	)
	(gr_line
		(start 338.957666 -11.2268)
		(end 340.126066 -11.2268)
		(stroke
			(width 0.254)
			(type default)
		)
		(layer "In6.Cu")
	)
	(gr_line
		(start 338.957666 -9.56691)
		(end 338.957666 -7.02691)
		(stroke
			(width 0.254)
			(type default)
		)
		(layer "In6.Cu")
	)
	(gr_line
		(start 338.957666 -7.02691)
		(end 340.126066 -7.02691)
		(stroke
			(width 0.254)
			(type default)
		)
		(layer "In6.Cu")
	)
	(gr_line
		(start 338.983066 -13.7668)
		(end 338.983066 -11.2522)
		(stroke
			(width 0.254)
			(type default)
		)
		(layer "In6.Cu")
	)
	(gr_line
		(start 338.983066 -11.2522)
		(end 340.100666 -11.2522)
		(stroke
			(width 0.254)
			(type default)
		)
		(layer "In6.Cu")
	)
	(gr_line
		(start 338.983066 -9.56691)
		(end 338.983066 -7.05231)
		(stroke
			(width 0.254)
			(type default)
		)
		(layer "In6.Cu")
	)
	(gr_line
		(start 338.983066 -7.05231)
		(end 340.100666 -7.05231)
		(stroke
			(width 0.254)
			(type default)
		)
		(layer "In6.Cu")
	)
	(gr_line
		(start 339.008466 -13.716)
		(end 339.008466 -11.2776)
		(stroke
			(width 0.3556)
			(type default)
		)
		(layer "In6.Cu")
	)
	(gr_line
		(start 339.008466 -11.2776)
		(end 340.049866 -11.2776)
		(stroke
			(width 0.3556)
			(type default)
		)
		(layer "In6.Cu")
	)
	(gr_line
		(start 339.008466 -9.51611)
		(end 339.008466 -7.07771)
		(stroke
			(width 0.3556)
			(type default)
		)
		(layer "In6.Cu")
	)
	(gr_line
		(start 339.008466 -7.07771)
		(end 340.049866 -7.07771)
		(stroke
			(width 0.3556)
			(type default)
		)
		(layer "In6.Cu")
	)
	(gr_line
		(start 339.059266 -13.6906)
		(end 339.059266 -11.3284)
		(stroke
			(width 0.381)
			(type default)
		)
		(layer "In6.Cu")
	)
	(gr_line
		(start 339.059266 -11.3284)
		(end 339.999066 -11.3284)
		(stroke
			(width 0.381)
			(type default)
		)
		(layer "In6.Cu")
	)
	(gr_line
		(start 339.059266 -9.49071)
		(end 339.059266 -7.12851)
		(stroke
			(width 0.381)
			(type default)
		)
		(layer "In6.Cu")
	)
	(gr_line
		(start 339.059266 -7.12851)
		(end 339.999066 -7.12851)
		(stroke
			(width 0.381)
			(type default)
		)
		(layer "In6.Cu")
	)
	(gr_line
		(start 339.135466 -13.6398)
		(end 339.135466 -11.3792)
		(stroke
			(width 0.381)
			(type default)
		)
		(layer "In6.Cu")
	)
	(gr_line
		(start 339.135466 -11.3792)
		(end 339.948266 -11.3792)
		(stroke
			(width 0.381)
			(type default)
		)
		(layer "In6.Cu")
	)
	(gr_line
		(start 339.135466 -9.43991)
		(end 339.135466 -7.17931)
		(stroke
			(width 0.381)
			(type default)
		)
		(layer "In6.Cu")
	)
	(gr_line
		(start 339.135466 -7.17931)
		(end 339.948266 -7.17931)
		(stroke
			(width 0.381)
			(type default)
		)
		(layer "In6.Cu")
	)
	(gr_line
		(start 339.160866 -13.5636)
		(end 339.160866 -11.3792)
		(stroke
			(width 0.508)
			(type default)
		)
		(layer "In6.Cu")
	)
	(gr_line
		(start 339.160866 -11.3792)
		(end 339.922866 -11.3792)
		(stroke
			(width 0.508)
			(type default)
		)
		(layer "In6.Cu")
	)
	(gr_line
		(start 339.160866 -9.36371)
		(end 339.160866 -7.17931)
		(stroke
			(width 0.508)
			(type default)
		)
		(layer "In6.Cu")
	)
	(gr_line
		(start 339.160866 -7.17931)
		(end 339.922866 -7.17931)
		(stroke
			(width 0.508)
			(type default)
		)
		(layer "In6.Cu")
	)
	(gr_line
		(start 339.186266 -13.4112)
		(end 339.770466 -13.4112)
		(stroke
			(width 0.762)
			(type default)
		)
		(layer "In6.Cu")
	)
	(gr_line
		(start 339.186266 -11.5824)
		(end 339.770466 -11.5824)
		(stroke
			(width 0.762)
			(type default)
		)
		(layer "In6.Cu")
	)
	(gr_line
		(start 339.186266 -9.21131)
		(end 339.770466 -9.21131)
		(stroke
			(width 0.762)
			(type default)
		)
		(layer "In6.Cu")
	)
	(gr_line
		(start 339.186266 -7.38251)
		(end 339.770466 -7.38251)
		(stroke
			(width 0.762)
			(type default)
		)
		(layer "In6.Cu")
	)
	(gr_line
		(start 339.211666 -13.5636)
		(end 339.211666 -11.43)
		(stroke
			(width 0.635)
			(type default)
		)
		(layer "In6.Cu")
	)
	(gr_line
		(start 339.211666 -13.5128)
		(end 339.211666 -11.4808)
		(stroke
			(width 0.762)
			(type default)
		)
		(layer "In6.Cu")
	)
	(gr_line
		(start 339.211666 -11.43)
		(end 339.897466 -11.43)
		(stroke
			(width 0.635)
			(type default)
		)
		(layer "In6.Cu")
	)
	(gr_line
		(start 339.211666 -9.36371)
		(end 339.211666 -7.23011)
		(stroke
			(width 0.635)
			(type default)
		)
		(layer "In6.Cu")
	)
	(gr_line
		(start 339.211666 -9.31291)
		(end 339.211666 -7.28091)
		(stroke
			(width 0.762)
			(type default)
		)
		(layer "In6.Cu")
	)
	(gr_line
		(start 339.211666 -7.23011)
		(end 339.897466 -7.23011)
		(stroke
			(width 0.635)
			(type default)
		)
		(layer "In6.Cu")
	)
	(gr_line
		(start 339.237066 -13.5128)
		(end 339.237066 -11.4808)
		(stroke
			(width 0.762)
			(type default)
		)
		(layer "In6.Cu")
	)
	(gr_line
		(start 339.237066 -11.4808)
		(end 339.821266 -11.4808)
		(stroke
			(width 0.762)
			(type default)
		)
		(layer "In6.Cu")
	)
	(gr_line
		(start 339.237066 -9.31291)
		(end 339.237066 -7.28091)
		(stroke
			(width 0.762)
			(type default)
		)
		(layer "In6.Cu")
	)
	(gr_line
		(start 339.237066 -7.28091)
		(end 339.821266 -7.28091)
		(stroke
			(width 0.762)
			(type default)
		)
		(layer "In6.Cu")
	)
	(gr_line
		(start 339.262466 -13.5128)
		(end 339.262466 -11.4808)
		(stroke
			(width 0.762)
			(type default)
		)
		(layer "In6.Cu")
	)
	(gr_line
		(start 339.262466 -13.5128)
		(end 339.846666 -13.5128)
		(stroke
			(width 0.762)
			(type default)
		)
		(layer "In6.Cu")
	)
	(gr_line
		(start 339.262466 -13.4874)
		(end 339.262466 -11.4554)
		(stroke
			(width 0.762)
			(type default)
		)
		(layer "In6.Cu")
	)
	(gr_line
		(start 339.262466 -9.31291)
		(end 339.262466 -7.28091)
		(stroke
			(width 0.762)
			(type default)
		)
		(layer "In6.Cu")
	)
	(gr_line
		(start 339.262466 -9.31291)
		(end 339.846666 -9.31291)
		(stroke
			(width 0.762)
			(type default)
		)
		(layer "In6.Cu")
	)
	(gr_line
		(start 339.262466 -9.28751)
		(end 339.262466 -7.25551)
		(stroke
			(width 0.762)
			(type default)
		)
		(layer "In6.Cu")
	)
	(gr_line
		(start 339.287866 -13.5128)
		(end 339.287866 -11.4808)
		(stroke
			(width 0.762)
			(type default)
		)
		(layer "In6.Cu")
	)
	(gr_line
		(start 339.287866 -9.31291)
		(end 339.287866 -7.28091)
		(stroke
			(width 0.762)
			(type default)
		)
		(layer "In6.Cu")
	)
	(gr_line
		(start 339.313266 -13.5128)
		(end 339.313266 -11.4808)
		(stroke
			(width 0.762)
			(type default)
		)
		(layer "In6.Cu")
	)
	(gr_line
		(start 339.313266 -9.31291)
		(end 339.313266 -7.28091)
		(stroke
			(width 0.762)
			(type default)
		)
		(layer "In6.Cu")
	)
	(gr_line
		(start 339.338666 -13.5128)
		(end 339.338666 -11.4808)
		(stroke
			(width 0.762)
			(type default)
		)
		(layer "In6.Cu")
	)
	(gr_line
		(start 339.338666 -9.31291)
		(end 339.338666 -7.28091)
		(stroke
			(width 0.762)
			(type default)
		)
		(layer "In6.Cu")
	)
	(gr_line
		(start 339.389466 -13.5128)
		(end 339.389466 -11.4808)
		(stroke
			(width 0.762)
			(type default)
		)
		(layer "In6.Cu")
	)
	(gr_line
		(start 339.389466 -9.31291)
		(end 339.389466 -7.28091)
		(stroke
			(width 0.762)
			(type default)
		)
		(layer "In6.Cu")
	)
	(gr_line
		(start 339.414866 -13.5128)
		(end 339.414866 -11.4808)
		(stroke
			(width 0.762)
			(type default)
		)
		(layer "In6.Cu")
	)
	(gr_line
		(start 339.414866 -9.31291)
		(end 339.414866 -7.28091)
		(stroke
			(width 0.762)
			(type default)
		)
		(layer "In6.Cu")
	)
	(gr_line
		(start 339.440266 -13.5128)
		(end 339.440266 -11.7094)
		(stroke
			(width 0.635)
			(type default)
		)
		(layer "In6.Cu")
	)
	(gr_line
		(start 339.440266 -11.7094)
		(end 339.541866 -11.7094)
		(stroke
			(width 0.635)
			(type default)
		)
		(layer "In6.Cu")
	)
	(gr_line
		(start 339.440266 -9.31291)
		(end 339.440266 -7.50951)
		(stroke
			(width 0.635)
			(type default)
		)
		(layer "In6.Cu")
	)
	(gr_line
		(start 339.440266 -7.50951)
		(end 339.541866 -7.50951)
		(stroke
			(width 0.635)
			(type default)
		)
		(layer "In6.Cu")
	)
	(gr_line
		(start 339.465666 -13.5128)
		(end 339.465666 -11.4808)
		(stroke
			(width 0.762)
			(type default)
		)
		(layer "In6.Cu")
	)
	(gr_line
		(start 339.465666 -13.4874)
		(end 339.465666 -11.4554)
		(stroke
			(width 0.762)
			(type default)
		)
		(layer "In6.Cu")
	)
	(gr_line
		(start 339.465666 -13.4366)
		(end 339.465666 -11.6586)
		(stroke
			(width 0.635)
			(type default)
		)
		(layer "In6.Cu")
	)
	(gr_line
		(start 339.465666 -9.31291)
		(end 339.465666 -7.28091)
		(stroke
			(width 0.762)
			(type default)
		)
		(layer "In6.Cu")
	)
	(gr_line
		(start 339.465666 -9.28751)
		(end 339.465666 -7.25551)
		(stroke
			(width 0.762)
			(type default)
		)
		(layer "In6.Cu")
	)
	(gr_line
		(start 339.465666 -9.23671)
		(end 339.465666 -7.45871)
		(stroke
			(width 0.635)
			(type default)
		)
		(layer "In6.Cu")
	)
	(gr_line
		(start 339.516466 -13.5128)
		(end 339.516466 -11.4808)
		(stroke
			(width 0.762)
			(type default)
		)
		(layer "In6.Cu")
	)
	(gr_line
		(start 339.516466 -9.31291)
		(end 339.516466 -7.28091)
		(stroke
			(width 0.762)
			(type default)
		)
		(layer "In6.Cu")
	)
	(gr_line
		(start 339.541866 -13.5128)
		(end 339.541866 -11.4808)
		(stroke
			(width 0.762)
			(type default)
		)
		(layer "In6.Cu")
	)
	(gr_line
		(start 339.541866 -13.4874)
		(end 339.541866 -11.4554)
		(stroke
			(width 0.762)
			(type default)
		)
		(layer "In6.Cu")
	)
	(gr_line
		(start 339.541866 -13.4366)
		(end 339.465666 -13.4366)
		(stroke
			(width 0.635)
			(type default)
		)
		(layer "In6.Cu")
	)
	(gr_line
		(start 339.541866 -11.7094)
		(end 339.541866 -13.4366)
		(stroke
			(width 0.635)
			(type default)
		)
		(layer "In6.Cu")
	)
	(gr_line
		(start 339.541866 -9.31291)
		(end 339.541866 -7.28091)
		(stroke
			(width 0.762)
			(type default)
		)
		(layer "In6.Cu")
	)
	(gr_line
		(start 339.541866 -9.28751)
		(end 339.541866 -7.25551)
		(stroke
			(width 0.762)
			(type default)
		)
		(layer "In6.Cu")
	)
	(gr_line
		(start 339.541866 -9.23671)
		(end 339.465666 -9.23671)
		(stroke
			(width 0.635)
			(type default)
		)
		(layer "In6.Cu")
	)
	(gr_line
		(start 339.541866 -7.50951)
		(end 339.541866 -9.23671)
		(stroke
			(width 0.635)
			(type default)
		)
		(layer "In6.Cu")
	)
	(gr_line
		(start 339.592666 -13.4874)
		(end 339.592666 -11.4554)
		(stroke
			(width 0.762)
			(type default)
		)
		(layer "In6.Cu")
	)
	(gr_line
		(start 339.592666 -9.28751)
		(end 339.592666 -7.25551)
		(stroke
			(width 0.762)
			(type default)
		)
		(layer "In6.Cu")
	)
	(gr_line
		(start 339.618066 -13.4874)
		(end 339.618066 -11.4554)
		(stroke
			(width 0.762)
			(type default)
		)
		(layer "In6.Cu")
	)
	(gr_line
		(start 339.618066 -9.28751)
		(end 339.618066 -7.25551)
		(stroke
			(width 0.762)
			(type default)
		)
		(layer "In6.Cu")
	)
	(gr_line
		(start 339.668866 -13.5128)
		(end 339.668866 -11.4808)
		(stroke
			(width 0.762)
			(type default)
		)
		(layer "In6.Cu")
	)
	(gr_line
		(start 339.668866 -9.31291)
		(end 339.668866 -7.28091)
		(stroke
			(width 0.762)
			(type default)
		)
		(layer "In6.Cu")
	)
	(gr_line
		(start 339.694266 -13.843)
		(end 340.202266 -13.843)
		(stroke
			(width 0.1016)
			(type default)
		)
		(layer "In6.Cu")
	)
	(gr_line
		(start 339.694266 -13.4874)
		(end 339.694266 -11.4554)
		(stroke
			(width 0.762)
			(type default)
		)
		(layer "In6.Cu")
	)
	(gr_line
		(start 339.694266 -9.64311)
		(end 340.202266 -9.64311)
		(stroke
			(width 0.1016)
			(type default)
		)
		(layer "In6.Cu")
	)
	(gr_line
		(start 339.694266 -9.28751)
		(end 339.694266 -7.25551)
		(stroke
			(width 0.762)
			(type default)
		)
		(layer "In6.Cu")
	)
	(gr_line
		(start 339.745066 -13.5128)
		(end 339.745066 -11.4808)
		(stroke
			(width 0.762)
			(type default)
		)
		(layer "In6.Cu")
	)
	(gr_line
		(start 339.745066 -13.4874)
		(end 339.745066 -11.4554)
		(stroke
			(width 0.762)
			(type default)
		)
		(layer "In6.Cu")
	)
	(gr_line
		(start 339.745066 -9.31291)
		(end 339.745066 -7.28091)
		(stroke
			(width 0.762)
			(type default)
		)
		(layer "In6.Cu")
	)
	(gr_line
		(start 339.745066 -9.28751)
		(end 339.745066 -7.25551)
		(stroke
			(width 0.762)
			(type default)
		)
		(layer "In6.Cu")
	)
	(gr_line
		(start 339.770466 -13.4874)
		(end 339.770466 -11.4554)
		(stroke
			(width 0.762)
			(type default)
		)
		(layer "In6.Cu")
	)
	(gr_line
		(start 339.770466 -9.28751)
		(end 339.770466 -7.25551)
		(stroke
			(width 0.762)
			(type default)
		)
		(layer "In6.Cu")
	)
	(gr_line
		(start 339.795866 -13.5636)
		(end 339.160866 -13.5636)
		(stroke
			(width 0.508)
			(type default)
		)
		(layer "In6.Cu")
	)
	(gr_line
		(start 339.795866 -13.5636)
		(end 339.211666 -13.5636)
		(stroke
			(width 0.635)
			(type default)
		)
		(layer "In6.Cu")
	)
	(gr_line
		(start 339.795866 -9.36371)
		(end 339.160866 -9.36371)
		(stroke
			(width 0.508)
			(type default)
		)
		(layer "In6.Cu")
	)
	(gr_line
		(start 339.795866 -9.36371)
		(end 339.211666 -9.36371)
		(stroke
			(width 0.635)
			(type default)
		)
		(layer "In6.Cu")
	)
	(gr_line
		(start 339.821266 -13.4874)
		(end 339.821266 -11.4554)
		(stroke
			(width 0.762)
			(type default)
		)
		(layer "In6.Cu")
	)
	(gr_line
		(start 339.821266 -9.28751)
		(end 339.821266 -7.25551)
		(stroke
			(width 0.762)
			(type default)
		)
		(layer "In6.Cu")
	)
	(gr_line
		(start 339.846666 -13.716)
		(end 339.008466 -13.716)
		(stroke
			(width 0.3556)
			(type default)
		)
		(layer "In6.Cu")
	)
	(gr_line
		(start 339.846666 -13.6906)
		(end 339.059266 -13.6906)
		(stroke
			(width 0.381)
			(type default)
		)
		(layer "In6.Cu")
	)
	(gr_line
		(start 339.846666 -9.51611)
		(end 339.008466 -9.51611)
		(stroke
			(width 0.3556)
			(type default)
		)
		(layer "In6.Cu")
	)
	(gr_line
		(start 339.846666 -9.49071)
		(end 339.059266 -9.49071)
		(stroke
			(width 0.381)
			(type default)
		)
		(layer "In6.Cu")
	)
	(gr_line
		(start 339.872066 -13.5128)
		(end 339.872066 -11.4808)
		(stroke
			(width 0.762)
			(type default)
		)
		(layer "In6.Cu")
	)
	(gr_line
		(start 339.872066 -9.31291)
		(end 339.872066 -7.28091)
		(stroke
			(width 0.762)
			(type default)
		)
		(layer "In6.Cu")
	)
	(gr_line
		(start 339.897466 -13.7668)
		(end 338.957666 -13.7668)
		(stroke
			(width 0.254)
			(type default)
		)
		(layer "In6.Cu")
	)
	(gr_line
		(start 339.897466 -13.5128)
		(end 339.440266 -13.5128)
		(stroke
			(width 0.635)
			(type default)
		)
		(layer "In6.Cu")
	)
	(gr_line
		(start 339.897466 -11.43)
		(end 339.897466 -13.5128)
		(stroke
			(width 0.635)
			(type default)
		)
		(layer "In6.Cu")
	)
	(gr_line
		(start 339.897466 -9.56691)
		(end 338.957666 -9.56691)
		(stroke
			(width 0.254)
			(type default)
		)
		(layer "In6.Cu")
	)
	(gr_line
		(start 339.897466 -9.31291)
		(end 339.440266 -9.31291)
		(stroke
			(width 0.635)
			(type default)
		)
		(layer "In6.Cu")
	)
	(gr_line
		(start 339.897466 -7.23011)
		(end 339.897466 -9.31291)
		(stroke
			(width 0.635)
			(type default)
		)
		(layer "In6.Cu")
	)
	(gr_line
		(start 339.922866 -13.7922)
		(end 338.906866 -13.7922)
		(stroke
			(width 0.1778)
			(type default)
		)
		(layer "In6.Cu")
	)
	(gr_line
		(start 339.922866 -13.5636)
		(end 339.795866 -13.5636)
		(stroke
			(width 0.508)
			(type default)
		)
		(layer "In6.Cu")
	)
	(gr_line
		(start 339.922866 -11.3792)
		(end 339.922866 -13.5636)
		(stroke
			(width 0.508)
			(type default)
		)
		(layer "In6.Cu")
	)
	(gr_line
		(start 339.922866 -9.59231)
		(end 338.906866 -9.59231)
		(stroke
			(width 0.1778)
			(type default)
		)
		(layer "In6.Cu")
	)
	(gr_line
		(start 339.922866 -9.36371)
		(end 339.795866 -9.36371)
		(stroke
			(width 0.508)
			(type default)
		)
		(layer "In6.Cu")
	)
	(gr_line
		(start 339.922866 -7.17931)
		(end 339.922866 -9.36371)
		(stroke
			(width 0.508)
			(type default)
		)
		(layer "In6.Cu")
	)
	(gr_line
		(start 339.948266 -13.5636)
		(end 339.795866 -13.5636)
		(stroke
			(width 0.381)
			(type default)
		)
		(layer "In6.Cu")
	)
	(gr_line
		(start 339.948266 -11.3792)
		(end 339.948266 -13.5636)
		(stroke
			(width 0.381)
			(type default)
		)
		(layer "In6.Cu")
	)
	(gr_line
		(start 339.948266 -9.36371)
		(end 339.795866 -9.36371)
		(stroke
			(width 0.381)
			(type default)
		)
		(layer "In6.Cu")
	)
	(gr_line
		(start 339.948266 -7.17931)
		(end 339.948266 -9.36371)
		(stroke
			(width 0.381)
			(type default)
		)
		(layer "In6.Cu")
	)
	(gr_line
		(start 339.999066 -13.6398)
		(end 339.135466 -13.6398)
		(stroke
			(width 0.381)
			(type default)
		)
		(layer "In6.Cu")
	)
	(gr_line
		(start 339.999066 -11.3284)
		(end 339.999066 -13.6398)
		(stroke
			(width 0.381)
			(type default)
		)
		(layer "In6.Cu")
	)
	(gr_line
		(start 339.999066 -9.43991)
		(end 339.135466 -9.43991)
		(stroke
			(width 0.381)
			(type default)
		)
		(layer "In6.Cu")
	)
	(gr_line
		(start 339.999066 -7.12851)
		(end 339.999066 -9.43991)
		(stroke
			(width 0.381)
			(type default)
		)
		(layer "In6.Cu")
	)
	(gr_line
		(start 340.049866 -13.6906)
		(end 339.846666 -13.6906)
		(stroke
			(width 0.3556)
			(type default)
		)
		(layer "In6.Cu")
	)
	(gr_line
		(start 340.049866 -11.2776)
		(end 340.049866 -13.6906)
		(stroke
			(width 0.3556)
			(type default)
		)
		(layer "In6.Cu")
	)
	(gr_line
		(start 340.049866 -9.49071)
		(end 339.846666 -9.49071)
		(stroke
			(width 0.3556)
			(type default)
		)
		(layer "In6.Cu")
	)
	(gr_line
		(start 340.049866 -7.07771)
		(end 340.049866 -9.49071)
		(stroke
			(width 0.3556)
			(type default)
		)
		(layer "In6.Cu")
	)
	(gr_line
		(start 340.075266 -13.8176)
		(end 338.881466 -13.8176)
		(stroke
			(width 0.127)
			(type default)
		)
		(layer "In6.Cu")
	)
	(gr_line
		(start 340.075266 -9.61771)
		(end 338.881466 -9.61771)
		(stroke
			(width 0.127)
			(type default)
		)
		(layer "In6.Cu")
	)
	(gr_line
		(start 340.100666 -13.716)
		(end 339.846666 -13.716)
		(stroke
			(width 0.254)
			(type default)
		)
		(layer "In6.Cu")
	)
	(gr_line
		(start 340.100666 -11.2522)
		(end 340.100666 -13.716)
		(stroke
			(width 0.254)
			(type default)
		)
		(layer "In6.Cu")
	)
	(gr_line
		(start 340.100666 -9.51611)
		(end 339.846666 -9.51611)
		(stroke
			(width 0.254)
			(type default)
		)
		(layer "In6.Cu")
	)
	(gr_line
		(start 340.100666 -7.05231)
		(end 340.100666 -9.51611)
		(stroke
			(width 0.254)
			(type default)
		)
		(layer "In6.Cu")
	)
	(gr_line
		(start 340.126066 -13.7668)
		(end 338.983066 -13.7668)
		(stroke
			(width 0.254)
			(type default)
		)
		(layer "In6.Cu")
	)
	(gr_line
		(start 340.126066 -13.7668)
		(end 339.897466 -13.7668)
		(stroke
			(width 0.1778)
			(type default)
		)
		(layer "In6.Cu")
	)
	(gr_line
		(start 340.126066 -11.2268)
		(end 340.126066 -13.7668)
		(stroke
			(width 0.254)
			(type default)
		)
		(layer "In6.Cu")
	)
	(gr_line
		(start 340.126066 -11.2014)
		(end 340.126066 -13.7668)
		(stroke
			(width 0.1778)
			(type default)
		)
		(layer "In6.Cu")
	)
	(gr_line
		(start 340.126066 -9.56691)
		(end 338.983066 -9.56691)
		(stroke
			(width 0.254)
			(type default)
		)
		(layer "In6.Cu")
	)
	(gr_line
		(start 340.126066 -9.56691)
		(end 339.897466 -9.56691)
		(stroke
			(width 0.1778)
			(type default)
		)
		(layer "In6.Cu")
	)
	(gr_line
		(start 340.126066 -7.02691)
		(end 340.126066 -9.56691)
		(stroke
			(width 0.254)
			(type default)
		)
		(layer "In6.Cu")
	)
	(gr_line
		(start 340.126066 -7.00151)
		(end 340.126066 -9.56691)
		(stroke
			(width 0.1778)
			(type default)
		)
		(layer "In6.Cu")
	)
	(gr_line
		(start 340.151466 -13.7922)
		(end 338.932266 -13.7922)
		(stroke
			(width 0.1778)
			(type default)
		)
		(layer "In6.Cu")
	)
	(gr_line
		(start 340.151466 -13.7922)
		(end 339.922866 -13.7922)
		(stroke
			(width 0.127)
			(type default)
		)
		(layer "In6.Cu")
	)
	(gr_line
		(start 340.151466 -11.176)
		(end 340.151466 -13.7922)
		(stroke
			(width 0.127)
			(type default)
		)
		(layer "In6.Cu")
	)
	(gr_line
		(start 340.151466 -11.176)
		(end 340.151466 -13.7922)
		(stroke
			(width 0.1778)
			(type default)
		)
		(layer "In6.Cu")
	)
	(gr_line
		(start 340.151466 -9.59231)
		(end 338.932266 -9.59231)
		(stroke
			(width 0.1778)
			(type default)
		)
		(layer "In6.Cu")
	)
	(gr_line
		(start 340.151466 -9.59231)
		(end 339.922866 -9.59231)
		(stroke
			(width 0.127)
			(type default)
		)
		(layer "In6.Cu")
	)
	(gr_line
		(start 340.151466 -6.97611)
		(end 340.151466 -9.59231)
		(stroke
			(width 0.127)
			(type default)
		)
		(layer "In6.Cu")
	)
	(gr_line
		(start 340.151466 -6.97611)
		(end 340.151466 -9.59231)
		(stroke
			(width 0.1778)
			(type default)
		)
		(layer "In6.Cu")
	)
	(gr_line
		(start 340.176866 -13.8176)
		(end 338.906866 -13.8176)
		(stroke
			(width 0.127)
			(type default)
		)
		(layer "In6.Cu")
	)
	(gr_line
		(start 340.176866 -11.1506)
		(end 340.176866 -13.8176)
		(stroke
			(width 0.127)
			(type default)
		)
		(layer "In6.Cu")
	)
	(gr_line
		(start 340.176866 -9.61771)
		(end 338.906866 -9.61771)
		(stroke
			(width 0.127)
			(type default)
		)
		(layer "In6.Cu")
	)
	(gr_line
		(start 340.176866 -6.95071)
		(end 340.176866 -9.61771)
		(stroke
			(width 0.127)
			(type default)
		)
		(layer "In6.Cu")
	)
	(gr_line
		(start 340.202266 -13.843)
		(end 340.202266 -11.1252)
		(stroke
			(width 0.1016)
			(type default)
		)
		(layer "In6.Cu")
	)
	(gr_line
		(start 340.202266 -11.1252)
		(end 338.856066 -11.1252)
		(stroke
			(width 0.1016)
			(type default)
		)
		(layer "In6.Cu")
	)
	(gr_line
		(start 340.202266 -9.64311)
		(end 340.202266 -6.92531)
		(stroke
			(width 0.1016)
			(type default)
		)
		(layer "In6.Cu")
	)
	(gr_line
		(start 340.202266 -6.92531)
		(end 338.856066 -6.92531)
		(stroke
			(width 0.1016)
			(type default)
		)
		(layer "In6.Cu")
	)
	(gr_line
		(start 348.856046 -12.543028)
		(end 349.694246 -12.543028)
		(stroke
			(width 0.1016)
			(type default)
		)
		(layer "In6.Cu")
	)
	(gr_line
		(start 348.856046 -9.825228)
		(end 348.856046 -12.543028)
		(stroke
			(width 0.1016)
			(type default)
		)
		(layer "In6.Cu")
	)
	(gr_line
		(start 348.856046 -8.343138)
		(end 349.694246 -8.343138)
		(stroke
			(width 0.1016)
			(type default)
		)
		(layer "In6.Cu")
	)
	(gr_line
		(start 348.856046 -5.625338)
		(end 348.856046 -8.343138)
		(stroke
			(width 0.1016)
			(type default)
		)
		(layer "In6.Cu")
	)
	(gr_line
		(start 348.881446 -12.517628)
		(end 348.881446 -9.850628)
		(stroke
			(width 0.127)
			(type default)
		)
		(layer "In6.Cu")
	)
	(gr_line
		(start 348.881446 -9.850628)
		(end 350.176846 -9.850628)
		(stroke
			(width 0.127)
			(type default)
		)
		(layer "In6.Cu")
	)
	(gr_line
		(start 348.881446 -8.317738)
		(end 348.881446 -5.650738)
		(stroke
			(width 0.127)
			(type default)
		)
		(layer "In6.Cu")
	)
	(gr_line
		(start 348.881446 -5.650738)
		(end 350.176846 -5.650738)
		(stroke
			(width 0.127)
			(type default)
		)
		(layer "In6.Cu")
	)
	(gr_line
		(start 348.906846 -12.517628)
		(end 348.906846 -9.876028)
		(stroke
			(width 0.127)
			(type default)
		)
		(layer "In6.Cu")
	)
	(gr_line
		(start 348.906846 -12.492228)
		(end 348.906846 -9.876028)
		(stroke
			(width 0.1778)
			(type default)
		)
		(layer "In6.Cu")
	)
	(gr_line
		(start 348.906846 -9.876028)
		(end 350.151446 -9.876028)
		(stroke
			(width 0.127)
			(type default)
		)
		(layer "In6.Cu")
	)
	(gr_line
		(start 348.906846 -9.876028)
		(end 350.151446 -9.876028)
		(stroke
			(width 0.1778)
			(type default)
		)
		(layer "In6.Cu")
	)
	(gr_line
		(start 348.906846 -8.317738)
		(end 348.906846 -5.676138)
		(stroke
			(width 0.127)
			(type default)
		)
		(layer "In6.Cu")
	)
	(gr_line
		(start 348.906846 -8.292338)
		(end 348.906846 -5.676138)
		(stroke
			(width 0.1778)
			(type default)
		)
		(layer "In6.Cu")
	)
	(gr_line
		(start 348.906846 -5.676138)
		(end 350.151446 -5.676138)
		(stroke
			(width 0.127)
			(type default)
		)
		(layer "In6.Cu")
	)
	(gr_line
		(start 348.906846 -5.676138)
		(end 350.151446 -5.676138)
		(stroke
			(width 0.1778)
			(type default)
		)
		(layer "In6.Cu")
	)
	(gr_line
		(start 348.932246 -12.492228)
		(end 348.932246 -9.901428)
		(stroke
			(width 0.1778)
			(type default)
		)
		(layer "In6.Cu")
	)
	(gr_line
		(start 348.932246 -9.901428)
		(end 350.126046 -9.901428)
		(stroke
			(width 0.1778)
			(type default)
		)
		(layer "In6.Cu")
	)
	(gr_line
		(start 348.932246 -8.292338)
		(end 348.932246 -5.701538)
		(stroke
			(width 0.1778)
			(type default)
		)
		(layer "In6.Cu")
	)
	(gr_line
		(start 348.932246 -5.701538)
		(end 350.126046 -5.701538)
		(stroke
			(width 0.1778)
			(type default)
		)
		(layer "In6.Cu")
	)
	(gr_line
		(start 348.957646 -12.466828)
		(end 348.957646 -9.926828)
		(stroke
			(width 0.254)
			(type default)
		)
		(layer "In6.Cu")
	)
	(gr_line
		(start 348.957646 -9.926828)
		(end 350.126046 -9.926828)
		(stroke
			(width 0.254)
			(type default)
		)
		(layer "In6.Cu")
	)
	(gr_line
		(start 348.957646 -8.266938)
		(end 348.957646 -5.726938)
		(stroke
			(width 0.254)
			(type default)
		)
		(layer "In6.Cu")
	)
	(gr_line
		(start 348.957646 -5.726938)
		(end 350.126046 -5.726938)
		(stroke
			(width 0.254)
			(type default)
		)
		(layer "In6.Cu")
	)
	(gr_line
		(start 348.983046 -12.466828)
		(end 348.983046 -9.952228)
		(stroke
			(width 0.254)
			(type default)
		)
		(layer "In6.Cu")
	)
	(gr_line
		(start 348.983046 -9.952228)
		(end 350.100646 -9.952228)
		(stroke
			(width 0.254)
			(type default)
		)
		(layer "In6.Cu")
	)
	(gr_line
		(start 348.983046 -8.266938)
		(end 348.983046 -5.752338)
		(stroke
			(width 0.254)
			(type default)
		)
		(layer "In6.Cu")
	)
	(gr_line
		(start 348.983046 -5.752338)
		(end 350.100646 -5.752338)
		(stroke
			(width 0.254)
			(type default)
		)
		(layer "In6.Cu")
	)
	(gr_line
		(start 349.008446 -12.416028)
		(end 349.008446 -9.977628)
		(stroke
			(width 0.3556)
			(type default)
		)
		(layer "In6.Cu")
	)
	(gr_line
		(start 349.008446 -9.977628)
		(end 350.049846 -9.977628)
		(stroke
			(width 0.3556)
			(type default)
		)
		(layer "In6.Cu")
	)
	(gr_line
		(start 349.008446 -8.216138)
		(end 349.008446 -5.777738)
		(stroke
			(width 0.3556)
			(type default)
		)
		(layer "In6.Cu")
	)
	(gr_line
		(start 349.008446 -5.777738)
		(end 350.049846 -5.777738)
		(stroke
			(width 0.3556)
			(type default)
		)
		(layer "In6.Cu")
	)
	(gr_line
		(start 349.059246 -12.390628)
		(end 349.059246 -10.028428)
		(stroke
			(width 0.381)
			(type default)
		)
		(layer "In6.Cu")
	)
	(gr_line
		(start 349.059246 -10.028428)
		(end 349.999046 -10.028428)
		(stroke
			(width 0.381)
			(type default)
		)
		(layer "In6.Cu")
	)
	(gr_line
		(start 349.059246 -8.190738)
		(end 349.059246 -5.828538)
		(stroke
			(width 0.381)
			(type default)
		)
		(layer "In6.Cu")
	)
	(gr_line
		(start 349.059246 -5.828538)
		(end 349.999046 -5.828538)
		(stroke
			(width 0.381)
			(type default)
		)
		(layer "In6.Cu")
	)
	(gr_line
		(start 349.135446 -12.339828)
		(end 349.135446 -10.079228)
		(stroke
			(width 0.381)
			(type default)
		)
		(layer "In6.Cu")
	)
	(gr_line
		(start 349.135446 -10.079228)
		(end 349.948246 -10.079228)
		(stroke
			(width 0.381)
			(type default)
		)
		(layer "In6.Cu")
	)
	(gr_line
		(start 349.135446 -8.139938)
		(end 349.135446 -5.879338)
		(stroke
			(width 0.381)
			(type default)
		)
		(layer "In6.Cu")
	)
	(gr_line
		(start 349.135446 -5.879338)
		(end 349.948246 -5.879338)
		(stroke
			(width 0.381)
			(type default)
		)
		(layer "In6.Cu")
	)
	(gr_line
		(start 349.160846 -12.263628)
		(end 349.160846 -10.079228)
		(stroke
			(width 0.508)
			(type default)
		)
		(layer "In6.Cu")
	)
	(gr_line
		(start 349.160846 -10.079228)
		(end 349.922846 -10.079228)
		(stroke
			(width 0.508)
			(type default)
		)
		(layer "In6.Cu")
	)
	(gr_line
		(start 349.160846 -8.063738)
		(end 349.160846 -5.879338)
		(stroke
			(width 0.508)
			(type default)
		)
		(layer "In6.Cu")
	)
	(gr_line
		(start 349.160846 -5.879338)
		(end 349.922846 -5.879338)
		(stroke
			(width 0.508)
			(type default)
		)
		(layer "In6.Cu")
	)
	(gr_line
		(start 349.186246 -12.111228)
		(end 349.770446 -12.111228)
		(stroke
			(width 0.762)
			(type default)
		)
		(layer "In6.Cu")
	)
	(gr_line
		(start 349.186246 -10.282428)
		(end 349.770446 -10.282428)
		(stroke
			(width 0.762)
			(type default)
		)
		(layer "In6.Cu")
	)
	(gr_line
		(start 349.186246 -7.911338)
		(end 349.770446 -7.911338)
		(stroke
			(width 0.762)
			(type default)
		)
		(layer "In6.Cu")
	)
	(gr_line
		(start 349.186246 -6.082538)
		(end 349.770446 -6.082538)
		(stroke
			(width 0.762)
			(type default)
		)
		(layer "In6.Cu")
	)
	(gr_line
		(start 349.211646 -12.263628)
		(end 349.211646 -10.130028)
		(stroke
			(width 0.635)
			(type default)
		)
		(layer "In6.Cu")
	)
	(gr_line
		(start 349.211646 -12.212828)
		(end 349.211646 -10.180828)
		(stroke
			(width 0.762)
			(type default)
		)
		(layer "In6.Cu")
	)
	(gr_line
		(start 349.211646 -10.130028)
		(end 349.897446 -10.130028)
		(stroke
			(width 0.635)
			(type default)
		)
		(layer "In6.Cu")
	)
	(gr_line
		(start 349.211646 -8.063738)
		(end 349.211646 -5.930138)
		(stroke
			(width 0.635)
			(type default)
		)
		(layer "In6.Cu")
	)
	(gr_line
		(start 349.211646 -8.012938)
		(end 349.211646 -5.980938)
		(stroke
			(width 0.762)
			(type default)
		)
		(layer "In6.Cu")
	)
	(gr_line
		(start 349.211646 -5.930138)
		(end 349.897446 -5.930138)
		(stroke
			(width 0.635)
			(type default)
		)
		(layer "In6.Cu")
	)
	(gr_line
		(start 349.237046 -12.212828)
		(end 349.237046 -10.180828)
		(stroke
			(width 0.762)
			(type default)
		)
		(layer "In6.Cu")
	)
	(gr_line
		(start 349.237046 -10.180828)
		(end 349.821246 -10.180828)
		(stroke
			(width 0.762)
			(type default)
		)
		(layer "In6.Cu")
	)
	(gr_line
		(start 349.237046 -8.012938)
		(end 349.237046 -5.980938)
		(stroke
			(width 0.762)
			(type default)
		)
		(layer "In6.Cu")
	)
	(gr_line
		(start 349.237046 -5.980938)
		(end 349.821246 -5.980938)
		(stroke
			(width 0.762)
			(type default)
		)
		(layer "In6.Cu")
	)
	(gr_line
		(start 349.262446 -12.212828)
		(end 349.262446 -10.180828)
		(stroke
			(width 0.762)
			(type default)
		)
		(layer "In6.Cu")
	)
	(gr_line
		(start 349.262446 -12.212828)
		(end 349.846646 -12.212828)
		(stroke
			(width 0.762)
			(type default)
		)
		(layer "In6.Cu")
	)
	(gr_line
		(start 349.262446 -12.187428)
		(end 349.262446 -10.155428)
		(stroke
			(width 0.762)
			(type default)
		)
		(layer "In6.Cu")
	)
	(gr_line
		(start 349.262446 -8.012938)
		(end 349.262446 -5.980938)
		(stroke
			(width 0.762)
			(type default)
		)
		(layer "In6.Cu")
	)
	(gr_line
		(start 349.262446 -8.012938)
		(end 349.846646 -8.012938)
		(stroke
			(width 0.762)
			(type default)
		)
		(layer "In6.Cu")
	)
	(gr_line
		(start 349.262446 -7.987538)
		(end 349.262446 -5.955538)
		(stroke
			(width 0.762)
			(type default)
		)
		(layer "In6.Cu")
	)
	(gr_line
		(start 349.287846 -12.212828)
		(end 349.287846 -10.180828)
		(stroke
			(width 0.762)
			(type default)
		)
		(layer "In6.Cu")
	)
	(gr_line
		(start 349.287846 -8.012938)
		(end 349.287846 -5.980938)
		(stroke
			(width 0.762)
			(type default)
		)
		(layer "In6.Cu")
	)
	(gr_line
		(start 349.313246 -12.212828)
		(end 349.313246 -10.180828)
		(stroke
			(width 0.762)
			(type default)
		)
		(layer "In6.Cu")
	)
	(gr_line
		(start 349.313246 -8.012938)
		(end 349.313246 -5.980938)
		(stroke
			(width 0.762)
			(type default)
		)
		(layer "In6.Cu")
	)
	(gr_line
		(start 349.338646 -12.212828)
		(end 349.338646 -10.180828)
		(stroke
			(width 0.762)
			(type default)
		)
		(layer "In6.Cu")
	)
	(gr_line
		(start 349.338646 -8.012938)
		(end 349.338646 -5.980938)
		(stroke
			(width 0.762)
			(type default)
		)
		(layer "In6.Cu")
	)
	(gr_line
		(start 349.389446 -12.212828)
		(end 349.389446 -10.180828)
		(stroke
			(width 0.762)
			(type default)
		)
		(layer "In6.Cu")
	)
	(gr_line
		(start 349.389446 -8.012938)
		(end 349.389446 -5.980938)
		(stroke
			(width 0.762)
			(type default)
		)
		(layer "In6.Cu")
	)
	(gr_line
		(start 349.414846 -12.212828)
		(end 349.414846 -10.180828)
		(stroke
			(width 0.762)
			(type default)
		)
		(layer "In6.Cu")
	)
	(gr_line
		(start 349.414846 -8.012938)
		(end 349.414846 -5.980938)
		(stroke
			(width 0.762)
			(type default)
		)
		(layer "In6.Cu")
	)
	(gr_line
		(start 349.440246 -12.212828)
		(end 349.440246 -10.409428)
		(stroke
			(width 0.635)
			(type default)
		)
		(layer "In6.Cu")
	)
	(gr_line
		(start 349.440246 -10.409428)
		(end 349.541846 -10.409428)
		(stroke
			(width 0.635)
			(type default)
		)
		(layer "In6.Cu")
	)
	(gr_line
		(start 349.440246 -8.012938)
		(end 349.440246 -6.209538)
		(stroke
			(width 0.635)
			(type default)
		)
		(layer "In6.Cu")
	)
	(gr_line
		(start 349.440246 -6.209538)
		(end 349.541846 -6.209538)
		(stroke
			(width 0.635)
			(type default)
		)
		(layer "In6.Cu")
	)
	(gr_line
		(start 349.465646 -12.212828)
		(end 349.465646 -10.180828)
		(stroke
			(width 0.762)
			(type default)
		)
		(layer "In6.Cu")
	)
	(gr_line
		(start 349.465646 -12.187428)
		(end 349.465646 -10.155428)
		(stroke
			(width 0.762)
			(type default)
		)
		(layer "In6.Cu")
	)
	(gr_line
		(start 349.465646 -12.136628)
		(end 349.465646 -10.358628)
		(stroke
			(width 0.635)
			(type default)
		)
		(layer "In6.Cu")
	)
	(gr_line
		(start 349.465646 -8.012938)
		(end 349.465646 -5.980938)
		(stroke
			(width 0.762)
			(type default)
		)
		(layer "In6.Cu")
	)
	(gr_line
		(start 349.465646 -7.987538)
		(end 349.465646 -5.955538)
		(stroke
			(width 0.762)
			(type default)
		)
		(layer "In6.Cu")
	)
	(gr_line
		(start 349.465646 -7.936738)
		(end 349.465646 -6.158738)
		(stroke
			(width 0.635)
			(type default)
		)
		(layer "In6.Cu")
	)
	(gr_line
		(start 349.516446 -12.212828)
		(end 349.516446 -10.180828)
		(stroke
			(width 0.762)
			(type default)
		)
		(layer "In6.Cu")
	)
	(gr_line
		(start 349.516446 -8.012938)
		(end 349.516446 -5.980938)
		(stroke
			(width 0.762)
			(type default)
		)
		(layer "In6.Cu")
	)
	(gr_line
		(start 349.541846 -12.212828)
		(end 349.541846 -10.180828)
		(stroke
			(width 0.762)
			(type default)
		)
		(layer "In6.Cu")
	)
	(gr_line
		(start 349.541846 -12.187428)
		(end 349.541846 -10.155428)
		(stroke
			(width 0.762)
			(type default)
		)
		(layer "In6.Cu")
	)
	(gr_line
		(start 349.541846 -12.136628)
		(end 349.465646 -12.136628)
		(stroke
			(width 0.635)
			(type default)
		)
		(layer "In6.Cu")
	)
	(gr_line
		(start 349.541846 -10.409428)
		(end 349.541846 -12.136628)
		(stroke
			(width 0.635)
			(type default)
		)
		(layer "In6.Cu")
	)
	(gr_line
		(start 349.541846 -8.012938)
		(end 349.541846 -5.980938)
		(stroke
			(width 0.762)
			(type default)
		)
		(layer "In6.Cu")
	)
	(gr_line
		(start 349.541846 -7.987538)
		(end 349.541846 -5.955538)
		(stroke
			(width 0.762)
			(type default)
		)
		(layer "In6.Cu")
	)
	(gr_line
		(start 349.541846 -7.936738)
		(end 349.465646 -7.936738)
		(stroke
			(width 0.635)
			(type default)
		)
		(layer "In6.Cu")
	)
	(gr_line
		(start 349.541846 -6.209538)
		(end 349.541846 -7.936738)
		(stroke
			(width 0.635)
			(type default)
		)
		(layer "In6.Cu")
	)
	(gr_line
		(start 349.592646 -12.187428)
		(end 349.592646 -10.155428)
		(stroke
			(width 0.762)
			(type default)
		)
		(layer "In6.Cu")
	)
	(gr_line
		(start 349.592646 -7.987538)
		(end 349.592646 -5.955538)
		(stroke
			(width 0.762)
			(type default)
		)
		(layer "In6.Cu")
	)
	(gr_line
		(start 349.618046 -12.187428)
		(end 349.618046 -10.155428)
		(stroke
			(width 0.762)
			(type default)
		)
		(layer "In6.Cu")
	)
	(gr_line
		(start 349.618046 -7.987538)
		(end 349.618046 -5.955538)
		(stroke
			(width 0.762)
			(type default)
		)
		(layer "In6.Cu")
	)
	(gr_line
		(start 349.668846 -12.212828)
		(end 349.668846 -10.180828)
		(stroke
			(width 0.762)
			(type default)
		)
		(layer "In6.Cu")
	)
	(gr_line
		(start 349.668846 -8.012938)
		(end 349.668846 -5.980938)
		(stroke
			(width 0.762)
			(type default)
		)
		(layer "In6.Cu")
	)
	(gr_line
		(start 349.694246 -12.543028)
		(end 350.202246 -12.543028)
		(stroke
			(width 0.1016)
			(type default)
		)
		(layer "In6.Cu")
	)
	(gr_line
		(start 349.694246 -12.187428)
		(end 349.694246 -10.155428)
		(stroke
			(width 0.762)
			(type default)
		)
		(layer "In6.Cu")
	)
	(gr_line
		(start 349.694246 -8.343138)
		(end 350.202246 -8.343138)
		(stroke
			(width 0.1016)
			(type default)
		)
		(layer "In6.Cu")
	)
	(gr_line
		(start 349.694246 -7.987538)
		(end 349.694246 -5.955538)
		(stroke
			(width 0.762)
			(type default)
		)
		(layer "In6.Cu")
	)
	(gr_line
		(start 349.745046 -12.212828)
		(end 349.745046 -10.180828)
		(stroke
			(width 0.762)
			(type default)
		)
		(layer "In6.Cu")
	)
	(gr_line
		(start 349.745046 -12.187428)
		(end 349.745046 -10.155428)
		(stroke
			(width 0.762)
			(type default)
		)
		(layer "In6.Cu")
	)
	(gr_line
		(start 349.745046 -8.012938)
		(end 349.745046 -5.980938)
		(stroke
			(width 0.762)
			(type default)
		)
		(layer "In6.Cu")
	)
	(gr_line
		(start 349.745046 -7.987538)
		(end 349.745046 -5.955538)
		(stroke
			(width 0.762)
			(type default)
		)
		(layer "In6.Cu")
	)
	(gr_line
		(start 349.770446 -12.187428)
		(end 349.770446 -10.155428)
		(stroke
			(width 0.762)
			(type default)
		)
		(layer "In6.Cu")
	)
	(gr_line
		(start 349.770446 -7.987538)
		(end 349.770446 -5.955538)
		(stroke
			(width 0.762)
			(type default)
		)
		(layer "In6.Cu")
	)
	(gr_line
		(start 349.795846 -12.263628)
		(end 349.160846 -12.263628)
		(stroke
			(width 0.508)
			(type default)
		)
		(layer "In6.Cu")
	)
	(gr_line
		(start 349.795846 -12.263628)
		(end 349.211646 -12.263628)
		(stroke
			(width 0.635)
			(type default)
		)
		(layer "In6.Cu")
	)
	(gr_line
		(start 349.795846 -8.063738)
		(end 349.160846 -8.063738)
		(stroke
			(width 0.508)
			(type default)
		)
		(layer "In6.Cu")
	)
	(gr_line
		(start 349.795846 -8.063738)
		(end 349.211646 -8.063738)
		(stroke
			(width 0.635)
			(type default)
		)
		(layer "In6.Cu")
	)
	(gr_line
		(start 349.821246 -12.187428)
		(end 349.821246 -10.155428)
		(stroke
			(width 0.762)
			(type default)
		)
		(layer "In6.Cu")
	)
	(gr_line
		(start 349.821246 -7.987538)
		(end 349.821246 -5.955538)
		(stroke
			(width 0.762)
			(type default)
		)
		(layer "In6.Cu")
	)
	(gr_line
		(start 349.846646 -12.416028)
		(end 349.008446 -12.416028)
		(stroke
			(width 0.3556)
			(type default)
		)
		(layer "In6.Cu")
	)
	(gr_line
		(start 349.846646 -12.390628)
		(end 349.059246 -12.390628)
		(stroke
			(width 0.381)
			(type default)
		)
		(layer "In6.Cu")
	)
	(gr_line
		(start 349.846646 -8.216138)
		(end 349.008446 -8.216138)
		(stroke
			(width 0.3556)
			(type default)
		)
		(layer "In6.Cu")
	)
	(gr_line
		(start 349.846646 -8.190738)
		(end 349.059246 -8.190738)
		(stroke
			(width 0.381)
			(type default)
		)
		(layer "In6.Cu")
	)
	(gr_line
		(start 349.872046 -12.212828)
		(end 349.872046 -10.180828)
		(stroke
			(width 0.762)
			(type default)
		)
		(layer "In6.Cu")
	)
	(gr_line
		(start 349.872046 -8.012938)
		(end 349.872046 -5.980938)
		(stroke
			(width 0.762)
			(type default)
		)
		(layer "In6.Cu")
	)
	(gr_line
		(start 349.897446 -12.466828)
		(end 348.957646 -12.466828)
		(stroke
			(width 0.254)
			(type default)
		)
		(layer "In6.Cu")
	)
	(gr_line
		(start 349.897446 -12.212828)
		(end 349.440246 -12.212828)
		(stroke
			(width 0.635)
			(type default)
		)
		(layer "In6.Cu")
	)
	(gr_line
		(start 349.897446 -10.130028)
		(end 349.897446 -12.212828)
		(stroke
			(width 0.635)
			(type default)
		)
		(layer "In6.Cu")
	)
	(gr_line
		(start 349.897446 -8.266938)
		(end 348.957646 -8.266938)
		(stroke
			(width 0.254)
			(type default)
		)
		(layer "In6.Cu")
	)
	(gr_line
		(start 349.897446 -8.012938)
		(end 349.440246 -8.012938)
		(stroke
			(width 0.635)
			(type default)
		)
		(layer "In6.Cu")
	)
	(gr_line
		(start 349.897446 -5.930138)
		(end 349.897446 -8.012938)
		(stroke
			(width 0.635)
			(type default)
		)
		(layer "In6.Cu")
	)
	(gr_line
		(start 349.922846 -12.492228)
		(end 348.906846 -12.492228)
		(stroke
			(width 0.1778)
			(type default)
		)
		(layer "In6.Cu")
	)
	(gr_line
		(start 349.922846 -12.263628)
		(end 349.795846 -12.263628)
		(stroke
			(width 0.508)
			(type default)
		)
		(layer "In6.Cu")
	)
	(gr_line
		(start 349.922846 -10.079228)
		(end 349.922846 -12.263628)
		(stroke
			(width 0.508)
			(type default)
		)
		(layer "In6.Cu")
	)
	(gr_line
		(start 349.922846 -8.292338)
		(end 348.906846 -8.292338)
		(stroke
			(width 0.1778)
			(type default)
		)
		(layer "In6.Cu")
	)
	(gr_line
		(start 349.922846 -8.063738)
		(end 349.795846 -8.063738)
		(stroke
			(width 0.508)
			(type default)
		)
		(layer "In6.Cu")
	)
	(gr_line
		(start 349.922846 -5.879338)
		(end 349.922846 -8.063738)
		(stroke
			(width 0.508)
			(type default)
		)
		(layer "In6.Cu")
	)
	(gr_line
		(start 349.948246 -12.263628)
		(end 349.795846 -12.263628)
		(stroke
			(width 0.381)
			(type default)
		)
		(layer "In6.Cu")
	)
	(gr_line
		(start 349.948246 -10.079228)
		(end 349.948246 -12.263628)
		(stroke
			(width 0.381)
			(type default)
		)
		(layer "In6.Cu")
	)
	(gr_line
		(start 349.948246 -8.063738)
		(end 349.795846 -8.063738)
		(stroke
			(width 0.381)
			(type default)
		)
		(layer "In6.Cu")
	)
	(gr_line
		(start 349.948246 -5.879338)
		(end 349.948246 -8.063738)
		(stroke
			(width 0.381)
			(type default)
		)
		(layer "In6.Cu")
	)
	(gr_line
		(start 349.999046 -12.339828)
		(end 349.135446 -12.339828)
		(stroke
			(width 0.381)
			(type default)
		)
		(layer "In6.Cu")
	)
	(gr_line
		(start 349.999046 -10.028428)
		(end 349.999046 -12.339828)
		(stroke
			(width 0.381)
			(type default)
		)
		(layer "In6.Cu")
	)
	(gr_line
		(start 349.999046 -8.139938)
		(end 349.135446 -8.139938)
		(stroke
			(width 0.381)
			(type default)
		)
		(layer "In6.Cu")
	)
	(gr_line
		(start 349.999046 -5.828538)
		(end 349.999046 -8.139938)
		(stroke
			(width 0.381)
			(type default)
		)
		(layer "In6.Cu")
	)
	(gr_line
		(start 350.049846 -12.390628)
		(end 349.846646 -12.390628)
		(stroke
			(width 0.3556)
			(type default)
		)
		(layer "In6.Cu")
	)
	(gr_line
		(start 350.049846 -9.977628)
		(end 350.049846 -12.390628)
		(stroke
			(width 0.3556)
			(type default)
		)
		(layer "In6.Cu")
	)
	(gr_line
		(start 350.049846 -8.190738)
		(end 349.846646 -8.190738)
		(stroke
			(width 0.3556)
			(type default)
		)
		(layer "In6.Cu")
	)
	(gr_line
		(start 350.049846 -5.777738)
		(end 350.049846 -8.190738)
		(stroke
			(width 0.3556)
			(type default)
		)
		(layer "In6.Cu")
	)
	(gr_line
		(start 350.075246 -12.517628)
		(end 348.881446 -12.517628)
		(stroke
			(width 0.127)
			(type default)
		)
		(layer "In6.Cu")
	)
	(gr_line
		(start 350.075246 -8.317738)
		(end 348.881446 -8.317738)
		(stroke
			(width 0.127)
			(type default)
		)
		(layer "In6.Cu")
	)
	(gr_line
		(start 350.100646 -12.416028)
		(end 349.846646 -12.416028)
		(stroke
			(width 0.254)
			(type default)
		)
		(layer "In6.Cu")
	)
	(gr_line
		(start 350.100646 -9.952228)
		(end 350.100646 -12.416028)
		(stroke
			(width 0.254)
			(type default)
		)
		(layer "In6.Cu")
	)
	(gr_line
		(start 350.100646 -8.216138)
		(end 349.846646 -8.216138)
		(stroke
			(width 0.254)
			(type default)
		)
		(layer "In6.Cu")
	)
	(gr_line
		(start 350.100646 -5.752338)
		(end 350.100646 -8.216138)
		(stroke
			(width 0.254)
			(type default)
		)
		(layer "In6.Cu")
	)
	(gr_line
		(start 350.126046 -12.466828)
		(end 348.983046 -12.466828)
		(stroke
			(width 0.254)
			(type default)
		)
		(layer "In6.Cu")
	)
	(gr_line
		(start 350.126046 -12.466828)
		(end 349.897446 -12.466828)
		(stroke
			(width 0.1778)
			(type default)
		)
		(layer "In6.Cu")
	)
	(gr_line
		(start 350.126046 -9.926828)
		(end 350.126046 -12.466828)
		(stroke
			(width 0.254)
			(type default)
		)
		(layer "In6.Cu")
	)
	(gr_line
		(start 350.126046 -9.901428)
		(end 350.126046 -12.466828)
		(stroke
			(width 0.1778)
			(type default)
		)
		(layer "In6.Cu")
	)
	(gr_line
		(start 350.126046 -8.266938)
		(end 348.983046 -8.266938)
		(stroke
			(width 0.254)
			(type default)
		)
		(layer "In6.Cu")
	)
	(gr_line
		(start 350.126046 -8.266938)
		(end 349.897446 -8.266938)
		(stroke
			(width 0.1778)
			(type default)
		)
		(layer "In6.Cu")
	)
	(gr_line
		(start 350.126046 -5.726938)
		(end 350.126046 -8.266938)
		(stroke
			(width 0.254)
			(type default)
		)
		(layer "In6.Cu")
	)
	(gr_line
		(start 350.126046 -5.701538)
		(end 350.126046 -8.266938)
		(stroke
			(width 0.1778)
			(type default)
		)
		(layer "In6.Cu")
	)
	(gr_line
		(start 350.151446 -12.492228)
		(end 348.932246 -12.492228)
		(stroke
			(width 0.1778)
			(type default)
		)
		(layer "In6.Cu")
	)
	(gr_line
		(start 350.151446 -12.492228)
		(end 349.922846 -12.492228)
		(stroke
			(width 0.127)
			(type default)
		)
		(layer "In6.Cu")
	)
	(gr_line
		(start 350.151446 -9.876028)
		(end 350.151446 -12.492228)
		(stroke
			(width 0.127)
			(type default)
		)
		(layer "In6.Cu")
	)
	(gr_line
		(start 350.151446 -9.876028)
		(end 350.151446 -12.492228)
		(stroke
			(width 0.1778)
			(type default)
		)
		(layer "In6.Cu")
	)
	(gr_line
		(start 350.151446 -8.292338)
		(end 348.932246 -8.292338)
		(stroke
			(width 0.1778)
			(type default)
		)
		(layer "In6.Cu")
	)
	(gr_line
		(start 350.151446 -8.292338)
		(end 349.922846 -8.292338)
		(stroke
			(width 0.127)
			(type default)
		)
		(layer "In6.Cu")
	)
	(gr_line
		(start 350.151446 -5.676138)
		(end 350.151446 -8.292338)
		(stroke
			(width 0.127)
			(type default)
		)
		(layer "In6.Cu")
	)
	(gr_line
		(start 350.151446 -5.676138)
		(end 350.151446 -8.292338)
		(stroke
			(width 0.1778)
			(type default)
		)
		(layer "In6.Cu")
	)
	(gr_line
		(start 350.176846 -12.517628)
		(end 348.906846 -12.517628)
		(stroke
			(width 0.127)
			(type default)
		)
		(layer "In6.Cu")
	)
	(gr_line
		(start 350.176846 -9.850628)
		(end 350.176846 -12.517628)
		(stroke
			(width 0.127)
			(type default)
		)
		(layer "In6.Cu")
	)
	(gr_line
		(start 350.176846 -8.317738)
		(end 348.906846 -8.317738)
		(stroke
			(width 0.127)
			(type default)
		)
		(layer "In6.Cu")
	)
	(gr_line
		(start 350.176846 -5.650738)
		(end 350.176846 -8.317738)
		(stroke
			(width 0.127)
			(type default)
		)
		(layer "In6.Cu")
	)
	(gr_line
		(start 350.202246 -12.543028)
		(end 350.202246 -9.825228)
		(stroke
			(width 0.1016)
			(type default)
		)
		(layer "In6.Cu")
	)
	(gr_line
		(start 350.202246 -9.825228)
		(end 348.856046 -9.825228)
		(stroke
			(width 0.1016)
			(type default)
		)
		(layer "In6.Cu")
	)
	(gr_line
		(start 350.202246 -8.343138)
		(end 350.202246 -5.625338)
		(stroke
			(width 0.1016)
			(type default)
		)
		(layer "In6.Cu")
	)
	(gr_line
		(start 350.202246 -5.625338)
		(end 348.856046 -5.625338)
		(stroke
			(width 0.1016)
			(type default)
		)
		(layer "In6.Cu")
	)
	(gr_line
		(start 353.918266 -3.95732)
		(end 353.918266 -5.22732)
		(stroke
			(width 1.016)
			(type default)
		)
		(layer "In6.Cu")
	)
	(gr_line
		(start 353.989894 -52.319936)
		(end 335.069942 -52.319936)
		(stroke
			(width 1.016)
			(type default)
		)
		(layer "In6.Cu")
	)
	(gr_arc
		(start 353.989894 -52.319936)
		(mid 354.697017 -52.027048)
		(end 354.989892 -51.319938)
		(stroke
			(width 1.016)
			(type default)
		)
		(layer "In6.Cu")
	)
	(gr_line
		(start 354.989892 -50.8)
		(end 354.989892 -51.319938)
		(stroke
			(width 1.016)
			(type default)
		)
		(layer "In6.Cu")
	)
	(gr_arc
		(start 355.98989 -49.800002)
		(mid 355.282785 -50.092895)
		(end 354.989892 -50.8)
		(stroke
			(width 1.016)
			(type default)
		)
		(layer "In6.Cu")
	)
	(gr_line
		(start 360.496866 -11.378946)
		(end 360.496866 -9.194546)
		(stroke
			(width 0.254)
			(type default)
		)
		(layer "In6.Cu")
	)
	(gr_line
		(start 360.496866 -9.194546)
		(end 362.071666 -9.194546)
		(stroke
			(width 0.254)
			(type default)
		)
		(layer "In6.Cu")
	)
	(gr_line
		(start 360.522266 -11.378946)
		(end 360.522266 -9.245346)
		(stroke
			(width 0.254)
			(type default)
		)
		(layer "In6.Cu")
	)
	(gr_line
		(start 360.522266 -9.245346)
		(end 362.046266 -9.245346)
		(stroke
			(width 0.254)
			(type default)
		)
		(layer "In6.Cu")
	)
	(gr_line
		(start 360.573066 -11.353546)
		(end 360.573066 -9.372346)
		(stroke
			(width 0.254)
			(type default)
		)
		(layer "In6.Cu")
	)
	(gr_line
		(start 360.573066 -9.372346)
		(end 362.020866 -9.372346)
		(stroke
			(width 0.254)
			(type default)
		)
		(layer "In6.Cu")
	)
	(gr_line
		(start 360.627168 -11.302746)
		(end 360.931968 -11.302746)
		(stroke
			(width 0.1016)
			(type default)
		)
		(layer "In6.Cu")
	)
	(gr_line
		(start 360.627168 -9.296146)
		(end 360.627168 -11.302746)
		(stroke
			(width 0.1016)
			(type default)
		)
		(layer "In6.Cu")
	)
	(gr_line
		(start 360.677968 -11.226546)
		(end 361.770168 -11.226546)
		(stroke
			(width 0.2032)
			(type default)
		)
		(layer "In6.Cu")
	)
	(gr_line
		(start 360.677968 -9.372346)
		(end 360.677968 -11.226546)
		(stroke
			(width 0.2032)
			(type default)
		)
		(layer "In6.Cu")
	)
	(gr_line
		(start 360.703368 -11.226546)
		(end 361.871768 -11.226546)
		(stroke
			(width 0.2032)
			(type default)
		)
		(layer "In6.Cu")
	)
	(gr_line
		(start 360.703368 -9.423146)
		(end 360.703368 -11.226546)
		(stroke
			(width 0.2032)
			(type default)
		)
		(layer "In6.Cu")
	)
	(gr_line
		(start 360.750866 -11.124946)
		(end 360.750866 -9.575546)
		(stroke
			(width 0.762)
			(type default)
		)
		(layer "In6.Cu")
	)
	(gr_line
		(start 360.750866 -11.124946)
		(end 361.665266 -11.124946)
		(stroke
			(width 0.762)
			(type default)
		)
		(layer "In6.Cu")
	)
	(gr_line
		(start 360.750866 -11.099546)
		(end 360.750866 -9.550146)
		(stroke
			(width 0.762)
			(type default)
		)
		(layer "In6.Cu")
	)
	(gr_line
		(start 360.750866 -10.997946)
		(end 360.750866 -9.448546)
		(stroke
			(width 0.762)
			(type default)
		)
		(layer "In6.Cu")
	)
	(gr_line
		(start 360.750866 -9.448546)
		(end 361.665266 -9.448546)
		(stroke
			(width 0.762)
			(type default)
		)
		(layer "In6.Cu")
	)
	(gr_line
		(start 360.754168 -11.175746)
		(end 361.846368 -11.175746)
		(stroke
			(width 0.2032)
			(type default)
		)
		(layer "In6.Cu")
	)
	(gr_line
		(start 360.754168 -9.473946)
		(end 360.754168 -11.175746)
		(stroke
			(width 0.2032)
			(type default)
		)
		(layer "In6.Cu")
	)
	(gr_line
		(start 360.776266 -10.997946)
		(end 361.690666 -10.997946)
		(stroke
			(width 0.762)
			(type default)
		)
		(layer "In6.Cu")
	)
	(gr_line
		(start 360.776266 -9.575546)
		(end 361.690666 -9.575546)
		(stroke
			(width 0.762)
			(type default)
		)
		(layer "In6.Cu")
	)
	(gr_line
		(start 360.855768 -11.074146)
		(end 361.643168 -11.074146)
		(stroke
			(width 0.508)
			(type default)
		)
		(layer "In6.Cu")
	)
	(gr_line
		(start 360.855768 -11.048746)
		(end 360.855768 -9.524746)
		(stroke
			(width 0.508)
			(type default)
		)
		(layer "In6.Cu")
	)
	(gr_line
		(start 360.881168 -11.074146)
		(end 360.881168 -9.550146)
		(stroke
			(width 0.508)
			(type default)
		)
		(layer "In6.Cu")
	)
	(gr_line
		(start 360.903266 -11.124946)
		(end 361.817666 -11.124946)
		(stroke
			(width 0.762)
			(type default)
		)
		(layer "In6.Cu")
	)
	(gr_line
		(start 360.903266 -9.448546)
		(end 361.817666 -9.448546)
		(stroke
			(width 0.762)
			(type default)
		)
		(layer "In6.Cu")
	)
	(gr_line
		(start 360.906568 -9.524746)
		(end 361.643168 -9.524746)
		(stroke
			(width 0.508)
			(type default)
		)
		(layer "In6.Cu")
	)
	(gr_line
		(start 360.931968 -11.302746)
		(end 361.922568 -11.302746)
		(stroke
			(width 0.1016)
			(type default)
		)
		(layer "In6.Cu")
	)
	(gr_line
		(start 360.931968 -11.074146)
		(end 360.931968 -9.550146)
		(stroke
			(width 0.508)
			(type default)
		)
		(layer "In6.Cu")
	)
	(gr_line
		(start 360.957368 -11.074146)
		(end 360.957368 -9.550146)
		(stroke
			(width 0.508)
			(type default)
		)
		(layer "In6.Cu")
	)
	(gr_line
		(start 360.982768 -11.074146)
		(end 360.982768 -9.550146)
		(stroke
			(width 0.508)
			(type default)
		)
		(layer "In6.Cu")
	)
	(gr_line
		(start 361.008168 -11.074146)
		(end 361.008168 -9.550146)
		(stroke
			(width 0.508)
			(type default)
		)
		(layer "In6.Cu")
	)
	(gr_line
		(start 361.008168 -11.048746)
		(end 361.008168 -9.524746)
		(stroke
			(width 0.508)
			(type default)
		)
		(layer "In6.Cu")
	)
	(gr_line
		(start 361.033568 -11.074146)
		(end 361.033568 -9.550146)
		(stroke
			(width 0.508)
			(type default)
		)
		(layer "In6.Cu")
	)
	(gr_line
		(start 361.058968 -11.074146)
		(end 361.058968 -9.550146)
		(stroke
			(width 0.508)
			(type default)
		)
		(layer "In6.Cu")
	)
	(gr_line
		(start 361.109768 -11.074146)
		(end 361.109768 -9.550146)
		(stroke
			(width 0.508)
			(type default)
		)
		(layer "In6.Cu")
	)
	(gr_line
		(start 361.109768 -11.048746)
		(end 361.109768 -9.524746)
		(stroke
			(width 0.508)
			(type default)
		)
		(layer "In6.Cu")
	)
	(gr_line
		(start 361.135168 -11.074146)
		(end 361.135168 -9.550146)
		(stroke
			(width 0.508)
			(type default)
		)
		(layer "In6.Cu")
	)
	(gr_line
		(start 361.160568 -11.074146)
		(end 361.160568 -9.550146)
		(stroke
			(width 0.508)
			(type default)
		)
		(layer "In6.Cu")
	)
	(gr_line
		(start 361.185968 -11.074146)
		(end 361.185968 -9.550146)
		(stroke
			(width 0.508)
			(type default)
		)
		(layer "In6.Cu")
	)
	(gr_line
		(start 361.236768 -11.074146)
		(end 361.236768 -9.550146)
		(stroke
			(width 0.508)
			(type default)
		)
		(layer "In6.Cu")
	)
	(gr_line
		(start 361.262168 -11.074146)
		(end 361.262168 -9.550146)
		(stroke
			(width 0.508)
			(type default)
		)
		(layer "In6.Cu")
	)
	(gr_line
		(start 361.262168 -11.048746)
		(end 361.262168 -9.524746)
		(stroke
			(width 0.508)
			(type default)
		)
		(layer "In6.Cu")
	)
	(gr_line
		(start 361.287568 -11.074146)
		(end 361.287568 -9.550146)
		(stroke
			(width 0.508)
			(type default)
		)
		(layer "In6.Cu")
	)
	(gr_line
		(start 361.312968 -11.074146)
		(end 361.312968 -9.550146)
		(stroke
			(width 0.508)
			(type default)
		)
		(layer "In6.Cu")
	)
	(gr_line
		(start 361.338368 -11.074146)
		(end 361.338368 -9.550146)
		(stroke
			(width 0.508)
			(type default)
		)
		(layer "In6.Cu")
	)
	(gr_line
		(start 361.338368 -11.048746)
		(end 361.338368 -9.524746)
		(stroke
			(width 0.508)
			(type default)
		)
		(layer "In6.Cu")
	)
	(gr_line
		(start 361.363768 -11.074146)
		(end 361.363768 -9.550146)
		(stroke
			(width 0.508)
			(type default)
		)
		(layer "In6.Cu")
	)
	(gr_line
		(start 361.389168 -11.074146)
		(end 361.389168 -9.550146)
		(stroke
			(width 0.508)
			(type default)
		)
		(layer "In6.Cu")
	)
	(gr_line
		(start 361.389168 -11.048746)
		(end 361.389168 -9.524746)
		(stroke
			(width 0.508)
			(type default)
		)
		(layer "In6.Cu")
	)
	(gr_line
		(start 361.414568 -11.074146)
		(end 361.414568 -9.550146)
		(stroke
			(width 0.508)
			(type default)
		)
		(layer "In6.Cu")
	)
	(gr_line
		(start 361.414568 -11.048746)
		(end 361.414568 -9.524746)
		(stroke
			(width 0.508)
			(type default)
		)
		(layer "In6.Cu")
	)
	(gr_line
		(start 361.439968 -11.048746)
		(end 361.439968 -9.524746)
		(stroke
			(width 0.508)
			(type default)
		)
		(layer "In6.Cu")
	)
	(gr_line
		(start 361.465368 -11.074146)
		(end 361.465368 -9.550146)
		(stroke
			(width 0.508)
			(type default)
		)
		(layer "In6.Cu")
	)
	(gr_line
		(start 361.487466 -11.378946)
		(end 360.496866 -11.378946)
		(stroke
			(width 0.254)
			(type default)
		)
		(layer "In6.Cu")
	)
	(gr_line
		(start 361.490768 -11.048746)
		(end 361.490768 -9.524746)
		(stroke
			(width 0.508)
			(type default)
		)
		(layer "In6.Cu")
	)
	(gr_line
		(start 361.516168 -11.048746)
		(end 361.516168 -9.524746)
		(stroke
			(width 0.508)
			(type default)
		)
		(layer "In6.Cu")
	)
	(gr_line
		(start 361.541568 -11.074146)
		(end 361.541568 -9.550146)
		(stroke
			(width 0.508)
			(type default)
		)
		(layer "In6.Cu")
	)
	(gr_line
		(start 361.566968 -11.074146)
		(end 361.566968 -9.550146)
		(stroke
			(width 0.508)
			(type default)
		)
		(layer "In6.Cu")
	)
	(gr_line
		(start 361.566968 -11.048746)
		(end 361.566968 -9.524746)
		(stroke
			(width 0.508)
			(type default)
		)
		(layer "In6.Cu")
	)
	(gr_line
		(start 361.617768 -11.074146)
		(end 361.617768 -9.550146)
		(stroke
			(width 0.508)
			(type default)
		)
		(layer "In6.Cu")
	)
	(gr_line
		(start 361.617768 -11.048746)
		(end 361.617768 -9.524746)
		(stroke
			(width 0.508)
			(type default)
		)
		(layer "In6.Cu")
	)
	(gr_line
		(start 361.668568 -11.074146)
		(end 361.668568 -9.550146)
		(stroke
			(width 0.508)
			(type default)
		)
		(layer "In6.Cu")
	)
	(gr_line
		(start 361.668568 -11.048746)
		(end 361.668568 -9.524746)
		(stroke
			(width 0.508)
			(type default)
		)
		(layer "In6.Cu")
	)
	(gr_line
		(start 361.690666 -11.099546)
		(end 361.690666 -9.550146)
		(stroke
			(width 0.762)
			(type default)
		)
		(layer "In6.Cu")
	)
	(gr_line
		(start 361.693968 -11.074146)
		(end 361.693968 -9.550146)
		(stroke
			(width 0.508)
			(type default)
		)
		(layer "In6.Cu")
	)
	(gr_line
		(start 361.719368 -11.074146)
		(end 361.719368 -9.550146)
		(stroke
			(width 0.508)
			(type default)
		)
		(layer "In6.Cu")
	)
	(gr_line
		(start 361.770168 -11.226546)
		(end 361.795568 -11.226546)
		(stroke
			(width 0.2032)
			(type default)
		)
		(layer "In6.Cu")
	)
	(gr_line
		(start 361.795568 -11.226546)
		(end 361.795568 -9.473946)
		(stroke
			(width 0.2032)
			(type default)
		)
		(layer "In6.Cu")
	)
	(gr_line
		(start 361.795568 -9.473946)
		(end 360.754168 -9.473946)
		(stroke
			(width 0.2032)
			(type default)
		)
		(layer "In6.Cu")
	)
	(gr_line
		(start 361.817666 -11.124946)
		(end 361.817666 -9.575546)
		(stroke
			(width 0.762)
			(type default)
		)
		(layer "In6.Cu")
	)
	(gr_line
		(start 361.817666 -11.099546)
		(end 361.817666 -9.600946)
		(stroke
			(width 0.762)
			(type default)
		)
		(layer "In6.Cu")
	)
	(gr_line
		(start 361.817666 -10.997946)
		(end 361.817666 -9.448546)
		(stroke
			(width 0.762)
			(type default)
		)
		(layer "In6.Cu")
	)
	(gr_line
		(start 361.846368 -11.175746)
		(end 361.846368 -9.423146)
		(stroke
			(width 0.2032)
			(type default)
		)
		(layer "In6.Cu")
	)
	(gr_line
		(start 361.846368 -9.423146)
		(end 360.703368 -9.423146)
		(stroke
			(width 0.2032)
			(type default)
		)
		(layer "In6.Cu")
	)
	(gr_line
		(start 361.871768 -11.226546)
		(end 361.871768 -9.372346)
		(stroke
			(width 0.2032)
			(type default)
		)
		(layer "In6.Cu")
	)
	(gr_line
		(start 361.871768 -9.372346)
		(end 360.677968 -9.372346)
		(stroke
			(width 0.2032)
			(type default)
		)
		(layer "In6.Cu")
	)
	(gr_line
		(start 361.922568 -11.302746)
		(end 361.922568 -9.296146)
		(stroke
			(width 0.1016)
			(type default)
		)
		(layer "In6.Cu")
	)
	(gr_line
		(start 361.922568 -9.296146)
		(end 360.627168 -9.296146)
		(stroke
			(width 0.1016)
			(type default)
		)
		(layer "In6.Cu")
	)
	(gr_line
		(start 362.020866 -11.226546)
		(end 361.770168 -11.226546)
		(stroke
			(width 0.254)
			(type default)
		)
		(layer "In6.Cu")
	)
	(gr_line
		(start 362.020866 -9.372346)
		(end 362.020866 -11.226546)
		(stroke
			(width 0.254)
			(type default)
		)
		(layer "In6.Cu")
	)
	(gr_line
		(start 362.046266 -11.353546)
		(end 360.573066 -11.353546)
		(stroke
			(width 0.254)
			(type default)
		)
		(layer "In6.Cu")
	)
	(gr_line
		(start 362.046266 -9.245346)
		(end 362.046266 -11.353546)
		(stroke
			(width 0.254)
			(type default)
		)
		(layer "In6.Cu")
	)
	(gr_line
		(start 362.071666 -11.378946)
		(end 360.522266 -11.378946)
		(stroke
			(width 0.254)
			(type default)
		)
		(layer "In6.Cu")
	)
	(gr_line
		(start 362.071666 -9.194546)
		(end 362.071666 -11.378946)
		(stroke
			(width 0.254)
			(type default)
		)
		(layer "In6.Cu")
	)
	(gr_line
		(start 365.296958 -11.378946)
		(end 365.296958 -9.194546)
		(stroke
			(width 0.254)
			(type default)
		)
		(layer "In6.Cu")
	)
	(gr_line
		(start 365.296958 -9.194546)
		(end 366.871758 -9.194546)
		(stroke
			(width 0.254)
			(type default)
		)
		(layer "In6.Cu")
	)
	(gr_line
		(start 365.322358 -11.378946)
		(end 365.322358 -9.245346)
		(stroke
			(width 0.254)
			(type default)
		)
		(layer "In6.Cu")
	)
	(gr_line
		(start 365.322358 -9.245346)
		(end 366.846358 -9.245346)
		(stroke
			(width 0.254)
			(type default)
		)
		(layer "In6.Cu")
	)
	(gr_line
		(start 365.373158 -11.353546)
		(end 365.373158 -9.372346)
		(stroke
			(width 0.254)
			(type default)
		)
		(layer "In6.Cu")
	)
	(gr_line
		(start 365.373158 -9.372346)
		(end 366.820958 -9.372346)
		(stroke
			(width 0.254)
			(type default)
		)
		(layer "In6.Cu")
	)
	(gr_line
		(start 365.42726 -11.302746)
		(end 365.73206 -11.302746)
		(stroke
			(width 0.1016)
			(type default)
		)
		(layer "In6.Cu")
	)
	(gr_line
		(start 365.42726 -9.296146)
		(end 365.42726 -11.302746)
		(stroke
			(width 0.1016)
			(type default)
		)
		(layer "In6.Cu")
	)
	(gr_line
		(start 365.4552 -5.715)
		(end 366.7252 -5.715)
		(stroke
			(width 1.016)
			(type default)
		)
		(layer "In6.Cu")
	)
	(gr_line
		(start 365.47806 -11.226546)
		(end 366.57026 -11.226546)
		(stroke
			(width 0.2032)
			(type default)
		)
		(layer "In6.Cu")
	)
	(gr_line
		(start 365.47806 -9.372346)
		(end 365.47806 -11.226546)
		(stroke
			(width 0.2032)
			(type default)
		)
		(layer "In6.Cu")
	)
	(gr_line
		(start 365.50346 -11.226546)
		(end 366.67186 -11.226546)
		(stroke
			(width 0.2032)
			(type default)
		)
		(layer "In6.Cu")
	)
	(gr_line
		(start 365.50346 -9.423146)
		(end 365.50346 -11.226546)
		(stroke
			(width 0.2032)
			(type default)
		)
		(layer "In6.Cu")
	)
	(gr_line
		(start 365.550958 -11.124946)
		(end 365.550958 -9.575546)
		(stroke
			(width 0.762)
			(type default)
		)
		(layer "In6.Cu")
	)
	(gr_line
		(start 365.550958 -11.124946)
		(end 366.465358 -11.124946)
		(stroke
			(width 0.762)
			(type default)
		)
		(layer "In6.Cu")
	)
	(gr_line
		(start 365.550958 -11.099546)
		(end 365.550958 -9.550146)
		(stroke
			(width 0.762)
			(type default)
		)
		(layer "In6.Cu")
	)
	(gr_line
		(start 365.550958 -10.997946)
		(end 365.550958 -9.448546)
		(stroke
			(width 0.762)
			(type default)
		)
		(layer "In6.Cu")
	)
	(gr_line
		(start 365.550958 -9.448546)
		(end 366.465358 -9.448546)
		(stroke
			(width 0.762)
			(type default)
		)
		(layer "In6.Cu")
	)
	(gr_line
		(start 365.55426 -11.175746)
		(end 366.64646 -11.175746)
		(stroke
			(width 0.2032)
			(type default)
		)
		(layer "In6.Cu")
	)
	(gr_line
		(start 365.55426 -9.473946)
		(end 365.55426 -11.175746)
		(stroke
			(width 0.2032)
			(type default)
		)
		(layer "In6.Cu")
	)
	(gr_line
		(start 365.576358 -10.997946)
		(end 366.490758 -10.997946)
		(stroke
			(width 0.762)
			(type default)
		)
		(layer "In6.Cu")
	)
	(gr_line
		(start 365.576358 -9.575546)
		(end 366.490758 -9.575546)
		(stroke
			(width 0.762)
			(type default)
		)
		(layer "In6.Cu")
	)
	(gr_line
		(start 365.65586 -11.074146)
		(end 366.44326 -11.074146)
		(stroke
			(width 0.508)
			(type default)
		)
		(layer "In6.Cu")
	)
	(gr_line
		(start 365.65586 -11.048746)
		(end 365.65586 -9.524746)
		(stroke
			(width 0.508)
			(type default)
		)
		(layer "In6.Cu")
	)
	(gr_line
		(start 365.68126 -11.074146)
		(end 365.68126 -9.550146)
		(stroke
			(width 0.508)
			(type default)
		)
		(layer "In6.Cu")
	)
	(gr_line
		(start 365.703358 -11.124946)
		(end 366.617758 -11.124946)
		(stroke
			(width 0.762)
			(type default)
		)
		(layer "In6.Cu")
	)
	(gr_line
		(start 365.703358 -9.448546)
		(end 366.617758 -9.448546)
		(stroke
			(width 0.762)
			(type default)
		)
		(layer "In6.Cu")
	)
	(gr_line
		(start 365.70666 -9.524746)
		(end 366.44326 -9.524746)
		(stroke
			(width 0.508)
			(type default)
		)
		(layer "In6.Cu")
	)
	(gr_line
		(start 365.73206 -11.302746)
		(end 366.72266 -11.302746)
		(stroke
			(width 0.1016)
			(type default)
		)
		(layer "In6.Cu")
	)
	(gr_line
		(start 365.73206 -11.074146)
		(end 365.73206 -9.550146)
		(stroke
			(width 0.508)
			(type default)
		)
		(layer "In6.Cu")
	)
	(gr_line
		(start 365.75746 -11.074146)
		(end 365.75746 -9.550146)
		(stroke
			(width 0.508)
			(type default)
		)
		(layer "In6.Cu")
	)
	(gr_line
		(start 365.78286 -11.074146)
		(end 365.78286 -9.550146)
		(stroke
			(width 0.508)
			(type default)
		)
		(layer "In6.Cu")
	)
	(gr_line
		(start 365.80826 -11.074146)
		(end 365.80826 -9.550146)
		(stroke
			(width 0.508)
			(type default)
		)
		(layer "In6.Cu")
	)
	(gr_line
		(start 365.80826 -11.048746)
		(end 365.80826 -9.524746)
		(stroke
			(width 0.508)
			(type default)
		)
		(layer "In6.Cu")
	)
	(gr_line
		(start 365.83366 -11.074146)
		(end 365.83366 -9.550146)
		(stroke
			(width 0.508)
			(type default)
		)
		(layer "In6.Cu")
	)
	(gr_line
		(start 365.85906 -11.074146)
		(end 365.85906 -9.550146)
		(stroke
			(width 0.508)
			(type default)
		)
		(layer "In6.Cu")
	)
	(gr_line
		(start 365.90986 -11.074146)
		(end 365.90986 -9.550146)
		(stroke
			(width 0.508)
			(type default)
		)
		(layer "In6.Cu")
	)
	(gr_line
		(start 365.90986 -11.048746)
		(end 365.90986 -9.524746)
		(stroke
			(width 0.508)
			(type default)
		)
		(layer "In6.Cu")
	)
	(gr_line
		(start 365.93526 -11.074146)
		(end 365.93526 -9.550146)
		(stroke
			(width 0.508)
			(type default)
		)
		(layer "In6.Cu")
	)
	(gr_line
		(start 365.96066 -11.074146)
		(end 365.96066 -9.550146)
		(stroke
			(width 0.508)
			(type default)
		)
		(layer "In6.Cu")
	)
	(gr_line
		(start 365.98606 -11.074146)
		(end 365.98606 -9.550146)
		(stroke
			(width 0.508)
			(type default)
		)
		(layer "In6.Cu")
	)
	(gr_line
		(start 366.03686 -11.074146)
		(end 366.03686 -9.550146)
		(stroke
			(width 0.508)
			(type default)
		)
		(layer "In6.Cu")
	)
	(gr_line
		(start 366.06226 -11.074146)
		(end 366.06226 -9.550146)
		(stroke
			(width 0.508)
			(type default)
		)
		(layer "In6.Cu")
	)
	(gr_line
		(start 366.06226 -11.048746)
		(end 366.06226 -9.524746)
		(stroke
			(width 0.508)
			(type default)
		)
		(layer "In6.Cu")
	)
	(gr_line
		(start 366.08766 -11.074146)
		(end 366.08766 -9.550146)
		(stroke
			(width 0.508)
			(type default)
		)
		(layer "In6.Cu")
	)
	(gr_line
		(start 366.11306 -11.074146)
		(end 366.11306 -9.550146)
		(stroke
			(width 0.508)
			(type default)
		)
		(layer "In6.Cu")
	)
	(gr_line
		(start 366.13846 -11.074146)
		(end 366.13846 -9.550146)
		(stroke
			(width 0.508)
			(type default)
		)
		(layer "In6.Cu")
	)
	(gr_line
		(start 366.13846 -11.048746)
		(end 366.13846 -9.524746)
		(stroke
			(width 0.508)
			(type default)
		)
		(layer "In6.Cu")
	)
	(gr_line
		(start 366.16386 -11.074146)
		(end 366.16386 -9.550146)
		(stroke
			(width 0.508)
			(type default)
		)
		(layer "In6.Cu")
	)
	(gr_line
		(start 366.18926 -11.074146)
		(end 366.18926 -9.550146)
		(stroke
			(width 0.508)
			(type default)
		)
		(layer "In6.Cu")
	)
	(gr_line
		(start 366.18926 -11.048746)
		(end 366.18926 -9.524746)
		(stroke
			(width 0.508)
			(type default)
		)
		(layer "In6.Cu")
	)
	(gr_line
		(start 366.21466 -11.074146)
		(end 366.21466 -9.550146)
		(stroke
			(width 0.508)
			(type default)
		)
		(layer "In6.Cu")
	)
	(gr_line
		(start 366.21466 -11.048746)
		(end 366.21466 -9.524746)
		(stroke
			(width 0.508)
			(type default)
		)
		(layer "In6.Cu")
	)
	(gr_line
		(start 366.24006 -11.048746)
		(end 366.24006 -9.524746)
		(stroke
			(width 0.508)
			(type default)
		)
		(layer "In6.Cu")
	)
	(gr_line
		(start 366.26546 -11.074146)
		(end 366.26546 -9.550146)
		(stroke
			(width 0.508)
			(type default)
		)
		(layer "In6.Cu")
	)
	(gr_line
		(start 366.287558 -11.378946)
		(end 365.296958 -11.378946)
		(stroke
			(width 0.254)
			(type default)
		)
		(layer "In6.Cu")
	)
	(gr_line
		(start 366.29086 -11.048746)
		(end 366.29086 -9.524746)
		(stroke
			(width 0.508)
			(type default)
		)
		(layer "In6.Cu")
	)
	(gr_line
		(start 366.31626 -11.048746)
		(end 366.31626 -9.524746)
		(stroke
			(width 0.508)
			(type default)
		)
		(layer "In6.Cu")
	)
	(gr_line
		(start 366.34166 -11.074146)
		(end 366.34166 -9.550146)
		(stroke
			(width 0.508)
			(type default)
		)
		(layer "In6.Cu")
	)
	(gr_line
		(start 366.36706 -11.074146)
		(end 366.36706 -9.550146)
		(stroke
			(width 0.508)
			(type default)
		)
		(layer "In6.Cu")
	)
	(gr_line
		(start 366.36706 -11.048746)
		(end 366.36706 -9.524746)
		(stroke
			(width 0.508)
			(type default)
		)
		(layer "In6.Cu")
	)
	(gr_line
		(start 366.41786 -11.074146)
		(end 366.41786 -9.550146)
		(stroke
			(width 0.508)
			(type default)
		)
		(layer "In6.Cu")
	)
	(gr_line
		(start 366.41786 -11.048746)
		(end 366.41786 -9.524746)
		(stroke
			(width 0.508)
			(type default)
		)
		(layer "In6.Cu")
	)
	(gr_line
		(start 366.46866 -11.074146)
		(end 366.46866 -9.550146)
		(stroke
			(width 0.508)
			(type default)
		)
		(layer "In6.Cu")
	)
	(gr_line
		(start 366.46866 -11.048746)
		(end 366.46866 -9.524746)
		(stroke
			(width 0.508)
			(type default)
		)
		(layer "In6.Cu")
	)
	(gr_line
		(start 366.490758 -11.099546)
		(end 366.490758 -9.550146)
		(stroke
			(width 0.762)
			(type default)
		)
		(layer "In6.Cu")
	)
	(gr_line
		(start 366.49406 -11.074146)
		(end 366.49406 -9.550146)
		(stroke
			(width 0.508)
			(type default)
		)
		(layer "In6.Cu")
	)
	(gr_line
		(start 366.51946 -11.074146)
		(end 366.51946 -9.550146)
		(stroke
			(width 0.508)
			(type default)
		)
		(layer "In6.Cu")
	)
	(gr_line
		(start 366.57026 -11.226546)
		(end 366.59566 -11.226546)
		(stroke
			(width 0.2032)
			(type default)
		)
		(layer "In6.Cu")
	)
	(gr_line
		(start 366.59566 -11.226546)
		(end 366.59566 -9.473946)
		(stroke
			(width 0.2032)
			(type default)
		)
		(layer "In6.Cu")
	)
	(gr_line
		(start 366.59566 -9.473946)
		(end 365.55426 -9.473946)
		(stroke
			(width 0.2032)
			(type default)
		)
		(layer "In6.Cu")
	)
	(gr_line
		(start 366.617758 -11.124946)
		(end 366.617758 -9.575546)
		(stroke
			(width 0.762)
			(type default)
		)
		(layer "In6.Cu")
	)
	(gr_line
		(start 366.617758 -11.099546)
		(end 366.617758 -9.600946)
		(stroke
			(width 0.762)
			(type default)
		)
		(layer "In6.Cu")
	)
	(gr_line
		(start 366.617758 -10.997946)
		(end 366.617758 -9.448546)
		(stroke
			(width 0.762)
			(type default)
		)
		(layer "In6.Cu")
	)
	(gr_line
		(start 366.64646 -11.175746)
		(end 366.64646 -9.423146)
		(stroke
			(width 0.2032)
			(type default)
		)
		(layer "In6.Cu")
	)
	(gr_line
		(start 366.64646 -9.423146)
		(end 365.50346 -9.423146)
		(stroke
			(width 0.2032)
			(type default)
		)
		(layer "In6.Cu")
	)
	(gr_line
		(start 366.67186 -11.226546)
		(end 366.67186 -9.372346)
		(stroke
			(width 0.2032)
			(type default)
		)
		(layer "In6.Cu")
	)
	(gr_line
		(start 366.67186 -9.372346)
		(end 365.47806 -9.372346)
		(stroke
			(width 0.2032)
			(type default)
		)
		(layer "In6.Cu")
	)
	(gr_line
		(start 366.72266 -11.302746)
		(end 366.72266 -9.296146)
		(stroke
			(width 0.1016)
			(type default)
		)
		(layer "In6.Cu")
	)
	(gr_line
		(start 366.72266 -9.296146)
		(end 365.42726 -9.296146)
		(stroke
			(width 0.1016)
			(type default)
		)
		(layer "In6.Cu")
	)
	(gr_line
		(start 366.820958 -11.226546)
		(end 366.57026 -11.226546)
		(stroke
			(width 0.254)
			(type default)
		)
		(layer "In6.Cu")
	)
	(gr_line
		(start 366.820958 -9.372346)
		(end 366.820958 -11.226546)
		(stroke
			(width 0.254)
			(type default)
		)
		(layer "In6.Cu")
	)
	(gr_line
		(start 366.846358 -11.353546)
		(end 365.373158 -11.353546)
		(stroke
			(width 0.254)
			(type default)
		)
		(layer "In6.Cu")
	)
	(gr_line
		(start 366.846358 -9.245346)
		(end 366.846358 -11.353546)
		(stroke
			(width 0.254)
			(type default)
		)
		(layer "In6.Cu")
	)
	(gr_line
		(start 366.871758 -11.378946)
		(end 365.322358 -11.378946)
		(stroke
			(width 0.254)
			(type default)
		)
		(layer "In6.Cu")
	)
	(gr_line
		(start 366.871758 -9.194546)
		(end 366.871758 -11.378946)
		(stroke
			(width 0.254)
			(type default)
		)
		(layer "In6.Cu")
	)
	(gr_line
		(start 370.98986 -49.800002)
		(end 355.98989 -49.800002)
		(stroke
			(width 1.016)
			(type default)
		)
		(layer "In6.Cu")
	)
	(gr_line
		(start 371.989858 -51.319938)
		(end 371.989858 -50.8)
		(stroke
			(width 1.016)
			(type default)
		)
		(layer "In6.Cu")
	)
	(gr_arc
		(start 371.989858 -51.319938)
		(mid 372.282761 -52.027034)
		(end 372.989856 -52.319936)
		(stroke
			(width 1.016)
			(type default)
		)
		(layer "In6.Cu")
	)
	(gr_arc
		(start 371.989858 -50.8)
		(mid 371.696965 -50.092895)
		(end 370.98986 -49.800002)
		(stroke
			(width 1.016)
			(type default)
		)
		(layer "In6.Cu")
	)
	(gr_line
		(start 379.990096 -52.319936)
		(end 372.989856 -52.319936)
		(stroke
			(width 1.016)
			(type default)
		)
		(layer "In6.Cu")
	)
	(gr_line
		(start 380.37262 -52.24399)
		(end 379.990096 -52.319936)
		(stroke
			(width 1.016)
			(type default)
		)
		(layer "In6.Cu")
	)
	(gr_line
		(start 380.697232 -52.027074)
		(end 380.37262 -52.24399)
		(stroke
			(width 1.016)
			(type default)
		)
		(layer "In6.Cu")
	)
	(gr_line
		(start 380.913894 -51.702716)
		(end 380.697232 -52.027074)
		(stroke
			(width 1.016)
			(type default)
		)
		(layer "In6.Cu")
	)
	(gr_line
		(start 380.98222 -51.376072)
		(end 380.913894 -51.702716)
		(stroke
			(width 1.016)
			(type default)
		)
		(layer "In6.Cu")
	)
	(gr_line
		(start 381.070866 -50.996088)
		(end 380.98222 -51.376072)
		(stroke
			(width 1.016)
			(type default)
		)
		(layer "In6.Cu")
	)
	(gr_line
		(start 381.288798 -50.677064)
		(end 381.070866 -50.996088)
		(stroke
			(width 1.016)
			(type default)
		)
		(layer "In6.Cu")
	)
	(gr_line
		(start 381.611124 -50.464466)
		(end 381.288798 -50.677064)
		(stroke
			(width 1.016)
			(type default)
		)
		(layer "In6.Cu")
	)
	(gr_line
		(start 381.990092 -50.390044)
		(end 381.611124 -50.464466)
		(stroke
			(width 1.016)
			(type default)
		)
		(layer "In6.Cu")
	)
	(gr_line
		(start 385.287266 -13.8176)
		(end 386.074666 -13.8176)
		(stroke
			(width 0.1016)
			(type default)
		)
		(layer "In6.Cu")
	)
	(gr_line
		(start 385.287266 -13.7668)
		(end 385.287266 -11.1506)
		(stroke
			(width 0.1016)
			(type default)
		)
		(layer "In6.Cu")
	)
	(gr_line
		(start 385.287266 -11.1506)
		(end 385.287266 -13.8176)
		(stroke
			(width 0.1016)
			(type default)
		)
		(layer "In6.Cu")
	)
	(gr_line
		(start 385.287266 -11.1506)
		(end 386.481066 -11.1506)
		(stroke
			(width 0.1016)
			(type default)
		)
		(layer "In6.Cu")
	)
	(gr_line
		(start 385.287266 -9.617456)
		(end 386.074666 -9.617456)
		(stroke
			(width 0.1016)
			(type default)
		)
		(layer "In6.Cu")
	)
	(gr_line
		(start 385.287266 -9.566656)
		(end 385.287266 -6.950456)
		(stroke
			(width 0.1016)
			(type default)
		)
		(layer "In6.Cu")
	)
	(gr_line
		(start 385.287266 -6.950456)
		(end 385.287266 -9.617456)
		(stroke
			(width 0.1016)
			(type default)
		)
		(layer "In6.Cu")
	)
	(gr_line
		(start 385.287266 -6.950456)
		(end 386.481066 -6.950456)
		(stroke
			(width 0.1016)
			(type default)
		)
		(layer "In6.Cu")
	)
	(gr_line
		(start 385.287266 -5.417312)
		(end 386.074666 -5.417312)
		(stroke
			(width 0.1016)
			(type default)
		)
		(layer "In6.Cu")
	)
	(gr_line
		(start 385.287266 -5.366512)
		(end 385.287266 -2.750312)
		(stroke
			(width 0.1016)
			(type default)
		)
		(layer "In6.Cu")
	)
	(gr_line
		(start 385.287266 -2.750312)
		(end 385.287266 -5.417312)
		(stroke
			(width 0.1016)
			(type default)
		)
		(layer "In6.Cu")
	)
	(gr_line
		(start 385.287266 -2.750312)
		(end 386.481066 -2.750312)
		(stroke
			(width 0.1016)
			(type default)
		)
		(layer "In6.Cu")
	)
	(gr_line
		(start 385.312666 -13.7668)
		(end 385.312666 -11.176)
		(stroke
			(width 0.1016)
			(type default)
		)
		(layer "In6.Cu")
	)
	(gr_line
		(start 385.312666 -11.176)
		(end 386.455666 -11.176)
		(stroke
			(width 0.1016)
			(type default)
		)
		(layer "In6.Cu")
	)
	(gr_line
		(start 385.312666 -9.566656)
		(end 385.312666 -6.975856)
		(stroke
			(width 0.1016)
			(type default)
		)
		(layer "In6.Cu")
	)
	(gr_line
		(start 385.312666 -6.975856)
		(end 386.455666 -6.975856)
		(stroke
			(width 0.1016)
			(type default)
		)
		(layer "In6.Cu")
	)
	(gr_line
		(start 385.312666 -5.366512)
		(end 385.312666 -2.775712)
		(stroke
			(width 0.1016)
			(type default)
		)
		(layer "In6.Cu")
	)
	(gr_line
		(start 385.312666 -2.775712)
		(end 386.455666 -2.775712)
		(stroke
			(width 0.1016)
			(type default)
		)
		(layer "In6.Cu")
	)
	(gr_line
		(start 385.338066 -13.7668)
		(end 385.338066 -11.2014)
		(stroke
			(width 0.1016)
			(type default)
		)
		(layer "In6.Cu")
	)
	(gr_line
		(start 385.338066 -11.2014)
		(end 385.592066 -11.2014)
		(stroke
			(width 0.1016)
			(type default)
		)
		(layer "In6.Cu")
	)
	(gr_line
		(start 385.338066 -9.566656)
		(end 385.338066 -7.001256)
		(stroke
			(width 0.1016)
			(type default)
		)
		(layer "In6.Cu")
	)
	(gr_line
		(start 385.338066 -7.001256)
		(end 385.592066 -7.001256)
		(stroke
			(width 0.1016)
			(type default)
		)
		(layer "In6.Cu")
	)
	(gr_line
		(start 385.338066 -5.366512)
		(end 385.338066 -2.801112)
		(stroke
			(width 0.1016)
			(type default)
		)
		(layer "In6.Cu")
	)
	(gr_line
		(start 385.338066 -2.801112)
		(end 385.592066 -2.801112)
		(stroke
			(width 0.1016)
			(type default)
		)
		(layer "In6.Cu")
	)
	(gr_line
		(start 385.363466 -13.7668)
		(end 385.363466 -11.2014)
		(stroke
			(width 0.2032)
			(type default)
		)
		(layer "In6.Cu")
	)
	(gr_line
		(start 385.363466 -11.2014)
		(end 386.379466 -11.2014)
		(stroke
			(width 0.2032)
			(type default)
		)
		(layer "In6.Cu")
	)
	(gr_line
		(start 385.363466 -9.566656)
		(end 385.363466 -7.001256)
		(stroke
			(width 0.2032)
			(type default)
		)
		(layer "In6.Cu")
	)
	(gr_line
		(start 385.363466 -7.001256)
		(end 386.379466 -7.001256)
		(stroke
			(width 0.2032)
			(type default)
		)
		(layer "In6.Cu")
	)
	(gr_line
		(start 385.363466 -5.366512)
		(end 385.363466 -2.801112)
		(stroke
			(width 0.2032)
			(type default)
		)
		(layer "In6.Cu")
	)
	(gr_line
		(start 385.363466 -2.801112)
		(end 386.379466 -2.801112)
		(stroke
			(width 0.2032)
			(type default)
		)
		(layer "In6.Cu")
	)
	(gr_line
		(start 385.414266 -13.7414)
		(end 385.414266 -11.2522)
		(stroke
			(width 0.2032)
			(type default)
		)
		(layer "In6.Cu")
	)
	(gr_line
		(start 385.414266 -13.7414)
		(end 385.414266 -11.2522)
		(stroke
			(width 0.254)
			(type default)
		)
		(layer "In6.Cu")
	)
	(gr_line
		(start 385.414266 -11.2522)
		(end 385.617466 -11.2522)
		(stroke
			(width 0.2032)
			(type default)
		)
		(layer "In6.Cu")
	)
	(gr_line
		(start 385.414266 -11.2522)
		(end 386.303266 -11.2522)
		(stroke
			(width 0.254)
			(type default)
		)
		(layer "In6.Cu")
	)
	(gr_line
		(start 385.414266 -9.541256)
		(end 385.414266 -7.052056)
		(stroke
			(width 0.2032)
			(type default)
		)
		(layer "In6.Cu")
	)
	(gr_line
		(start 385.414266 -9.541256)
		(end 385.414266 -7.052056)
		(stroke
			(width 0.254)
			(type default)
		)
		(layer "In6.Cu")
	)
	(gr_line
		(start 385.414266 -7.052056)
		(end 385.617466 -7.052056)
		(stroke
			(width 0.2032)
			(type default)
		)
		(layer "In6.Cu")
	)
	(gr_line
		(start 385.414266 -7.052056)
		(end 386.303266 -7.052056)
		(stroke
			(width 0.254)
			(type default)
		)
		(layer "In6.Cu")
	)
	(gr_line
		(start 385.414266 -5.341112)
		(end 385.414266 -2.851912)
		(stroke
			(width 0.2032)
			(type default)
		)
		(layer "In6.Cu")
	)
	(gr_line
		(start 385.414266 -5.341112)
		(end 385.414266 -2.851912)
		(stroke
			(width 0.254)
			(type default)
		)
		(layer "In6.Cu")
	)
	(gr_line
		(start 385.414266 -2.851912)
		(end 385.617466 -2.851912)
		(stroke
			(width 0.2032)
			(type default)
		)
		(layer "In6.Cu")
	)
	(gr_line
		(start 385.414266 -2.851912)
		(end 386.303266 -2.851912)
		(stroke
			(width 0.254)
			(type default)
		)
		(layer "In6.Cu")
	)
	(gr_line
		(start 385.439666 -13.716)
		(end 385.439666 -11.2776)
		(stroke
			(width 0.254)
			(type default)
		)
		(layer "In6.Cu")
	)
	(gr_line
		(start 385.439666 -11.2776)
		(end 386.277866 -11.2776)
		(stroke
			(width 0.254)
			(type default)
		)
		(layer "In6.Cu")
	)
	(gr_line
		(start 385.439666 -9.515856)
		(end 385.439666 -7.077456)
		(stroke
			(width 0.254)
			(type default)
		)
		(layer "In6.Cu")
	)
	(gr_line
		(start 385.439666 -7.077456)
		(end 386.277866 -7.077456)
		(stroke
			(width 0.254)
			(type default)
		)
		(layer "In6.Cu")
	)
	(gr_line
		(start 385.439666 -5.315712)
		(end 385.439666 -2.877312)
		(stroke
			(width 0.254)
			(type default)
		)
		(layer "In6.Cu")
	)
	(gr_line
		(start 385.439666 -2.877312)
		(end 386.277866 -2.877312)
		(stroke
			(width 0.254)
			(type default)
		)
		(layer "In6.Cu")
	)
	(gr_line
		(start 385.465066 -13.6906)
		(end 385.465066 -11.303)
		(stroke
			(width 0.254)
			(type default)
		)
		(layer "In6.Cu")
	)
	(gr_line
		(start 385.465066 -11.303)
		(end 386.252466 -11.303)
		(stroke
			(width 0.254)
			(type default)
		)
		(layer "In6.Cu")
	)
	(gr_line
		(start 385.465066 -9.490456)
		(end 385.465066 -7.102856)
		(stroke
			(width 0.254)
			(type default)
		)
		(layer "In6.Cu")
	)
	(gr_line
		(start 385.465066 -7.102856)
		(end 386.252466 -7.102856)
		(stroke
			(width 0.254)
			(type default)
		)
		(layer "In6.Cu")
	)
	(gr_line
		(start 385.465066 -5.290312)
		(end 385.465066 -2.902712)
		(stroke
			(width 0.254)
			(type default)
		)
		(layer "In6.Cu")
	)
	(gr_line
		(start 385.465066 -2.902712)
		(end 386.252466 -2.902712)
		(stroke
			(width 0.254)
			(type default)
		)
		(layer "In6.Cu")
	)
	(gr_line
		(start 385.490466 -13.6144)
		(end 386.125466 -13.6144)
		(stroke
			(width 0.508)
			(type default)
		)
		(layer "In6.Cu")
	)
	(gr_line
		(start 385.490466 -11.43)
		(end 386.125466 -11.43)
		(stroke
			(width 0.508)
			(type default)
		)
		(layer "In6.Cu")
	)
	(gr_line
		(start 385.490466 -11.3792)
		(end 386.125466 -11.3792)
		(stroke
			(width 0.508)
			(type default)
		)
		(layer "In6.Cu")
	)
	(gr_line
		(start 385.490466 -9.414256)
		(end 386.125466 -9.414256)
		(stroke
			(width 0.508)
			(type default)
		)
		(layer "In6.Cu")
	)
	(gr_line
		(start 385.490466 -7.229856)
		(end 386.125466 -7.229856)
		(stroke
			(width 0.508)
			(type default)
		)
		(layer "In6.Cu")
	)
	(gr_line
		(start 385.490466 -7.179056)
		(end 386.125466 -7.179056)
		(stroke
			(width 0.508)
			(type default)
		)
		(layer "In6.Cu")
	)
	(gr_line
		(start 385.490466 -5.214112)
		(end 386.125466 -5.214112)
		(stroke
			(width 0.508)
			(type default)
		)
		(layer "In6.Cu")
	)
	(gr_line
		(start 385.490466 -3.029712)
		(end 386.125466 -3.029712)
		(stroke
			(width 0.508)
			(type default)
		)
		(layer "In6.Cu")
	)
	(gr_line
		(start 385.490466 -2.978912)
		(end 386.125466 -2.978912)
		(stroke
			(width 0.508)
			(type default)
		)
		(layer "In6.Cu")
	)
	(gr_line
		(start 385.515866 -11.684)
		(end 386.150866 -11.684)
		(stroke
			(width 0.508)
			(type default)
		)
		(layer "In6.Cu")
	)
	(gr_line
		(start 385.515866 -7.483856)
		(end 386.150866 -7.483856)
		(stroke
			(width 0.508)
			(type default)
		)
		(layer "In6.Cu")
	)
	(gr_line
		(start 385.515866 -3.283712)
		(end 386.150866 -3.283712)
		(stroke
			(width 0.508)
			(type default)
		)
		(layer "In6.Cu")
	)
	(gr_line
		(start 385.541266 -13.6398)
		(end 385.541266 -11.3792)
		(stroke
			(width 0.254)
			(type default)
		)
		(layer "In6.Cu")
	)
	(gr_line
		(start 385.541266 -13.4874)
		(end 386.176266 -13.4874)
		(stroke
			(width 0.508)
			(type default)
		)
		(layer "In6.Cu")
	)
	(gr_line
		(start 385.541266 -11.3792)
		(end 386.176266 -11.3792)
		(stroke
			(width 0.254)
			(type default)
		)
		(layer "In6.Cu")
	)
	(gr_line
		(start 385.541266 -9.439656)
		(end 385.541266 -7.179056)
		(stroke
			(width 0.254)
			(type default)
		)
		(layer "In6.Cu")
	)
	(gr_line
		(start 385.541266 -9.287256)
		(end 386.176266 -9.287256)
		(stroke
			(width 0.508)
			(type default)
		)
		(layer "In6.Cu")
	)
	(gr_line
		(start 385.541266 -7.179056)
		(end 386.176266 -7.179056)
		(stroke
			(width 0.254)
			(type default)
		)
		(layer "In6.Cu")
	)
	(gr_line
		(start 385.541266 -5.239512)
		(end 385.541266 -2.978912)
		(stroke
			(width 0.254)
			(type default)
		)
		(layer "In6.Cu")
	)
	(gr_line
		(start 385.541266 -5.087112)
		(end 386.176266 -5.087112)
		(stroke
			(width 0.508)
			(type default)
		)
		(layer "In6.Cu")
	)
	(gr_line
		(start 385.541266 -2.978912)
		(end 386.176266 -2.978912)
		(stroke
			(width 0.254)
			(type default)
		)
		(layer "In6.Cu")
	)
	(gr_line
		(start 385.566666 -13.335)
		(end 386.201666 -13.335)
		(stroke
			(width 0.508)
			(type default)
		)
		(layer "In6.Cu")
	)
	(gr_line
		(start 385.566666 -9.134856)
		(end 386.201666 -9.134856)
		(stroke
			(width 0.508)
			(type default)
		)
		(layer "In6.Cu")
	)
	(gr_line
		(start 385.566666 -4.934712)
		(end 386.201666 -4.934712)
		(stroke
			(width 0.508)
			(type default)
		)
		(layer "In6.Cu")
	)
	(gr_line
		(start 385.592066 -13.6144)
		(end 386.227066 -13.6144)
		(stroke
			(width 0.508)
			(type default)
		)
		(layer "In6.Cu")
	)
	(gr_line
		(start 385.592066 -11.2014)
		(end 386.430266 -11.2014)
		(stroke
			(width 0.2032)
			(type default)
		)
		(layer "In6.Cu")
	)
	(gr_line
		(start 385.592066 -9.414256)
		(end 386.227066 -9.414256)
		(stroke
			(width 0.508)
			(type default)
		)
		(layer "In6.Cu")
	)
	(gr_line
		(start 385.592066 -7.001256)
		(end 386.430266 -7.001256)
		(stroke
			(width 0.2032)
			(type default)
		)
		(layer "In6.Cu")
	)
	(gr_line
		(start 385.592066 -5.214112)
		(end 386.227066 -5.214112)
		(stroke
			(width 0.508)
			(type default)
		)
		(layer "In6.Cu")
	)
	(gr_line
		(start 385.592066 -2.801112)
		(end 386.430266 -2.801112)
		(stroke
			(width 0.2032)
			(type default)
		)
		(layer "In6.Cu")
	)
	(gr_line
		(start 385.617466 -13.6144)
		(end 385.617466 -11.43)
		(stroke
			(width 0.254)
			(type default)
		)
		(layer "In6.Cu")
	)
	(gr_line
		(start 385.617466 -11.43)
		(end 386.100066 -11.43)
		(stroke
			(width 0.254)
			(type default)
		)
		(layer "In6.Cu")
	)
	(gr_line
		(start 385.617466 -11.2522)
		(end 386.354066 -11.2522)
		(stroke
			(width 0.254)
			(type default)
		)
		(layer "In6.Cu")
	)
	(gr_line
		(start 385.617466 -9.414256)
		(end 385.617466 -7.229856)
		(stroke
			(width 0.254)
			(type default)
		)
		(layer "In6.Cu")
	)
	(gr_line
		(start 385.617466 -7.229856)
		(end 386.100066 -7.229856)
		(stroke
			(width 0.254)
			(type default)
		)
		(layer "In6.Cu")
	)
	(gr_line
		(start 385.617466 -7.052056)
		(end 386.354066 -7.052056)
		(stroke
			(width 0.254)
			(type default)
		)
		(layer "In6.Cu")
	)
	(gr_line
		(start 385.617466 -5.214112)
		(end 385.617466 -3.029712)
		(stroke
			(width 0.254)
			(type default)
		)
		(layer "In6.Cu")
	)
	(gr_line
		(start 385.617466 -3.029712)
		(end 386.100066 -3.029712)
		(stroke
			(width 0.254)
			(type default)
		)
		(layer "In6.Cu")
	)
	(gr_line
		(start 385.617466 -2.851912)
		(end 386.354066 -2.851912)
		(stroke
			(width 0.254)
			(type default)
		)
		(layer "In6.Cu")
	)
	(gr_line
		(start 385.636008 -11.36523)
		(end 386.271008 -11.36523)
		(stroke
			(width 0.508)
			(type default)
		)
		(layer "In6.Cu")
	)
	(gr_line
		(start 385.636008 -7.165086)
		(end 386.271008 -7.165086)
		(stroke
			(width 0.508)
			(type default)
		)
		(layer "In6.Cu")
	)
	(gr_line
		(start 385.636008 -2.964942)
		(end 386.271008 -2.964942)
		(stroke
			(width 0.508)
			(type default)
		)
		(layer "In6.Cu")
	)
	(gr_line
		(start 385.642866 -13.6144)
		(end 386.277866 -13.6144)
		(stroke
			(width 0.508)
			(type default)
		)
		(layer "In6.Cu")
	)
	(gr_line
		(start 385.642866 -13.4874)
		(end 385.642866 -11.5062)
		(stroke
			(width 0.762)
			(type default)
		)
		(layer "In6.Cu")
	)
	(gr_line
		(start 385.642866 -11.5062)
		(end 386.277866 -11.5062)
		(stroke
			(width 0.508)
			(type default)
		)
		(layer "In6.Cu")
	)
	(gr_line
		(start 385.642866 -9.414256)
		(end 386.277866 -9.414256)
		(stroke
			(width 0.508)
			(type default)
		)
		(layer "In6.Cu")
	)
	(gr_line
		(start 385.642866 -9.287256)
		(end 385.642866 -7.306056)
		(stroke
			(width 0.762)
			(type default)
		)
		(layer "In6.Cu")
	)
	(gr_line
		(start 385.642866 -7.306056)
		(end 386.277866 -7.306056)
		(stroke
			(width 0.508)
			(type default)
		)
		(layer "In6.Cu")
	)
	(gr_line
		(start 385.642866 -5.214112)
		(end 386.277866 -5.214112)
		(stroke
			(width 0.508)
			(type default)
		)
		(layer "In6.Cu")
	)
	(gr_line
		(start 385.642866 -5.087112)
		(end 385.642866 -3.105912)
		(stroke
			(width 0.762)
			(type default)
		)
		(layer "In6.Cu")
	)
	(gr_line
		(start 385.642866 -3.105912)
		(end 386.277866 -3.105912)
		(stroke
			(width 0.508)
			(type default)
		)
		(layer "In6.Cu")
	)
	(gr_line
		(start 385.693666 -13.5382)
		(end 385.693666 -11.5062)
		(stroke
			(width 0.254)
			(type default)
		)
		(layer "In6.Cu")
	)
	(gr_line
		(start 385.693666 -11.5062)
		(end 386.023866 -11.5062)
		(stroke
			(width 0.254)
			(type default)
		)
		(layer "In6.Cu")
	)
	(gr_line
		(start 385.693666 -9.338056)
		(end 385.693666 -7.306056)
		(stroke
			(width 0.254)
			(type default)
		)
		(layer "In6.Cu")
	)
	(gr_line
		(start 385.693666 -7.306056)
		(end 386.023866 -7.306056)
		(stroke
			(width 0.254)
			(type default)
		)
		(layer "In6.Cu")
	)
	(gr_line
		(start 385.693666 -5.137912)
		(end 385.693666 -3.105912)
		(stroke
			(width 0.254)
			(type default)
		)
		(layer "In6.Cu")
	)
	(gr_line
		(start 385.693666 -3.105912)
		(end 386.023866 -3.105912)
		(stroke
			(width 0.254)
			(type default)
		)
		(layer "In6.Cu")
	)
	(gr_line
		(start 385.795266 -13.462)
		(end 385.795266 -11.6586)
		(stroke
			(width 0.254)
			(type default)
		)
		(layer "In6.Cu")
	)
	(gr_line
		(start 385.795266 -13.462)
		(end 385.795266 -11.4808)
		(stroke
			(width 0.762)
			(type default)
		)
		(layer "In6.Cu")
	)
	(gr_line
		(start 385.795266 -11.6586)
		(end 385.896866 -11.6586)
		(stroke
			(width 0.254)
			(type default)
		)
		(layer "In6.Cu")
	)
	(gr_line
		(start 385.795266 -9.261856)
		(end 385.795266 -7.458456)
		(stroke
			(width 0.254)
			(type default)
		)
		(layer "In6.Cu")
	)
	(gr_line
		(start 385.795266 -9.261856)
		(end 385.795266 -7.280656)
		(stroke
			(width 0.762)
			(type default)
		)
		(layer "In6.Cu")
	)
	(gr_line
		(start 385.795266 -7.458456)
		(end 385.896866 -7.458456)
		(stroke
			(width 0.254)
			(type default)
		)
		(layer "In6.Cu")
	)
	(gr_line
		(start 385.795266 -5.061712)
		(end 385.795266 -3.258312)
		(stroke
			(width 0.254)
			(type default)
		)
		(layer "In6.Cu")
	)
	(gr_line
		(start 385.795266 -5.061712)
		(end 385.795266 -3.080512)
		(stroke
			(width 0.762)
			(type default)
		)
		(layer "In6.Cu")
	)
	(gr_line
		(start 385.795266 -3.258312)
		(end 385.896866 -3.258312)
		(stroke
			(width 0.254)
			(type default)
		)
		(layer "In6.Cu")
	)
	(gr_line
		(start 385.896866 -13.5636)
		(end 385.846066 -13.5636)
		(stroke
			(width 0.254)
			(type default)
		)
		(layer "In6.Cu")
	)
	(gr_line
		(start 385.896866 -11.6586)
		(end 385.896866 -13.5636)
		(stroke
			(width 0.254)
			(type default)
		)
		(layer "In6.Cu")
	)
	(gr_line
		(start 385.896866 -9.363456)
		(end 385.846066 -9.363456)
		(stroke
			(width 0.254)
			(type default)
		)
		(layer "In6.Cu")
	)
	(gr_line
		(start 385.896866 -7.458456)
		(end 385.896866 -9.363456)
		(stroke
			(width 0.254)
			(type default)
		)
		(layer "In6.Cu")
	)
	(gr_line
		(start 385.896866 -5.163312)
		(end 385.846066 -5.163312)
		(stroke
			(width 0.254)
			(type default)
		)
		(layer "In6.Cu")
	)
	(gr_line
		(start 385.896866 -3.258312)
		(end 385.896866 -5.163312)
		(stroke
			(width 0.254)
			(type default)
		)
		(layer "In6.Cu")
	)
	(gr_line
		(start 385.947666 -13.4874)
		(end 385.947666 -11.5062)
		(stroke
			(width 0.762)
			(type default)
		)
		(layer "In6.Cu")
	)
	(gr_line
		(start 385.947666 -9.287256)
		(end 385.947666 -7.306056)
		(stroke
			(width 0.762)
			(type default)
		)
		(layer "In6.Cu")
	)
	(gr_line
		(start 385.947666 -5.087112)
		(end 385.947666 -3.105912)
		(stroke
			(width 0.762)
			(type default)
		)
		(layer "In6.Cu")
	)
	(gr_line
		(start 386.023866 -13.462)
		(end 385.795266 -13.462)
		(stroke
			(width 0.254)
			(type default)
		)
		(layer "In6.Cu")
	)
	(gr_line
		(start 386.023866 -11.5062)
		(end 386.023866 -13.462)
		(stroke
			(width 0.254)
			(type default)
		)
		(layer "In6.Cu")
	)
	(gr_line
		(start 386.023866 -9.261856)
		(end 385.795266 -9.261856)
		(stroke
			(width 0.254)
			(type default)
		)
		(layer "In6.Cu")
	)
	(gr_line
		(start 386.023866 -7.306056)
		(end 386.023866 -9.261856)
		(stroke
			(width 0.254)
			(type default)
		)
		(layer "In6.Cu")
	)
	(gr_line
		(start 386.023866 -5.061712)
		(end 385.795266 -5.061712)
		(stroke
			(width 0.254)
			(type default)
		)
		(layer "In6.Cu")
	)
	(gr_line
		(start 386.023866 -3.105912)
		(end 386.023866 -5.061712)
		(stroke
			(width 0.254)
			(type default)
		)
		(layer "In6.Cu")
	)
	(gr_line
		(start 386.074666 -13.8176)
		(end 386.074666 -13.7668)
		(stroke
			(width 0.1016)
			(type default)
		)
		(layer "In6.Cu")
	)
	(gr_line
		(start 386.074666 -13.8176)
		(end 386.481066 -13.8176)
		(stroke
			(width 0.1016)
			(type default)
		)
		(layer "In6.Cu")
	)
	(gr_line
		(start 386.074666 -13.7668)
		(end 385.312666 -13.7668)
		(stroke
			(width 0.1016)
			(type default)
		)
		(layer "In6.Cu")
	)
	(gr_line
		(start 386.074666 -13.4874)
		(end 386.074666 -11.5062)
		(stroke
			(width 0.762)
			(type default)
		)
		(layer "In6.Cu")
	)
	(gr_line
		(start 386.074666 -9.617456)
		(end 386.074666 -9.566656)
		(stroke
			(width 0.1016)
			(type default)
		)
		(layer "In6.Cu")
	)
	(gr_line
		(start 386.074666 -9.617456)
		(end 386.481066 -9.617456)
		(stroke
			(width 0.1016)
			(type default)
		)
		(layer "In6.Cu")
	)
	(gr_line
		(start 386.074666 -9.566656)
		(end 385.312666 -9.566656)
		(stroke
			(width 0.1016)
			(type default)
		)
		(layer "In6.Cu")
	)
	(gr_line
		(start 386.074666 -9.287256)
		(end 386.074666 -7.306056)
		(stroke
			(width 0.762)
			(type default)
		)
		(layer "In6.Cu")
	)
	(gr_line
		(start 386.074666 -5.417312)
		(end 386.074666 -5.366512)
		(stroke
			(width 0.1016)
			(type default)
		)
		(layer "In6.Cu")
	)
	(gr_line
		(start 386.074666 -5.417312)
		(end 386.481066 -5.417312)
		(stroke
			(width 0.1016)
			(type default)
		)
		(layer "In6.Cu")
	)
	(gr_line
		(start 386.074666 -5.366512)
		(end 385.312666 -5.366512)
		(stroke
			(width 0.1016)
			(type default)
		)
		(layer "In6.Cu")
	)
	(gr_line
		(start 386.074666 -5.087112)
		(end 386.074666 -3.105912)
		(stroke
			(width 0.762)
			(type default)
		)
		(layer "In6.Cu")
	)
	(gr_line
		(start 386.100066 -13.5382)
		(end 385.693666 -13.5382)
		(stroke
			(width 0.254)
			(type default)
		)
		(layer "In6.Cu")
	)
	(gr_line
		(start 386.100066 -11.43)
		(end 386.100066 -13.5382)
		(stroke
			(width 0.254)
			(type default)
		)
		(layer "In6.Cu")
	)
	(gr_line
		(start 386.100066 -9.338056)
		(end 385.693666 -9.338056)
		(stroke
			(width 0.254)
			(type default)
		)
		(layer "In6.Cu")
	)
	(gr_line
		(start 386.100066 -7.229856)
		(end 386.100066 -9.338056)
		(stroke
			(width 0.254)
			(type default)
		)
		(layer "In6.Cu")
	)
	(gr_line
		(start 386.100066 -5.137912)
		(end 385.693666 -5.137912)
		(stroke
			(width 0.254)
			(type default)
		)
		(layer "In6.Cu")
	)
	(gr_line
		(start 386.100066 -3.029712)
		(end 386.100066 -5.137912)
		(stroke
			(width 0.254)
			(type default)
		)
		(layer "In6.Cu")
	)
	(gr_line
		(start 386.150866 -13.4874)
		(end 386.150866 -11.5062)
		(stroke
			(width 0.762)
			(type default)
		)
		(layer "In6.Cu")
	)
	(gr_line
		(start 386.150866 -9.287256)
		(end 386.150866 -7.306056)
		(stroke
			(width 0.762)
			(type default)
		)
		(layer "In6.Cu")
	)
	(gr_line
		(start 386.150866 -5.087112)
		(end 386.150866 -3.105912)
		(stroke
			(width 0.762)
			(type default)
		)
		(layer "In6.Cu")
	)
	(gr_line
		(start 386.176266 -13.6144)
		(end 385.617466 -13.6144)
		(stroke
			(width 0.254)
			(type default)
		)
		(layer "In6.Cu")
	)
	(gr_line
		(start 386.176266 -11.3792)
		(end 386.176266 -13.6144)
		(stroke
			(width 0.254)
			(type default)
		)
		(layer "In6.Cu")
	)
	(gr_line
		(start 386.176266 -9.414256)
		(end 385.617466 -9.414256)
		(stroke
			(width 0.254)
			(type default)
		)
		(layer "In6.Cu")
	)
	(gr_line
		(start 386.176266 -7.179056)
		(end 386.176266 -9.414256)
		(stroke
			(width 0.254)
			(type default)
		)
		(layer "In6.Cu")
	)
	(gr_line
		(start 386.176266 -5.214112)
		(end 385.617466 -5.214112)
		(stroke
			(width 0.254)
			(type default)
		)
		(layer "In6.Cu")
	)
	(gr_line
		(start 386.176266 -2.978912)
		(end 386.176266 -5.214112)
		(stroke
			(width 0.254)
			(type default)
		)
		(layer "In6.Cu")
	)
	(gr_line
		(start 386.252466 -13.6398)
		(end 385.541266 -13.6398)
		(stroke
			(width 0.254)
			(type default)
		)
		(layer "In6.Cu")
	)
	(gr_line
		(start 386.252466 -11.303)
		(end 386.252466 -13.6398)
		(stroke
			(width 0.254)
			(type default)
		)
		(layer "In6.Cu")
	)
	(gr_line
		(start 386.252466 -9.439656)
		(end 385.541266 -9.439656)
		(stroke
			(width 0.254)
			(type default)
		)
		(layer "In6.Cu")
	)
	(gr_line
		(start 386.252466 -7.102856)
		(end 386.252466 -9.439656)
		(stroke
			(width 0.254)
			(type default)
		)
		(layer "In6.Cu")
	)
	(gr_line
		(start 386.252466 -5.239512)
		(end 385.541266 -5.239512)
		(stroke
			(width 0.254)
			(type default)
		)
		(layer "In6.Cu")
	)
	(gr_line
		(start 386.252466 -2.902712)
		(end 386.252466 -5.239512)
		(stroke
			(width 0.254)
			(type default)
		)
		(layer "In6.Cu")
	)
	(gr_line
		(start 386.277866 -13.7668)
		(end 385.287266 -13.7668)
		(stroke
			(width 0.1016)
			(type default)
		)
		(layer "In6.Cu")
	)
	(gr_line
		(start 386.277866 -13.6906)
		(end 385.465066 -13.6906)
		(stroke
			(width 0.254)
			(type default)
		)
		(layer "In6.Cu")
	)
	(gr_line
		(start 386.277866 -11.2776)
		(end 386.277866 -13.6906)
		(stroke
			(width 0.254)
			(type default)
		)
		(layer "In6.Cu")
	)
	(gr_line
		(start 386.277866 -9.566656)
		(end 385.287266 -9.566656)
		(stroke
			(width 0.1016)
			(type default)
		)
		(layer "In6.Cu")
	)
	(gr_line
		(start 386.277866 -9.490456)
		(end 385.465066 -9.490456)
		(stroke
			(width 0.254)
			(type default)
		)
		(layer "In6.Cu")
	)
	(gr_line
		(start 386.277866 -7.077456)
		(end 386.277866 -9.490456)
		(stroke
			(width 0.254)
			(type default)
		)
		(layer "In6.Cu")
	)
	(gr_line
		(start 386.277866 -5.366512)
		(end 385.287266 -5.366512)
		(stroke
			(width 0.1016)
			(type default)
		)
		(layer "In6.Cu")
	)
	(gr_line
		(start 386.277866 -5.290312)
		(end 385.465066 -5.290312)
		(stroke
			(width 0.254)
			(type default)
		)
		(layer "In6.Cu")
	)
	(gr_line
		(start 386.277866 -2.877312)
		(end 386.277866 -5.290312)
		(stroke
			(width 0.254)
			(type default)
		)
		(layer "In6.Cu")
	)
	(gr_line
		(start 386.303266 -13.716)
		(end 385.439666 -13.716)
		(stroke
			(width 0.254)
			(type default)
		)
		(layer "In6.Cu")
	)
	(gr_line
		(start 386.303266 -11.2522)
		(end 386.303266 -13.716)
		(stroke
			(width 0.254)
			(type default)
		)
		(layer "In6.Cu")
	)
	(gr_line
		(start 386.303266 -9.515856)
		(end 385.439666 -9.515856)
		(stroke
			(width 0.254)
			(type default)
		)
		(layer "In6.Cu")
	)
	(gr_line
		(start 386.303266 -7.052056)
		(end 386.303266 -9.515856)
		(stroke
			(width 0.254)
			(type default)
		)
		(layer "In6.Cu")
	)
	(gr_line
		(start 386.303266 -5.315712)
		(end 385.439666 -5.315712)
		(stroke
			(width 0.254)
			(type default)
		)
		(layer "In6.Cu")
	)
	(gr_line
		(start 386.303266 -2.851912)
		(end 386.303266 -5.315712)
		(stroke
			(width 0.254)
			(type default)
		)
		(layer "In6.Cu")
	)
	(gr_line
		(start 386.354066 -13.7414)
		(end 385.414266 -13.7414)
		(stroke
			(width 0.254)
			(type default)
		)
		(layer "In6.Cu")
	)
	(gr_line
		(start 386.354066 -11.2522)
		(end 386.354066 -13.7414)
		(stroke
			(width 0.254)
			(type default)
		)
		(layer "In6.Cu")
	)
	(gr_line
		(start 386.354066 -9.541256)
		(end 385.414266 -9.541256)
		(stroke
			(width 0.254)
			(type default)
		)
		(layer "In6.Cu")
	)
	(gr_line
		(start 386.354066 -7.052056)
		(end 386.354066 -9.541256)
		(stroke
			(width 0.254)
			(type default)
		)
		(layer "In6.Cu")
	)
	(gr_line
		(start 386.354066 -5.341112)
		(end 385.414266 -5.341112)
		(stroke
			(width 0.254)
			(type default)
		)
		(layer "In6.Cu")
	)
	(gr_line
		(start 386.354066 -2.851912)
		(end 386.354066 -5.341112)
		(stroke
			(width 0.254)
			(type default)
		)
		(layer "In6.Cu")
	)
	(gr_line
		(start 386.379466 -13.7414)
		(end 385.414266 -13.7414)
		(stroke
			(width 0.2032)
			(type default)
		)
		(layer "In6.Cu")
	)
	(gr_line
		(start 386.379466 -11.2014)
		(end 386.379466 -13.7414)
		(stroke
			(width 0.2032)
			(type default)
		)
		(layer "In6.Cu")
	)
	(gr_line
		(start 386.379466 -9.541256)
		(end 385.414266 -9.541256)
		(stroke
			(width 0.2032)
			(type default)
		)
		(layer "In6.Cu")
	)
	(gr_line
		(start 386.379466 -7.001256)
		(end 386.379466 -9.541256)
		(stroke
			(width 0.2032)
			(type default)
		)
		(layer "In6.Cu")
	)
	(gr_line
		(start 386.379466 -5.341112)
		(end 385.414266 -5.341112)
		(stroke
			(width 0.2032)
			(type default)
		)
		(layer "In6.Cu")
	)
	(gr_line
		(start 386.379466 -2.801112)
		(end 386.379466 -5.341112)
		(stroke
			(width 0.2032)
			(type default)
		)
		(layer "In6.Cu")
	)
	(gr_line
		(start 386.430266 -13.7668)
		(end 385.363466 -13.7668)
		(stroke
			(width 0.2032)
			(type default)
		)
		(layer "In6.Cu")
	)
	(gr_line
		(start 386.430266 -11.2014)
		(end 386.430266 -13.7668)
		(stroke
			(width 0.2032)
			(type default)
		)
		(layer "In6.Cu")
	)
	(gr_line
		(start 386.430266 -9.566656)
		(end 385.363466 -9.566656)
		(stroke
			(width 0.2032)
			(type default)
		)
		(layer "In6.Cu")
	)
	(gr_line
		(start 386.430266 -7.001256)
		(end 386.430266 -9.566656)
		(stroke
			(width 0.2032)
			(type default)
		)
		(layer "In6.Cu")
	)
	(gr_line
		(start 386.430266 -5.366512)
		(end 385.363466 -5.366512)
		(stroke
			(width 0.2032)
			(type default)
		)
		(layer "In6.Cu")
	)
	(gr_line
		(start 386.430266 -2.801112)
		(end 386.430266 -5.366512)
		(stroke
			(width 0.2032)
			(type default)
		)
		(layer "In6.Cu")
	)
	(gr_line
		(start 386.455666 -13.7668)
		(end 385.338066 -13.7668)
		(stroke
			(width 0.1016)
			(type default)
		)
		(layer "In6.Cu")
	)
	(gr_line
		(start 386.455666 -11.176)
		(end 386.455666 -13.7668)
		(stroke
			(width 0.1016)
			(type default)
		)
		(layer "In6.Cu")
	)
	(gr_line
		(start 386.455666 -9.566656)
		(end 385.338066 -9.566656)
		(stroke
			(width 0.1016)
			(type default)
		)
		(layer "In6.Cu")
	)
	(gr_line
		(start 386.455666 -6.975856)
		(end 386.455666 -9.566656)
		(stroke
			(width 0.1016)
			(type default)
		)
		(layer "In6.Cu")
	)
	(gr_line
		(start 386.455666 -5.366512)
		(end 385.338066 -5.366512)
		(stroke
			(width 0.1016)
			(type default)
		)
		(layer "In6.Cu")
	)
	(gr_line
		(start 386.455666 -2.775712)
		(end 386.455666 -5.366512)
		(stroke
			(width 0.1016)
			(type default)
		)
		(layer "In6.Cu")
	)
	(gr_line
		(start 386.481066 -13.8176)
		(end 386.074666 -13.8176)
		(stroke
			(width 0.1016)
			(type default)
		)
		(layer "In6.Cu")
	)
	(gr_line
		(start 386.481066 -13.8176)
		(end 386.481066 -11.1506)
		(stroke
			(width 0.1016)
			(type default)
		)
		(layer "In6.Cu")
	)
	(gr_line
		(start 386.481066 -11.1506)
		(end 385.287266 -11.1506)
		(stroke
			(width 0.1016)
			(type default)
		)
		(layer "In6.Cu")
	)
	(gr_line
		(start 386.481066 -11.1506)
		(end 386.481066 -13.8176)
		(stroke
			(width 0.1016)
			(type default)
		)
		(layer "In6.Cu")
	)
	(gr_line
		(start 386.481066 -9.617456)
		(end 386.074666 -9.617456)
		(stroke
			(width 0.1016)
			(type default)
		)
		(layer "In6.Cu")
	)
	(gr_line
		(start 386.481066 -9.617456)
		(end 386.481066 -6.950456)
		(stroke
			(width 0.1016)
			(type default)
		)
		(layer "In6.Cu")
	)
	(gr_line
		(start 386.481066 -6.950456)
		(end 385.287266 -6.950456)
		(stroke
			(width 0.1016)
			(type default)
		)
		(layer "In6.Cu")
	)
	(gr_line
		(start 386.481066 -6.950456)
		(end 386.481066 -9.617456)
		(stroke
			(width 0.1016)
			(type default)
		)
		(layer "In6.Cu")
	)
	(gr_line
		(start 386.481066 -5.417312)
		(end 386.074666 -5.417312)
		(stroke
			(width 0.1016)
			(type default)
		)
		(layer "In6.Cu")
	)
	(gr_line
		(start 386.481066 -5.417312)
		(end 386.481066 -2.750312)
		(stroke
			(width 0.1016)
			(type default)
		)
		(layer "In6.Cu")
	)
	(gr_line
		(start 386.481066 -2.750312)
		(end 385.287266 -2.750312)
		(stroke
			(width 0.1016)
			(type default)
		)
		(layer "In6.Cu")
	)
	(gr_line
		(start 386.481066 -2.750312)
		(end 386.481066 -5.417312)
		(stroke
			(width 0.1016)
			(type default)
		)
		(layer "In6.Cu")
	)
	(gr_line
		(start 387.217666 -24.6634)
		(end 387.217666 -23.3934)
		(stroke
			(width 0.7874)
			(type default)
		)
		(layer "In6.Cu")
	)
	(gr_line
		(start 387.287262 -12.563348)
		(end 388.074662 -12.563348)
		(stroke
			(width 0.1016)
			(type default)
		)
		(layer "In6.Cu")
	)
	(gr_line
		(start 387.287262 -12.512548)
		(end 387.287262 -9.896348)
		(stroke
			(width 0.1016)
			(type default)
		)
		(layer "In6.Cu")
	)
	(gr_line
		(start 387.287262 -12.463272)
		(end 388.074662 -12.463272)
		(stroke
			(width 0.1016)
			(type default)
		)
		(layer "In6.Cu")
	)
	(gr_line
		(start 387.287262 -12.412472)
		(end 387.287262 -9.796272)
		(stroke
			(width 0.1016)
			(type default)
		)
		(layer "In6.Cu")
	)
	(gr_line
		(start 387.287262 -9.896348)
		(end 387.287262 -12.563348)
		(stroke
			(width 0.1016)
			(type default)
		)
		(layer "In6.Cu")
	)
	(gr_line
		(start 387.287262 -9.896348)
		(end 388.481062 -9.896348)
		(stroke
			(width 0.1016)
			(type default)
		)
		(layer "In6.Cu")
	)
	(gr_line
		(start 387.287262 -9.796272)
		(end 387.287262 -12.463272)
		(stroke
			(width 0.1016)
			(type default)
		)
		(layer "In6.Cu")
	)
	(gr_line
		(start 387.287262 -9.796272)
		(end 388.481062 -9.796272)
		(stroke
			(width 0.1016)
			(type default)
		)
		(layer "In6.Cu")
	)
	(gr_line
		(start 387.287262 -8.363204)
		(end 388.074662 -8.363204)
		(stroke
			(width 0.1016)
			(type default)
		)
		(layer "In6.Cu")
	)
	(gr_line
		(start 387.287262 -8.312404)
		(end 387.287262 -5.696204)
		(stroke
			(width 0.1016)
			(type default)
		)
		(layer "In6.Cu")
	)
	(gr_line
		(start 387.287262 -8.263128)
		(end 388.074662 -8.263128)
		(stroke
			(width 0.1016)
			(type default)
		)
		(layer "In6.Cu")
	)
	(gr_line
		(start 387.287262 -8.212328)
		(end 387.287262 -5.596128)
		(stroke
			(width 0.1016)
			(type default)
		)
		(layer "In6.Cu")
	)
	(gr_line
		(start 387.287262 -5.696204)
		(end 387.287262 -8.363204)
		(stroke
			(width 0.1016)
			(type default)
		)
		(layer "In6.Cu")
	)
	(gr_line
		(start 387.287262 -5.696204)
		(end 388.481062 -5.696204)
		(stroke
			(width 0.1016)
			(type default)
		)
		(layer "In6.Cu")
	)
	(gr_line
		(start 387.287262 -5.596128)
		(end 387.287262 -8.263128)
		(stroke
			(width 0.1016)
			(type default)
		)
		(layer "In6.Cu")
	)
	(gr_line
		(start 387.287262 -5.596128)
		(end 388.481062 -5.596128)
		(stroke
			(width 0.1016)
			(type default)
		)
		(layer "In6.Cu")
	)
	(gr_line
		(start 387.287262 -4.16306)
		(end 388.074662 -4.16306)
		(stroke
			(width 0.1016)
			(type default)
		)
		(layer "In6.Cu")
	)
	(gr_line
		(start 387.287262 -4.11226)
		(end 387.287262 -1.49606)
		(stroke
			(width 0.1016)
			(type default)
		)
		(layer "In6.Cu")
	)
	(gr_line
		(start 387.287262 -4.062984)
		(end 388.074662 -4.062984)
		(stroke
			(width 0.1016)
			(type default)
		)
		(layer "In6.Cu")
	)
	(gr_line
		(start 387.287262 -4.012184)
		(end 387.287262 -1.395984)
		(stroke
			(width 0.1016)
			(type default)
		)
		(layer "In6.Cu")
	)
	(gr_line
		(start 387.287262 -1.49606)
		(end 387.287262 -4.16306)
		(stroke
			(width 0.1016)
			(type default)
		)
		(layer "In6.Cu")
	)
	(gr_line
		(start 387.287262 -1.49606)
		(end 388.481062 -1.49606)
		(stroke
			(width 0.1016)
			(type default)
		)
		(layer "In6.Cu")
	)
	(gr_line
		(start 387.287262 -1.395984)
		(end 387.287262 -4.062984)
		(stroke
			(width 0.1016)
			(type default)
		)
		(layer "In6.Cu")
	)
	(gr_line
		(start 387.287262 -1.395984)
		(end 388.481062 -1.395984)
		(stroke
			(width 0.1016)
			(type default)
		)
		(layer "In6.Cu")
	)
	(gr_line
		(start 387.312662 -12.512548)
		(end 387.312662 -9.921748)
		(stroke
			(width 0.1016)
			(type default)
		)
		(layer "In6.Cu")
	)
	(gr_line
		(start 387.312662 -12.412472)
		(end 387.312662 -9.821672)
		(stroke
			(width 0.1016)
			(type default)
		)
		(layer "In6.Cu")
	)
	(gr_line
		(start 387.312662 -9.921748)
		(end 388.455662 -9.921748)
		(stroke
			(width 0.1016)
			(type default)
		)
		(layer "In6.Cu")
	)
	(gr_line
		(start 387.312662 -9.821672)
		(end 388.455662 -9.821672)
		(stroke
			(width 0.1016)
			(type default)
		)
		(layer "In6.Cu")
	)
	(gr_line
		(start 387.312662 -8.312404)
		(end 387.312662 -5.721604)
		(stroke
			(width 0.1016)
			(type default)
		)
		(layer "In6.Cu")
	)
	(gr_line
		(start 387.312662 -8.212328)
		(end 387.312662 -5.621528)
		(stroke
			(width 0.1016)
			(type default)
		)
		(layer "In6.Cu")
	)
	(gr_line
		(start 387.312662 -5.721604)
		(end 388.455662 -5.721604)
		(stroke
			(width 0.1016)
			(type default)
		)
		(layer "In6.Cu")
	)
	(gr_line
		(start 387.312662 -5.621528)
		(end 388.455662 -5.621528)
		(stroke
			(width 0.1016)
			(type default)
		)
		(layer "In6.Cu")
	)
	(gr_line
		(start 387.312662 -4.11226)
		(end 387.312662 -1.52146)
		(stroke
			(width 0.1016)
			(type default)
		)
		(layer "In6.Cu")
	)
	(gr_line
		(start 387.312662 -4.012184)
		(end 387.312662 -1.421384)
		(stroke
			(width 0.1016)
			(type default)
		)
		(layer "In6.Cu")
	)
	(gr_line
		(start 387.312662 -1.52146)
		(end 388.455662 -1.52146)
		(stroke
			(width 0.1016)
			(type default)
		)
		(layer "In6.Cu")
	)
	(gr_line
		(start 387.312662 -1.421384)
		(end 388.455662 -1.421384)
		(stroke
			(width 0.1016)
			(type default)
		)
		(layer "In6.Cu")
	)
	(gr_line
		(start 387.338062 -12.512548)
		(end 387.338062 -9.947148)
		(stroke
			(width 0.1016)
			(type default)
		)
		(layer "In6.Cu")
	)
	(gr_line
		(start 387.338062 -12.412472)
		(end 387.338062 -9.847072)
		(stroke
			(width 0.1016)
			(type default)
		)
		(layer "In6.Cu")
	)
	(gr_line
		(start 387.338062 -9.947148)
		(end 387.592062 -9.947148)
		(stroke
			(width 0.1016)
			(type default)
		)
		(layer "In6.Cu")
	)
	(gr_line
		(start 387.338062 -9.847072)
		(end 387.592062 -9.847072)
		(stroke
			(width 0.1016)
			(type default)
		)
		(layer "In6.Cu")
	)
	(gr_line
		(start 387.338062 -8.312404)
		(end 387.338062 -5.747004)
		(stroke
			(width 0.1016)
			(type default)
		)
		(layer "In6.Cu")
	)
	(gr_line
		(start 387.338062 -8.212328)
		(end 387.338062 -5.646928)
		(stroke
			(width 0.1016)
			(type default)
		)
		(layer "In6.Cu")
	)
	(gr_line
		(start 387.338062 -5.747004)
		(end 387.592062 -5.747004)
		(stroke
			(width 0.1016)
			(type default)
		)
		(layer "In6.Cu")
	)
	(gr_line
		(start 387.338062 -5.646928)
		(end 387.592062 -5.646928)
		(stroke
			(width 0.1016)
			(type default)
		)
		(layer "In6.Cu")
	)
	(gr_line
		(start 387.338062 -4.11226)
		(end 387.338062 -1.54686)
		(stroke
			(width 0.1016)
			(type default)
		)
		(layer "In6.Cu")
	)
	(gr_line
		(start 387.338062 -4.012184)
		(end 387.338062 -1.446784)
		(stroke
			(width 0.1016)
			(type default)
		)
		(layer "In6.Cu")
	)
	(gr_line
		(start 387.338062 -1.54686)
		(end 387.592062 -1.54686)
		(stroke
			(width 0.1016)
			(type default)
		)
		(layer "In6.Cu")
	)
	(gr_line
		(start 387.338062 -1.446784)
		(end 387.592062 -1.446784)
		(stroke
			(width 0.1016)
			(type default)
		)
		(layer "In6.Cu")
	)
	(gr_line
		(start 387.363462 -12.512548)
		(end 387.363462 -9.947148)
		(stroke
			(width 0.2032)
			(type default)
		)
		(layer "In6.Cu")
	)
	(gr_line
		(start 387.363462 -12.412472)
		(end 387.363462 -9.847072)
		(stroke
			(width 0.2032)
			(type default)
		)
		(layer "In6.Cu")
	)
	(gr_line
		(start 387.363462 -9.947148)
		(end 388.379462 -9.947148)
		(stroke
			(width 0.2032)
			(type default)
		)
		(layer "In6.Cu")
	)
	(gr_line
		(start 387.363462 -9.847072)
		(end 388.379462 -9.847072)
		(stroke
			(width 0.2032)
			(type default)
		)
		(layer "In6.Cu")
	)
	(gr_line
		(start 387.363462 -8.312404)
		(end 387.363462 -5.747004)
		(stroke
			(width 0.2032)
			(type default)
		)
		(layer "In6.Cu")
	)
	(gr_line
		(start 387.363462 -8.212328)
		(end 387.363462 -5.646928)
		(stroke
			(width 0.2032)
			(type default)
		)
		(layer "In6.Cu")
	)
	(gr_line
		(start 387.363462 -5.747004)
		(end 388.379462 -5.747004)
		(stroke
			(width 0.2032)
			(type default)
		)
		(layer "In6.Cu")
	)
	(gr_line
		(start 387.363462 -5.646928)
		(end 388.379462 -5.646928)
		(stroke
			(width 0.2032)
			(type default)
		)
		(layer "In6.Cu")
	)
	(gr_line
		(start 387.363462 -4.11226)
		(end 387.363462 -1.54686)
		(stroke
			(width 0.2032)
			(type default)
		)
		(layer "In6.Cu")
	)
	(gr_line
		(start 387.363462 -4.012184)
		(end 387.363462 -1.446784)
		(stroke
			(width 0.2032)
			(type default)
		)
		(layer "In6.Cu")
	)
	(gr_line
		(start 387.363462 -1.54686)
		(end 388.379462 -1.54686)
		(stroke
			(width 0.2032)
			(type default)
		)
		(layer "In6.Cu")
	)
	(gr_line
		(start 387.363462 -1.446784)
		(end 388.379462 -1.446784)
		(stroke
			(width 0.2032)
			(type default)
		)
		(layer "In6.Cu")
	)
	(gr_line
		(start 387.414262 -12.487148)
		(end 387.414262 -9.997948)
		(stroke
			(width 0.2032)
			(type default)
		)
		(layer "In6.Cu")
	)
	(gr_line
		(start 387.414262 -12.487148)
		(end 387.414262 -9.997948)
		(stroke
			(width 0.254)
			(type default)
		)
		(layer "In6.Cu")
	)
	(gr_line
		(start 387.414262 -12.387072)
		(end 387.414262 -9.897872)
		(stroke
			(width 0.2032)
			(type default)
		)
		(layer "In6.Cu")
	)
	(gr_line
		(start 387.414262 -12.387072)
		(end 387.414262 -9.897872)
		(stroke
			(width 0.254)
			(type default)
		)
		(layer "In6.Cu")
	)
	(gr_line
		(start 387.414262 -9.997948)
		(end 387.617462 -9.997948)
		(stroke
			(width 0.2032)
			(type default)
		)
		(layer "In6.Cu")
	)
	(gr_line
		(start 387.414262 -9.997948)
		(end 388.303262 -9.997948)
		(stroke
			(width 0.254)
			(type default)
		)
		(layer "In6.Cu")
	)
	(gr_line
		(start 387.414262 -9.897872)
		(end 387.617462 -9.897872)
		(stroke
			(width 0.2032)
			(type default)
		)
		(layer "In6.Cu")
	)
	(gr_line
		(start 387.414262 -9.897872)
		(end 388.303262 -9.897872)
		(stroke
			(width 0.254)
			(type default)
		)
		(layer "In6.Cu")
	)
	(gr_line
		(start 387.414262 -8.287004)
		(end 387.414262 -5.797804)
		(stroke
			(width 0.2032)
			(type default)
		)
		(layer "In6.Cu")
	)
	(gr_line
		(start 387.414262 -8.287004)
		(end 387.414262 -5.797804)
		(stroke
			(width 0.254)
			(type default)
		)
		(layer "In6.Cu")
	)
	(gr_line
		(start 387.414262 -8.186928)
		(end 387.414262 -5.697728)
		(stroke
			(width 0.2032)
			(type default)
		)
		(layer "In6.Cu")
	)
	(gr_line
		(start 387.414262 -8.186928)
		(end 387.414262 -5.697728)
		(stroke
			(width 0.254)
			(type default)
		)
		(layer "In6.Cu")
	)
	(gr_line
		(start 387.414262 -5.797804)
		(end 387.617462 -5.797804)
		(stroke
			(width 0.2032)
			(type default)
		)
		(layer "In6.Cu")
	)
	(gr_line
		(start 387.414262 -5.797804)
		(end 388.303262 -5.797804)
		(stroke
			(width 0.254)
			(type default)
		)
		(layer "In6.Cu")
	)
	(gr_line
		(start 387.414262 -5.697728)
		(end 387.617462 -5.697728)
		(stroke
			(width 0.2032)
			(type default)
		)
		(layer "In6.Cu")
	)
	(gr_line
		(start 387.414262 -5.697728)
		(end 388.303262 -5.697728)
		(stroke
			(width 0.254)
			(type default)
		)
		(layer "In6.Cu")
	)
	(gr_line
		(start 387.414262 -4.08686)
		(end 387.414262 -1.59766)
		(stroke
			(width 0.2032)
			(type default)
		)
		(layer "In6.Cu")
	)
	(gr_line
		(start 387.414262 -4.08686)
		(end 387.414262 -1.59766)
		(stroke
			(width 0.254)
			(type default)
		)
		(layer "In6.Cu")
	)
	(gr_line
		(start 387.414262 -3.986784)
		(end 387.414262 -1.497584)
		(stroke
			(width 0.2032)
			(type default)
		)
		(layer "In6.Cu")
	)
	(gr_line
		(start 387.414262 -3.986784)
		(end 387.414262 -1.497584)
		(stroke
			(width 0.254)
			(type default)
		)
		(layer "In6.Cu")
	)
	(gr_line
		(start 387.414262 -1.59766)
		(end 387.617462 -1.59766)
		(stroke
			(width 0.2032)
			(type default)
		)
		(layer "In6.Cu")
	)
	(gr_line
		(start 387.414262 -1.59766)
		(end 388.303262 -1.59766)
		(stroke
			(width 0.254)
			(type default)
		)
		(layer "In6.Cu")
	)
	(gr_line
		(start 387.414262 -1.497584)
		(end 387.617462 -1.497584)
		(stroke
			(width 0.2032)
			(type default)
		)
		(layer "In6.Cu")
	)
	(gr_line
		(start 387.414262 -1.497584)
		(end 388.303262 -1.497584)
		(stroke
			(width 0.254)
			(type default)
		)
		(layer "In6.Cu")
	)
	(gr_line
		(start 387.439662 -12.461748)
		(end 387.439662 -10.023348)
		(stroke
			(width 0.254)
			(type default)
		)
		(layer "In6.Cu")
	)
	(gr_line
		(start 387.439662 -12.361672)
		(end 387.439662 -9.923272)
		(stroke
			(width 0.254)
			(type default)
		)
		(layer "In6.Cu")
	)
	(gr_line
		(start 387.439662 -10.023348)
		(end 388.277862 -10.023348)
		(stroke
			(width 0.254)
			(type default)
		)
		(layer "In6.Cu")
	)
	(gr_line
		(start 387.439662 -9.923272)
		(end 388.277862 -9.923272)
		(stroke
			(width 0.254)
			(type default)
		)
		(layer "In6.Cu")
	)
	(gr_line
		(start 387.439662 -8.261604)
		(end 387.439662 -5.823204)
		(stroke
			(width 0.254)
			(type default)
		)
		(layer "In6.Cu")
	)
	(gr_line
		(start 387.439662 -8.161528)
		(end 387.439662 -5.723128)
		(stroke
			(width 0.254)
			(type default)
		)
		(layer "In6.Cu")
	)
	(gr_line
		(start 387.439662 -5.823204)
		(end 388.277862 -5.823204)
		(stroke
			(width 0.254)
			(type default)
		)
		(layer "In6.Cu")
	)
	(gr_line
		(start 387.439662 -5.723128)
		(end 388.277862 -5.723128)
		(stroke
			(width 0.254)
			(type default)
		)
		(layer "In6.Cu")
	)
	(gr_line
		(start 387.439662 -4.06146)
		(end 387.439662 -1.62306)
		(stroke
			(width 0.254)
			(type default)
		)
		(layer "In6.Cu")
	)
	(gr_line
		(start 387.439662 -3.961384)
		(end 387.439662 -1.522984)
		(stroke
			(width 0.254)
			(type default)
		)
		(layer "In6.Cu")
	)
	(gr_line
		(start 387.439662 -1.62306)
		(end 388.277862 -1.62306)
		(stroke
			(width 0.254)
			(type default)
		)
		(layer "In6.Cu")
	)
	(gr_line
		(start 387.439662 -1.522984)
		(end 388.277862 -1.522984)
		(stroke
			(width 0.254)
			(type default)
		)
		(layer "In6.Cu")
	)
	(gr_line
		(start 387.465062 -12.436348)
		(end 387.465062 -10.048748)
		(stroke
			(width 0.254)
			(type default)
		)
		(layer "In6.Cu")
	)
	(gr_line
		(start 387.465062 -12.336272)
		(end 387.465062 -9.948672)
		(stroke
			(width 0.254)
			(type default)
		)
		(layer "In6.Cu")
	)
	(gr_line
		(start 387.465062 -10.048748)
		(end 388.252462 -10.048748)
		(stroke
			(width 0.254)
			(type default)
		)
		(layer "In6.Cu")
	)
	(gr_line
		(start 387.465062 -9.948672)
		(end 388.252462 -9.948672)
		(stroke
			(width 0.254)
			(type default)
		)
		(layer "In6.Cu")
	)
	(gr_line
		(start 387.465062 -8.236204)
		(end 387.465062 -5.848604)
		(stroke
			(width 0.254)
			(type default)
		)
		(layer "In6.Cu")
	)
	(gr_line
		(start 387.465062 -8.136128)
		(end 387.465062 -5.748528)
		(stroke
			(width 0.254)
			(type default)
		)
		(layer "In6.Cu")
	)
	(gr_line
		(start 387.465062 -5.848604)
		(end 388.252462 -5.848604)
		(stroke
			(width 0.254)
			(type default)
		)
		(layer "In6.Cu")
	)
	(gr_line
		(start 387.465062 -5.748528)
		(end 388.252462 -5.748528)
		(stroke
			(width 0.254)
			(type default)
		)
		(layer "In6.Cu")
	)
	(gr_line
		(start 387.465062 -4.03606)
		(end 387.465062 -1.64846)
		(stroke
			(width 0.254)
			(type default)
		)
		(layer "In6.Cu")
	)
	(gr_line
		(start 387.465062 -3.935984)
		(end 387.465062 -1.548384)
		(stroke
			(width 0.254)
			(type default)
		)
		(layer "In6.Cu")
	)
	(gr_line
		(start 387.465062 -1.64846)
		(end 388.252462 -1.64846)
		(stroke
			(width 0.254)
			(type default)
		)
		(layer "In6.Cu")
	)
	(gr_line
		(start 387.465062 -1.548384)
		(end 388.252462 -1.548384)
		(stroke
			(width 0.254)
			(type default)
		)
		(layer "In6.Cu")
	)
	(gr_line
		(start 387.490462 -12.360148)
		(end 388.125462 -12.360148)
		(stroke
			(width 0.508)
			(type default)
		)
		(layer "In6.Cu")
	)
	(gr_line
		(start 387.490462 -12.260072)
		(end 388.125462 -12.260072)
		(stroke
			(width 0.508)
			(type default)
		)
		(layer "In6.Cu")
	)
	(gr_line
		(start 387.490462 -10.175748)
		(end 388.125462 -10.175748)
		(stroke
			(width 0.508)
			(type default)
		)
		(layer "In6.Cu")
	)
	(gr_line
		(start 387.490462 -10.124948)
		(end 388.125462 -10.124948)
		(stroke
			(width 0.508)
			(type default)
		)
		(layer "In6.Cu")
	)
	(gr_line
		(start 387.490462 -10.075672)
		(end 388.125462 -10.075672)
		(stroke
			(width 0.508)
			(type default)
		)
		(layer "In6.Cu")
	)
	(gr_line
		(start 387.490462 -10.024872)
		(end 388.125462 -10.024872)
		(stroke
			(width 0.508)
			(type default)
		)
		(layer "In6.Cu")
	)
	(gr_line
		(start 387.490462 -8.160004)
		(end 388.125462 -8.160004)
		(stroke
			(width 0.508)
			(type default)
		)
		(layer "In6.Cu")
	)
	(gr_line
		(start 387.490462 -8.059928)
		(end 388.125462 -8.059928)
		(stroke
			(width 0.508)
			(type default)
		)
		(layer "In6.Cu")
	)
	(gr_line
		(start 387.490462 -5.975604)
		(end 388.125462 -5.975604)
		(stroke
			(width 0.508)
			(type default)
		)
		(layer "In6.Cu")
	)
	(gr_line
		(start 387.490462 -5.924804)
		(end 388.125462 -5.924804)
		(stroke
			(width 0.508)
			(type default)
		)
		(layer "In6.Cu")
	)
	(gr_line
		(start 387.490462 -5.875528)
		(end 388.125462 -5.875528)
		(stroke
			(width 0.508)
			(type default)
		)
		(layer "In6.Cu")
	)
	(gr_line
		(start 387.490462 -5.824728)
		(end 388.125462 -5.824728)
		(stroke
			(width 0.508)
			(type default)
		)
		(layer "In6.Cu")
	)
	(gr_line
		(start 387.490462 -3.95986)
		(end 388.125462 -3.95986)
		(stroke
			(width 0.508)
			(type default)
		)
		(layer "In6.Cu")
	)
	(gr_line
		(start 387.490462 -3.859784)
		(end 388.125462 -3.859784)
		(stroke
			(width 0.508)
			(type default)
		)
		(layer "In6.Cu")
	)
	(gr_line
		(start 387.490462 -1.77546)
		(end 388.125462 -1.77546)
		(stroke
			(width 0.508)
			(type default)
		)
		(layer "In6.Cu")
	)
	(gr_line
		(start 387.490462 -1.72466)
		(end 388.125462 -1.72466)
		(stroke
			(width 0.508)
			(type default)
		)
		(layer "In6.Cu")
	)
	(gr_line
		(start 387.490462 -1.675384)
		(end 388.125462 -1.675384)
		(stroke
			(width 0.508)
			(type default)
		)
		(layer "In6.Cu")
	)
	(gr_line
		(start 387.490462 -1.624584)
		(end 388.125462 -1.624584)
		(stroke
			(width 0.508)
			(type default)
		)
		(layer "In6.Cu")
	)
	(gr_line
		(start 387.515862 -10.429748)
		(end 388.150862 -10.429748)
		(stroke
			(width 0.508)
			(type default)
		)
		(layer "In6.Cu")
	)
	(gr_line
		(start 387.515862 -10.329672)
		(end 388.150862 -10.329672)
		(stroke
			(width 0.508)
			(type default)
		)
		(layer "In6.Cu")
	)
	(gr_line
		(start 387.515862 -6.229604)
		(end 388.150862 -6.229604)
		(stroke
			(width 0.508)
			(type default)
		)
		(layer "In6.Cu")
	)
	(gr_line
		(start 387.515862 -6.129528)
		(end 388.150862 -6.129528)
		(stroke
			(width 0.508)
			(type default)
		)
		(layer "In6.Cu")
	)
	(gr_line
		(start 387.515862 -2.02946)
		(end 388.150862 -2.02946)
		(stroke
			(width 0.508)
			(type default)
		)
		(layer "In6.Cu")
	)
	(gr_line
		(start 387.515862 -1.929384)
		(end 388.150862 -1.929384)
		(stroke
			(width 0.508)
			(type default)
		)
		(layer "In6.Cu")
	)
	(gr_line
		(start 387.541262 -12.385548)
		(end 387.541262 -10.124948)
		(stroke
			(width 0.254)
			(type default)
		)
		(layer "In6.Cu")
	)
	(gr_line
		(start 387.541262 -12.285472)
		(end 387.541262 -10.024872)
		(stroke
			(width 0.254)
			(type default)
		)
		(layer "In6.Cu")
	)
	(gr_line
		(start 387.541262 -12.233148)
		(end 388.176262 -12.233148)
		(stroke
			(width 0.508)
			(type default)
		)
		(layer "In6.Cu")
	)
	(gr_line
		(start 387.541262 -12.133072)
		(end 388.176262 -12.133072)
		(stroke
			(width 0.508)
			(type default)
		)
		(layer "In6.Cu")
	)
	(gr_line
		(start 387.541262 -10.124948)
		(end 388.176262 -10.124948)
		(stroke
			(width 0.254)
			(type default)
		)
		(layer "In6.Cu")
	)
	(gr_line
		(start 387.541262 -10.024872)
		(end 388.176262 -10.024872)
		(stroke
			(width 0.254)
			(type default)
		)
		(layer "In6.Cu")
	)
	(gr_line
		(start 387.541262 -8.185404)
		(end 387.541262 -5.924804)
		(stroke
			(width 0.254)
			(type default)
		)
		(layer "In6.Cu")
	)
	(gr_line
		(start 387.541262 -8.085328)
		(end 387.541262 -5.824728)
		(stroke
			(width 0.254)
			(type default)
		)
		(layer "In6.Cu")
	)
	(gr_line
		(start 387.541262 -8.033004)
		(end 388.176262 -8.033004)
		(stroke
			(width 0.508)
			(type default)
		)
		(layer "In6.Cu")
	)
	(gr_line
		(start 387.541262 -7.932928)
		(end 388.176262 -7.932928)
		(stroke
			(width 0.508)
			(type default)
		)
		(layer "In6.Cu")
	)
	(gr_line
		(start 387.541262 -5.924804)
		(end 388.176262 -5.924804)
		(stroke
			(width 0.254)
			(type default)
		)
		(layer "In6.Cu")
	)
	(gr_line
		(start 387.541262 -5.824728)
		(end 388.176262 -5.824728)
		(stroke
			(width 0.254)
			(type default)
		)
		(layer "In6.Cu")
	)
	(gr_line
		(start 387.541262 -3.98526)
		(end 387.541262 -1.72466)
		(stroke
			(width 0.254)
			(type default)
		)
		(layer "In6.Cu")
	)
	(gr_line
		(start 387.541262 -3.885184)
		(end 387.541262 -1.624584)
		(stroke
			(width 0.254)
			(type default)
		)
		(layer "In6.Cu")
	)
	(gr_line
		(start 387.541262 -3.83286)
		(end 388.176262 -3.83286)
		(stroke
			(width 0.508)
			(type default)
		)
		(layer "In6.Cu")
	)
	(gr_line
		(start 387.541262 -3.732784)
		(end 388.176262 -3.732784)
		(stroke
			(width 0.508)
			(type default)
		)
		(layer "In6.Cu")
	)
	(gr_line
		(start 387.541262 -1.72466)
		(end 388.176262 -1.72466)
		(stroke
			(width 0.254)
			(type default)
		)
		(layer "In6.Cu")
	)
	(gr_line
		(start 387.541262 -1.624584)
		(end 388.176262 -1.624584)
		(stroke
			(width 0.254)
			(type default)
		)
		(layer "In6.Cu")
	)
	(gr_line
		(start 387.566662 -12.080748)
		(end 388.201662 -12.080748)
		(stroke
			(width 0.508)
			(type default)
		)
		(layer "In6.Cu")
	)
	(gr_line
		(start 387.566662 -11.980672)
		(end 388.201662 -11.980672)
		(stroke
			(width 0.508)
			(type default)
		)
		(layer "In6.Cu")
	)
	(gr_line
		(start 387.566662 -7.880604)
		(end 388.201662 -7.880604)
		(stroke
			(width 0.508)
			(type default)
		)
		(layer "In6.Cu")
	)
	(gr_line
		(start 387.566662 -7.780528)
		(end 388.201662 -7.780528)
		(stroke
			(width 0.508)
			(type default)
		)
		(layer "In6.Cu")
	)
	(gr_line
		(start 387.566662 -3.68046)
		(end 388.201662 -3.68046)
		(stroke
			(width 0.508)
			(type default)
		)
		(layer "In6.Cu")
	)
	(gr_line
		(start 387.566662 -3.580384)
		(end 388.201662 -3.580384)
		(stroke
			(width 0.508)
			(type default)
		)
		(layer "In6.Cu")
	)
	(gr_line
		(start 387.592062 -12.360148)
		(end 388.227062 -12.360148)
		(stroke
			(width 0.508)
			(type default)
		)
		(layer "In6.Cu")
	)
	(gr_line
		(start 387.592062 -12.260072)
		(end 388.227062 -12.260072)
		(stroke
			(width 0.508)
			(type default)
		)
		(layer "In6.Cu")
	)
	(gr_line
		(start 387.592062 -9.947148)
		(end 388.430262 -9.947148)
		(stroke
			(width 0.2032)
			(type default)
		)
		(layer "In6.Cu")
	)
	(gr_line
		(start 387.592062 -9.847072)
		(end 388.430262 -9.847072)
		(stroke
			(width 0.2032)
			(type default)
		)
		(layer "In6.Cu")
	)
	(gr_line
		(start 387.592062 -8.160004)
		(end 388.227062 -8.160004)
		(stroke
			(width 0.508)
			(type default)
		)
		(layer "In6.Cu")
	)
	(gr_line
		(start 387.592062 -8.059928)
		(end 388.227062 -8.059928)
		(stroke
			(width 0.508)
			(type default)
		)
		(layer "In6.Cu")
	)
	(gr_line
		(start 387.592062 -5.747004)
		(end 388.430262 -5.747004)
		(stroke
			(width 0.2032)
			(type default)
		)
		(layer "In6.Cu")
	)
	(gr_line
		(start 387.592062 -5.646928)
		(end 388.430262 -5.646928)
		(stroke
			(width 0.2032)
			(type default)
		)
		(layer "In6.Cu")
	)
	(gr_line
		(start 387.592062 -3.95986)
		(end 388.227062 -3.95986)
		(stroke
			(width 0.508)
			(type default)
		)
		(layer "In6.Cu")
	)
	(gr_line
		(start 387.592062 -3.859784)
		(end 388.227062 -3.859784)
		(stroke
			(width 0.508)
			(type default)
		)
		(layer "In6.Cu")
	)
	(gr_line
		(start 387.592062 -1.54686)
		(end 388.430262 -1.54686)
		(stroke
			(width 0.2032)
			(type default)
		)
		(layer "In6.Cu")
	)
	(gr_line
		(start 387.592062 -1.446784)
		(end 388.430262 -1.446784)
		(stroke
			(width 0.2032)
			(type default)
		)
		(layer "In6.Cu")
	)
	(gr_line
		(start 387.617462 -12.360148)
		(end 387.617462 -10.175748)
		(stroke
			(width 0.254)
			(type default)
		)
		(layer "In6.Cu")
	)
	(gr_line
		(start 387.617462 -12.260072)
		(end 387.617462 -10.075672)
		(stroke
			(width 0.254)
			(type default)
		)
		(layer "In6.Cu")
	)
	(gr_line
		(start 387.617462 -10.175748)
		(end 388.100062 -10.175748)
		(stroke
			(width 0.254)
			(type default)
		)
		(layer "In6.Cu")
	)
	(gr_line
		(start 387.617462 -10.075672)
		(end 388.100062 -10.075672)
		(stroke
			(width 0.254)
			(type default)
		)
		(layer "In6.Cu")
	)
	(gr_line
		(start 387.617462 -9.997948)
		(end 388.354062 -9.997948)
		(stroke
			(width 0.254)
			(type default)
		)
		(layer "In6.Cu")
	)
	(gr_line
		(start 387.617462 -9.897872)
		(end 388.354062 -9.897872)
		(stroke
			(width 0.254)
			(type default)
		)
		(layer "In6.Cu")
	)
	(gr_line
		(start 387.617462 -8.160004)
		(end 387.617462 -5.975604)
		(stroke
			(width 0.254)
			(type default)
		)
		(layer "In6.Cu")
	)
	(gr_line
		(start 387.617462 -8.059928)
		(end 387.617462 -5.875528)
		(stroke
			(width 0.254)
			(type default)
		)
		(layer "In6.Cu")
	)
	(gr_line
		(start 387.617462 -5.975604)
		(end 388.100062 -5.975604)
		(stroke
			(width 0.254)
			(type default)
		)
		(layer "In6.Cu")
	)
	(gr_line
		(start 387.617462 -5.875528)
		(end 388.100062 -5.875528)
		(stroke
			(width 0.254)
			(type default)
		)
		(layer "In6.Cu")
	)
	(gr_line
		(start 387.617462 -5.797804)
		(end 388.354062 -5.797804)
		(stroke
			(width 0.254)
			(type default)
		)
		(layer "In6.Cu")
	)
	(gr_line
		(start 387.617462 -5.697728)
		(end 388.354062 -5.697728)
		(stroke
			(width 0.254)
			(type default)
		)
		(layer "In6.Cu")
	)
	(gr_line
		(start 387.617462 -3.95986)
		(end 387.617462 -1.77546)
		(stroke
			(width 0.254)
			(type default)
		)
		(layer "In6.Cu")
	)
	(gr_line
		(start 387.617462 -3.859784)
		(end 387.617462 -1.675384)
		(stroke
			(width 0.254)
			(type default)
		)
		(layer "In6.Cu")
	)
	(gr_line
		(start 387.617462 -1.77546)
		(end 388.100062 -1.77546)
		(stroke
			(width 0.254)
			(type default)
		)
		(layer "In6.Cu")
	)
	(gr_line
		(start 387.617462 -1.675384)
		(end 388.100062 -1.675384)
		(stroke
			(width 0.254)
			(type default)
		)
		(layer "In6.Cu")
	)
	(gr_line
		(start 387.617462 -1.59766)
		(end 388.354062 -1.59766)
		(stroke
			(width 0.254)
			(type default)
		)
		(layer "In6.Cu")
	)
	(gr_line
		(start 387.617462 -1.497584)
		(end 388.354062 -1.497584)
		(stroke
			(width 0.254)
			(type default)
		)
		(layer "In6.Cu")
	)
	(gr_line
		(start 387.636004 -10.110978)
		(end 388.271004 -10.110978)
		(stroke
			(width 0.508)
			(type default)
		)
		(layer "In6.Cu")
	)
	(gr_line
		(start 387.636004 -10.010902)
		(end 388.271004 -10.010902)
		(stroke
			(width 0.508)
			(type default)
		)
		(layer "In6.Cu")
	)
	(gr_line
		(start 387.636004 -5.910834)
		(end 388.271004 -5.910834)
		(stroke
			(width 0.508)
			(type default)
		)
		(layer "In6.Cu")
	)
	(gr_line
		(start 387.636004 -5.810758)
		(end 388.271004 -5.810758)
		(stroke
			(width 0.508)
			(type default)
		)
		(layer "In6.Cu")
	)
	(gr_line
		(start 387.636004 -1.71069)
		(end 388.271004 -1.71069)
		(stroke
			(width 0.508)
			(type default)
		)
		(layer "In6.Cu")
	)
	(gr_line
		(start 387.636004 -1.610614)
		(end 388.271004 -1.610614)
		(stroke
			(width 0.508)
			(type default)
		)
		(layer "In6.Cu")
	)
	(gr_line
		(start 387.642862 -12.360148)
		(end 388.277862 -12.360148)
		(stroke
			(width 0.508)
			(type default)
		)
		(layer "In6.Cu")
	)
	(gr_line
		(start 387.642862 -12.260072)
		(end 388.277862 -12.260072)
		(stroke
			(width 0.508)
			(type default)
		)
		(layer "In6.Cu")
	)
	(gr_line
		(start 387.642862 -12.233148)
		(end 387.642862 -10.251948)
		(stroke
			(width 0.762)
			(type default)
		)
		(layer "In6.Cu")
	)
	(gr_line
		(start 387.642862 -12.133072)
		(end 387.642862 -10.151872)
		(stroke
			(width 0.762)
			(type default)
		)
		(layer "In6.Cu")
	)
	(gr_line
		(start 387.642862 -10.251948)
		(end 388.277862 -10.251948)
		(stroke
			(width 0.508)
			(type default)
		)
		(layer "In6.Cu")
	)
	(gr_line
		(start 387.642862 -10.151872)
		(end 388.277862 -10.151872)
		(stroke
			(width 0.508)
			(type default)
		)
		(layer "In6.Cu")
	)
	(gr_line
		(start 387.642862 -8.160004)
		(end 388.277862 -8.160004)
		(stroke
			(width 0.508)
			(type default)
		)
		(layer "In6.Cu")
	)
	(gr_line
		(start 387.642862 -8.059928)
		(end 388.277862 -8.059928)
		(stroke
			(width 0.508)
			(type default)
		)
		(layer "In6.Cu")
	)
	(gr_line
		(start 387.642862 -8.033004)
		(end 387.642862 -6.051804)
		(stroke
			(width 0.762)
			(type default)
		)
		(layer "In6.Cu")
	)
	(gr_line
		(start 387.642862 -7.932928)
		(end 387.642862 -5.951728)
		(stroke
			(width 0.762)
			(type default)
		)
		(layer "In6.Cu")
	)
	(gr_line
		(start 387.642862 -6.051804)
		(end 388.277862 -6.051804)
		(stroke
			(width 0.508)
			(type default)
		)
		(layer "In6.Cu")
	)
	(gr_line
		(start 387.642862 -5.951728)
		(end 388.277862 -5.951728)
		(stroke
			(width 0.508)
			(type default)
		)
		(layer "In6.Cu")
	)
	(gr_line
		(start 387.642862 -3.95986)
		(end 388.277862 -3.95986)
		(stroke
			(width 0.508)
			(type default)
		)
		(layer "In6.Cu")
	)
	(gr_line
		(start 387.642862 -3.859784)
		(end 388.277862 -3.859784)
		(stroke
			(width 0.508)
			(type default)
		)
		(layer "In6.Cu")
	)
	(gr_line
		(start 387.642862 -3.83286)
		(end 387.642862 -1.85166)
		(stroke
			(width 0.762)
			(type default)
		)
		(layer "In6.Cu")
	)
	(gr_line
		(start 387.642862 -3.732784)
		(end 387.642862 -1.751584)
		(stroke
			(width 0.762)
			(type default)
		)
		(layer "In6.Cu")
	)
	(gr_line
		(start 387.642862 -1.85166)
		(end 388.277862 -1.85166)
		(stroke
			(width 0.508)
			(type default)
		)
		(layer "In6.Cu")
	)
	(gr_line
		(start 387.642862 -1.751584)
		(end 388.277862 -1.751584)
		(stroke
			(width 0.508)
			(type default)
		)
		(layer "In6.Cu")
	)
	(gr_line
		(start 387.693662 -12.283948)
		(end 387.693662 -10.251948)
		(stroke
			(width 0.254)
			(type default)
		)
		(layer "In6.Cu")
	)
	(gr_line
		(start 387.693662 -12.183872)
		(end 387.693662 -10.151872)
		(stroke
			(width 0.254)
			(type default)
		)
		(layer "In6.Cu")
	)
	(gr_line
		(start 387.693662 -10.251948)
		(end 388.023862 -10.251948)
		(stroke
			(width 0.254)
			(type default)
		)
		(layer "In6.Cu")
	)
	(gr_line
		(start 387.693662 -10.151872)
		(end 388.023862 -10.151872)
		(stroke
			(width 0.254)
			(type default)
		)
		(layer "In6.Cu")
	)
	(gr_line
		(start 387.693662 -8.083804)
		(end 387.693662 -6.051804)
		(stroke
			(width 0.254)
			(type default)
		)
		(layer "In6.Cu")
	)
	(gr_line
		(start 387.693662 -7.983728)
		(end 387.693662 -5.951728)
		(stroke
			(width 0.254)
			(type default)
		)
		(layer "In6.Cu")
	)
	(gr_line
		(start 387.693662 -6.051804)
		(end 388.023862 -6.051804)
		(stroke
			(width 0.254)
			(type default)
		)
		(layer "In6.Cu")
	)
	(gr_line
		(start 387.693662 -5.951728)
		(end 388.023862 -5.951728)
		(stroke
			(width 0.254)
			(type default)
		)
		(layer "In6.Cu")
	)
	(gr_line
		(start 387.693662 -3.88366)
		(end 387.693662 -1.85166)
		(stroke
			(width 0.254)
			(type default)
		)
		(layer "In6.Cu")
	)
	(gr_line
		(start 387.693662 -3.783584)
		(end 387.693662 -1.751584)
		(stroke
			(width 0.254)
			(type default)
		)
		(layer "In6.Cu")
	)
	(gr_line
		(start 387.693662 -1.85166)
		(end 388.023862 -1.85166)
		(stroke
			(width 0.254)
			(type default)
		)
		(layer "In6.Cu")
	)
	(gr_line
		(start 387.693662 -1.751584)
		(end 388.023862 -1.751584)
		(stroke
			(width 0.254)
			(type default)
		)
		(layer "In6.Cu")
	)
	(gr_line
		(start 387.795262 -12.207748)
		(end 387.795262 -10.404348)
		(stroke
			(width 0.254)
			(type default)
		)
		(layer "In6.Cu")
	)
	(gr_line
		(start 387.795262 -12.207748)
		(end 387.795262 -10.226548)
		(stroke
			(width 0.762)
			(type default)
		)
		(layer "In6.Cu")
	)
	(gr_line
		(start 387.795262 -12.107672)
		(end 387.795262 -10.304272)
		(stroke
			(width 0.254)
			(type default)
		)
		(layer "In6.Cu")
	)
	(gr_line
		(start 387.795262 -12.107672)
		(end 387.795262 -10.126472)
		(stroke
			(width 0.762)
			(type default)
		)
		(layer "In6.Cu")
	)
	(gr_line
		(start 387.795262 -10.404348)
		(end 387.896862 -10.404348)
		(stroke
			(width 0.254)
			(type default)
		)
		(layer "In6.Cu")
	)
	(gr_line
		(start 387.795262 -10.304272)
		(end 387.896862 -10.304272)
		(stroke
			(width 0.254)
			(type default)
		)
		(layer "In6.Cu")
	)
	(gr_line
		(start 387.795262 -8.007604)
		(end 387.795262 -6.204204)
		(stroke
			(width 0.254)
			(type default)
		)
		(layer "In6.Cu")
	)
	(gr_line
		(start 387.795262 -8.007604)
		(end 387.795262 -6.026404)
		(stroke
			(width 0.762)
			(type default)
		)
		(layer "In6.Cu")
	)
	(gr_line
		(start 387.795262 -7.907528)
		(end 387.795262 -6.104128)
		(stroke
			(width 0.254)
			(type default)
		)
		(layer "In6.Cu")
	)
	(gr_line
		(start 387.795262 -7.907528)
		(end 387.795262 -5.926328)
		(stroke
			(width 0.762)
			(type default)
		)
		(layer "In6.Cu")
	)
	(gr_line
		(start 387.795262 -6.204204)
		(end 387.896862 -6.204204)
		(stroke
			(width 0.254)
			(type default)
		)
		(layer "In6.Cu")
	)
	(gr_line
		(start 387.795262 -6.104128)
		(end 387.896862 -6.104128)
		(stroke
			(width 0.254)
			(type default)
		)
		(layer "In6.Cu")
	)
	(gr_line
		(start 387.795262 -3.80746)
		(end 387.795262 -2.00406)
		(stroke
			(width 0.254)
			(type default)
		)
		(layer "In6.Cu")
	)
	(gr_line
		(start 387.795262 -3.80746)
		(end 387.795262 -1.82626)
		(stroke
			(width 0.762)
			(type default)
		)
		(layer "In6.Cu")
	)
	(gr_line
		(start 387.795262 -3.707384)
		(end 387.795262 -1.903984)
		(stroke
			(width 0.254)
			(type default)
		)
		(layer "In6.Cu")
	)
	(gr_line
		(start 387.795262 -3.707384)
		(end 387.795262 -1.726184)
		(stroke
			(width 0.762)
			(type default)
		)
		(layer "In6.Cu")
	)
	(gr_line
		(start 387.795262 -2.00406)
		(end 387.896862 -2.00406)
		(stroke
			(width 0.254)
			(type default)
		)
		(layer "In6.Cu")
	)
	(gr_line
		(start 387.795262 -1.903984)
		(end 387.896862 -1.903984)
		(stroke
			(width 0.254)
			(type default)
		)
		(layer "In6.Cu")
	)
	(gr_line
		(start 387.896862 -12.309348)
		(end 387.846062 -12.309348)
		(stroke
			(width 0.254)
			(type default)
		)
		(layer "In6.Cu")
	)
	(gr_line
		(start 387.896862 -12.209272)
		(end 387.846062 -12.209272)
		(stroke
			(width 0.254)
			(type default)
		)
		(layer "In6.Cu")
	)
	(gr_line
		(start 387.896862 -10.404348)
		(end 387.896862 -12.309348)
		(stroke
			(width 0.254)
			(type default)
		)
		(layer "In6.Cu")
	)
	(gr_line
		(start 387.896862 -10.304272)
		(end 387.896862 -12.209272)
		(stroke
			(width 0.254)
			(type default)
		)
		(layer "In6.Cu")
	)
	(gr_line
		(start 387.896862 -8.109204)
		(end 387.846062 -8.109204)
		(stroke
			(width 0.254)
			(type default)
		)
		(layer "In6.Cu")
	)
	(gr_line
		(start 387.896862 -8.009128)
		(end 387.846062 -8.009128)
		(stroke
			(width 0.254)
			(type default)
		)
		(layer "In6.Cu")
	)
	(gr_line
		(start 387.896862 -6.204204)
		(end 387.896862 -8.109204)
		(stroke
			(width 0.254)
			(type default)
		)
		(layer "In6.Cu")
	)
	(gr_line
		(start 387.896862 -6.104128)
		(end 387.896862 -8.009128)
		(stroke
			(width 0.254)
			(type default)
		)
		(layer "In6.Cu")
	)
	(gr_line
		(start 387.896862 -3.90906)
		(end 387.846062 -3.90906)
		(stroke
			(width 0.254)
			(type default)
		)
		(layer "In6.Cu")
	)
	(gr_line
		(start 387.896862 -3.808984)
		(end 387.846062 -3.808984)
		(stroke
			(width 0.254)
			(type default)
		)
		(layer "In6.Cu")
	)
	(gr_line
		(start 387.896862 -2.00406)
		(end 387.896862 -3.90906)
		(stroke
			(width 0.254)
			(type default)
		)
		(layer "In6.Cu")
	)
	(gr_line
		(start 387.896862 -1.903984)
		(end 387.896862 -3.808984)
		(stroke
			(width 0.254)
			(type default)
		)
		(layer "In6.Cu")
	)
	(gr_line
		(start 387.947662 -12.233148)
		(end 387.947662 -10.251948)
		(stroke
			(width 0.762)
			(type default)
		)
		(layer "In6.Cu")
	)
	(gr_line
		(start 387.947662 -12.133072)
		(end 387.947662 -10.151872)
		(stroke
			(width 0.762)
			(type default)
		)
		(layer "In6.Cu")
	)
	(gr_line
		(start 387.947662 -8.033004)
		(end 387.947662 -6.051804)
		(stroke
			(width 0.762)
			(type default)
		)
		(layer "In6.Cu")
	)
	(gr_line
		(start 387.947662 -7.932928)
		(end 387.947662 -5.951728)
		(stroke
			(width 0.762)
			(type default)
		)
		(layer "In6.Cu")
	)
	(gr_line
		(start 387.947662 -3.83286)
		(end 387.947662 -1.85166)
		(stroke
			(width 0.762)
			(type default)
		)
		(layer "In6.Cu")
	)
	(gr_line
		(start 387.947662 -3.732784)
		(end 387.947662 -1.751584)
		(stroke
			(width 0.762)
			(type default)
		)
		(layer "In6.Cu")
	)
	(gr_line
		(start 388.023862 -12.207748)
		(end 387.795262 -12.207748)
		(stroke
			(width 0.254)
			(type default)
		)
		(layer "In6.Cu")
	)
	(gr_line
		(start 388.023862 -12.107672)
		(end 387.795262 -12.107672)
		(stroke
			(width 0.254)
			(type default)
		)
		(layer "In6.Cu")
	)
	(gr_line
		(start 388.023862 -10.251948)
		(end 388.023862 -12.207748)
		(stroke
			(width 0.254)
			(type default)
		)
		(layer "In6.Cu")
	)
	(gr_line
		(start 388.023862 -10.151872)
		(end 388.023862 -12.107672)
		(stroke
			(width 0.254)
			(type default)
		)
		(layer "In6.Cu")
	)
	(gr_line
		(start 388.023862 -8.007604)
		(end 387.795262 -8.007604)
		(stroke
			(width 0.254)
			(type default)
		)
		(layer "In6.Cu")
	)
	(gr_line
		(start 388.023862 -7.907528)
		(end 387.795262 -7.907528)
		(stroke
			(width 0.254)
			(type default)
		)
		(layer "In6.Cu")
	)
	(gr_line
		(start 388.023862 -6.051804)
		(end 388.023862 -8.007604)
		(stroke
			(width 0.254)
			(type default)
		)
		(layer "In6.Cu")
	)
	(gr_line
		(start 388.023862 -5.951728)
		(end 388.023862 -7.907528)
		(stroke
			(width 0.254)
			(type default)
		)
		(layer "In6.Cu")
	)
	(gr_line
		(start 388.023862 -3.80746)
		(end 387.795262 -3.80746)
		(stroke
			(width 0.254)
			(type default)
		)
		(layer "In6.Cu")
	)
	(gr_line
		(start 388.023862 -3.707384)
		(end 387.795262 -3.707384)
		(stroke
			(width 0.254)
			(type default)
		)
		(layer "In6.Cu")
	)
	(gr_line
		(start 388.023862 -1.85166)
		(end 388.023862 -3.80746)
		(stroke
			(width 0.254)
			(type default)
		)
		(layer "In6.Cu")
	)
	(gr_line
		(start 388.023862 -1.751584)
		(end 388.023862 -3.707384)
		(stroke
			(width 0.254)
			(type default)
		)
		(layer "In6.Cu")
	)
	(gr_line
		(start 388.074662 -12.563348)
		(end 388.074662 -12.512548)
		(stroke
			(width 0.1016)
			(type default)
		)
		(layer "In6.Cu")
	)
	(gr_line
		(start 388.074662 -12.563348)
		(end 388.481062 -12.563348)
		(stroke
			(width 0.1016)
			(type default)
		)
		(layer "In6.Cu")
	)
	(gr_line
		(start 388.074662 -12.512548)
		(end 387.312662 -12.512548)
		(stroke
			(width 0.1016)
			(type default)
		)
		(layer "In6.Cu")
	)
	(gr_line
		(start 388.074662 -12.463272)
		(end 388.074662 -12.412472)
		(stroke
			(width 0.1016)
			(type default)
		)
		(layer "In6.Cu")
	)
	(gr_line
		(start 388.074662 -12.463272)
		(end 388.481062 -12.463272)
		(stroke
			(width 0.1016)
			(type default)
		)
		(layer "In6.Cu")
	)
	(gr_line
		(start 388.074662 -12.412472)
		(end 387.312662 -12.412472)
		(stroke
			(width 0.1016)
			(type default)
		)
		(layer "In6.Cu")
	)
	(gr_line
		(start 388.074662 -12.233148)
		(end 388.074662 -10.251948)
		(stroke
			(width 0.762)
			(type default)
		)
		(layer "In6.Cu")
	)
	(gr_line
		(start 388.074662 -12.133072)
		(end 388.074662 -10.151872)
		(stroke
			(width 0.762)
			(type default)
		)
		(layer "In6.Cu")
	)
	(gr_line
		(start 388.074662 -8.363204)
		(end 388.074662 -8.312404)
		(stroke
			(width 0.1016)
			(type default)
		)
		(layer "In6.Cu")
	)
	(gr_line
		(start 388.074662 -8.363204)
		(end 388.481062 -8.363204)
		(stroke
			(width 0.1016)
			(type default)
		)
		(layer "In6.Cu")
	)
	(gr_line
		(start 388.074662 -8.312404)
		(end 387.312662 -8.312404)
		(stroke
			(width 0.1016)
			(type default)
		)
		(layer "In6.Cu")
	)
	(gr_line
		(start 388.074662 -8.263128)
		(end 388.074662 -8.212328)
		(stroke
			(width 0.1016)
			(type default)
		)
		(layer "In6.Cu")
	)
	(gr_line
		(start 388.074662 -8.263128)
		(end 388.481062 -8.263128)
		(stroke
			(width 0.1016)
			(type default)
		)
		(layer "In6.Cu")
	)
	(gr_line
		(start 388.074662 -8.212328)
		(end 387.312662 -8.212328)
		(stroke
			(width 0.1016)
			(type default)
		)
		(layer "In6.Cu")
	)
	(gr_line
		(start 388.074662 -8.033004)
		(end 388.074662 -6.051804)
		(stroke
			(width 0.762)
			(type default)
		)
		(layer "In6.Cu")
	)
	(gr_line
		(start 388.074662 -7.932928)
		(end 388.074662 -5.951728)
		(stroke
			(width 0.762)
			(type default)
		)
		(layer "In6.Cu")
	)
	(gr_line
		(start 388.074662 -4.16306)
		(end 388.074662 -4.11226)
		(stroke
			(width 0.1016)
			(type default)
		)
		(layer "In6.Cu")
	)
	(gr_line
		(start 388.074662 -4.16306)
		(end 388.481062 -4.16306)
		(stroke
			(width 0.1016)
			(type default)
		)
		(layer "In6.Cu")
	)
	(gr_line
		(start 388.074662 -4.11226)
		(end 387.312662 -4.11226)
		(stroke
			(width 0.1016)
			(type default)
		)
		(layer "In6.Cu")
	)
	(gr_line
		(start 388.074662 -4.062984)
		(end 388.074662 -4.012184)
		(stroke
			(width 0.1016)
			(type default)
		)
		(layer "In6.Cu")
	)
	(gr_line
		(start 388.074662 -4.062984)
		(end 388.481062 -4.062984)
		(stroke
			(width 0.1016)
			(type default)
		)
		(layer "In6.Cu")
	)
	(gr_line
		(start 388.074662 -4.012184)
		(end 387.312662 -4.012184)
		(stroke
			(width 0.1016)
			(type default)
		)
		(layer "In6.Cu")
	)
	(gr_line
		(start 388.074662 -3.83286)
		(end 388.074662 -1.85166)
		(stroke
			(width 0.762)
			(type default)
		)
		(layer "In6.Cu")
	)
	(gr_line
		(start 388.074662 -3.732784)
		(end 388.074662 -1.751584)
		(stroke
			(width 0.762)
			(type default)
		)
		(layer "In6.Cu")
	)
	(gr_line
		(start 388.100062 -12.283948)
		(end 387.693662 -12.283948)
		(stroke
			(width 0.254)
			(type default)
		)
		(layer "In6.Cu")
	)
	(gr_line
		(start 388.100062 -12.183872)
		(end 387.693662 -12.183872)
		(stroke
			(width 0.254)
			(type default)
		)
		(layer "In6.Cu")
	)
	(gr_line
		(start 388.100062 -10.175748)
		(end 388.100062 -12.283948)
		(stroke
			(width 0.254)
			(type default)
		)
		(layer "In6.Cu")
	)
	(gr_line
		(start 388.100062 -10.075672)
		(end 388.100062 -12.183872)
		(stroke
			(width 0.254)
			(type default)
		)
		(layer "In6.Cu")
	)
	(gr_line
		(start 388.100062 -8.083804)
		(end 387.693662 -8.083804)
		(stroke
			(width 0.254)
			(type default)
		)
		(layer "In6.Cu")
	)
	(gr_line
		(start 388.100062 -7.983728)
		(end 387.693662 -7.983728)
		(stroke
			(width 0.254)
			(type default)
		)
		(layer "In6.Cu")
	)
	(gr_line
		(start 388.100062 -5.975604)
		(end 388.100062 -8.083804)
		(stroke
			(width 0.254)
			(type default)
		)
		(layer "In6.Cu")
	)
	(gr_line
		(start 388.100062 -5.875528)
		(end 388.100062 -7.983728)
		(stroke
			(width 0.254)
			(type default)
		)
		(layer "In6.Cu")
	)
	(gr_line
		(start 388.100062 -3.88366)
		(end 387.693662 -3.88366)
		(stroke
			(width 0.254)
			(type default)
		)
		(layer "In6.Cu")
	)
	(gr_line
		(start 388.100062 -3.783584)
		(end 387.693662 -3.783584)
		(stroke
			(width 0.254)
			(type default)
		)
		(layer "In6.Cu")
	)
	(gr_line
		(start 388.100062 -1.77546)
		(end 388.100062 -3.88366)
		(stroke
			(width 0.254)
			(type default)
		)
		(layer "In6.Cu")
	)
	(gr_line
		(start 388.100062 -1.675384)
		(end 388.100062 -3.783584)
		(stroke
			(width 0.254)
			(type default)
		)
		(layer "In6.Cu")
	)
	(gr_line
		(start 388.150862 -12.233148)
		(end 388.150862 -10.251948)
		(stroke
			(width 0.762)
			(type default)
		)
		(layer "In6.Cu")
	)
	(gr_line
		(start 388.150862 -12.133072)
		(end 388.150862 -10.151872)
		(stroke
			(width 0.762)
			(type default)
		)
		(layer "In6.Cu")
	)
	(gr_line
		(start 388.150862 -8.033004)
		(end 388.150862 -6.051804)
		(stroke
			(width 0.762)
			(type default)
		)
		(layer "In6.Cu")
	)
	(gr_line
		(start 388.150862 -7.932928)
		(end 388.150862 -5.951728)
		(stroke
			(width 0.762)
			(type default)
		)
		(layer "In6.Cu")
	)
	(gr_line
		(start 388.150862 -3.83286)
		(end 388.150862 -1.85166)
		(stroke
			(width 0.762)
			(type default)
		)
		(layer "In6.Cu")
	)
	(gr_line
		(start 388.150862 -3.732784)
		(end 388.150862 -1.751584)
		(stroke
			(width 0.762)
			(type default)
		)
		(layer "In6.Cu")
	)
	(gr_line
		(start 388.176262 -12.360148)
		(end 387.617462 -12.360148)
		(stroke
			(width 0.254)
			(type default)
		)
		(layer "In6.Cu")
	)
	(gr_line
		(start 388.176262 -12.260072)
		(end 387.617462 -12.260072)
		(stroke
			(width 0.254)
			(type default)
		)
		(layer "In6.Cu")
	)
	(gr_line
		(start 388.176262 -10.124948)
		(end 388.176262 -12.360148)
		(stroke
			(width 0.254)
			(type default)
		)
		(layer "In6.Cu")
	)
	(gr_line
		(start 388.176262 -10.024872)
		(end 388.176262 -12.260072)
		(stroke
			(width 0.254)
			(type default)
		)
		(layer "In6.Cu")
	)
	(gr_line
		(start 388.176262 -8.160004)
		(end 387.617462 -8.160004)
		(stroke
			(width 0.254)
			(type default)
		)
		(layer "In6.Cu")
	)
	(gr_line
		(start 388.176262 -8.059928)
		(end 387.617462 -8.059928)
		(stroke
			(width 0.254)
			(type default)
		)
		(layer "In6.Cu")
	)
	(gr_line
		(start 388.176262 -5.924804)
		(end 388.176262 -8.160004)
		(stroke
			(width 0.254)
			(type default)
		)
		(layer "In6.Cu")
	)
	(gr_line
		(start 388.176262 -5.824728)
		(end 388.176262 -8.059928)
		(stroke
			(width 0.254)
			(type default)
		)
		(layer "In6.Cu")
	)
	(gr_line
		(start 388.176262 -3.95986)
		(end 387.617462 -3.95986)
		(stroke
			(width 0.254)
			(type default)
		)
		(layer "In6.Cu")
	)
	(gr_line
		(start 388.176262 -3.859784)
		(end 387.617462 -3.859784)
		(stroke
			(width 0.254)
			(type default)
		)
		(layer "In6.Cu")
	)
	(gr_line
		(start 388.176262 -1.72466)
		(end 388.176262 -3.95986)
		(stroke
			(width 0.254)
			(type default)
		)
		(layer "In6.Cu")
	)
	(gr_line
		(start 388.176262 -1.624584)
		(end 388.176262 -3.859784)
		(stroke
			(width 0.254)
			(type default)
		)
		(layer "In6.Cu")
	)
	(gr_line
		(start 388.252462 -12.385548)
		(end 387.541262 -12.385548)
		(stroke
			(width 0.254)
			(type default)
		)
		(layer "In6.Cu")
	)
	(gr_line
		(start 388.252462 -12.285472)
		(end 387.541262 -12.285472)
		(stroke
			(width 0.254)
			(type default)
		)
		(layer "In6.Cu")
	)
	(gr_line
		(start 388.252462 -10.048748)
		(end 388.252462 -12.385548)
		(stroke
			(width 0.254)
			(type default)
		)
		(layer "In6.Cu")
	)
	(gr_line
		(start 388.252462 -9.948672)
		(end 388.252462 -12.285472)
		(stroke
			(width 0.254)
			(type default)
		)
		(layer "In6.Cu")
	)
	(gr_line
		(start 388.252462 -8.185404)
		(end 387.541262 -8.185404)
		(stroke
			(width 0.254)
			(type default)
		)
		(layer "In6.Cu")
	)
	(gr_line
		(start 388.252462 -8.085328)
		(end 387.541262 -8.085328)
		(stroke
			(width 0.254)
			(type default)
		)
		(layer "In6.Cu")
	)
	(gr_line
		(start 388.252462 -5.848604)
		(end 388.252462 -8.185404)
		(stroke
			(width 0.254)
			(type default)
		)
		(layer "In6.Cu")
	)
	(gr_line
		(start 388.252462 -5.748528)
		(end 388.252462 -8.085328)
		(stroke
			(width 0.254)
			(type default)
		)
		(layer "In6.Cu")
	)
	(gr_line
		(start 388.252462 -3.98526)
		(end 387.541262 -3.98526)
		(stroke
			(width 0.254)
			(type default)
		)
		(layer "In6.Cu")
	)
	(gr_line
		(start 388.252462 -3.885184)
		(end 387.541262 -3.885184)
		(stroke
			(width 0.254)
			(type default)
		)
		(layer "In6.Cu")
	)
	(gr_line
		(start 388.252462 -1.64846)
		(end 388.252462 -3.98526)
		(stroke
			(width 0.254)
			(type default)
		)
		(layer "In6.Cu")
	)
	(gr_line
		(start 388.252462 -1.548384)
		(end 388.252462 -3.885184)
		(stroke
			(width 0.254)
			(type default)
		)
		(layer "In6.Cu")
	)
	(gr_line
		(start 388.277862 -12.512548)
		(end 387.287262 -12.512548)
		(stroke
			(width 0.1016)
			(type default)
		)
		(layer "In6.Cu")
	)
	(gr_line
		(start 388.277862 -12.436348)
		(end 387.465062 -12.436348)
		(stroke
			(width 0.254)
			(type default)
		)
		(layer "In6.Cu")
	)
	(gr_line
		(start 388.277862 -12.412472)
		(end 387.287262 -12.412472)
		(stroke
			(width 0.1016)
			(type default)
		)
		(layer "In6.Cu")
	)
	(gr_line
		(start 388.277862 -12.336272)
		(end 387.465062 -12.336272)
		(stroke
			(width 0.254)
			(type default)
		)
		(layer "In6.Cu")
	)
	(gr_line
		(start 388.277862 -10.023348)
		(end 388.277862 -12.436348)
		(stroke
			(width 0.254)
			(type default)
		)
		(layer "In6.Cu")
	)
	(gr_line
		(start 388.277862 -9.923272)
		(end 388.277862 -12.336272)
		(stroke
			(width 0.254)
			(type default)
		)
		(layer "In6.Cu")
	)
	(gr_line
		(start 388.277862 -8.312404)
		(end 387.287262 -8.312404)
		(stroke
			(width 0.1016)
			(type default)
		)
		(layer "In6.Cu")
	)
	(gr_line
		(start 388.277862 -8.236204)
		(end 387.465062 -8.236204)
		(stroke
			(width 0.254)
			(type default)
		)
		(layer "In6.Cu")
	)
	(gr_line
		(start 388.277862 -8.212328)
		(end 387.287262 -8.212328)
		(stroke
			(width 0.1016)
			(type default)
		)
		(layer "In6.Cu")
	)
	(gr_line
		(start 388.277862 -8.136128)
		(end 387.465062 -8.136128)
		(stroke
			(width 0.254)
			(type default)
		)
		(layer "In6.Cu")
	)
	(gr_line
		(start 388.277862 -5.823204)
		(end 388.277862 -8.236204)
		(stroke
			(width 0.254)
			(type default)
		)
		(layer "In6.Cu")
	)
	(gr_line
		(start 388.277862 -5.723128)
		(end 388.277862 -8.136128)
		(stroke
			(width 0.254)
			(type default)
		)
		(layer "In6.Cu")
	)
	(gr_line
		(start 388.277862 -4.11226)
		(end 387.287262 -4.11226)
		(stroke
			(width 0.1016)
			(type default)
		)
		(layer "In6.Cu")
	)
	(gr_line
		(start 388.277862 -4.03606)
		(end 387.465062 -4.03606)
		(stroke
			(width 0.254)
			(type default)
		)
		(layer "In6.Cu")
	)
	(gr_line
		(start 388.277862 -4.012184)
		(end 387.287262 -4.012184)
		(stroke
			(width 0.1016)
			(type default)
		)
		(layer "In6.Cu")
	)
	(gr_line
		(start 388.277862 -3.935984)
		(end 387.465062 -3.935984)
		(stroke
			(width 0.254)
			(type default)
		)
		(layer "In6.Cu")
	)
	(gr_line
		(start 388.277862 -1.62306)
		(end 388.277862 -4.03606)
		(stroke
			(width 0.254)
			(type default)
		)
		(layer "In6.Cu")
	)
	(gr_line
		(start 388.277862 -1.522984)
		(end 388.277862 -3.935984)
		(stroke
			(width 0.254)
			(type default)
		)
		(layer "In6.Cu")
	)
	(gr_line
		(start 388.303262 -12.461748)
		(end 387.439662 -12.461748)
		(stroke
			(width 0.254)
			(type default)
		)
		(layer "In6.Cu")
	)
	(gr_line
		(start 388.303262 -12.361672)
		(end 387.439662 -12.361672)
		(stroke
			(width 0.254)
			(type default)
		)
		(layer "In6.Cu")
	)
	(gr_line
		(start 388.303262 -9.997948)
		(end 388.303262 -12.461748)
		(stroke
			(width 0.254)
			(type default)
		)
		(layer "In6.Cu")
	)
	(gr_line
		(start 388.303262 -9.897872)
		(end 388.303262 -12.361672)
		(stroke
			(width 0.254)
			(type default)
		)
		(layer "In6.Cu")
	)
	(gr_line
		(start 388.303262 -8.261604)
		(end 387.439662 -8.261604)
		(stroke
			(width 0.254)
			(type default)
		)
		(layer "In6.Cu")
	)
	(gr_line
		(start 388.303262 -8.161528)
		(end 387.439662 -8.161528)
		(stroke
			(width 0.254)
			(type default)
		)
		(layer "In6.Cu")
	)
	(gr_line
		(start 388.303262 -5.797804)
		(end 388.303262 -8.261604)
		(stroke
			(width 0.254)
			(type default)
		)
		(layer "In6.Cu")
	)
	(gr_line
		(start 388.303262 -5.697728)
		(end 388.303262 -8.161528)
		(stroke
			(width 0.254)
			(type default)
		)
		(layer "In6.Cu")
	)
	(gr_line
		(start 388.303262 -4.06146)
		(end 387.439662 -4.06146)
		(stroke
			(width 0.254)
			(type default)
		)
		(layer "In6.Cu")
	)
	(gr_line
		(start 388.303262 -3.961384)
		(end 387.439662 -3.961384)
		(stroke
			(width 0.254)
			(type default)
		)
		(layer "In6.Cu")
	)
	(gr_line
		(start 388.303262 -1.59766)
		(end 388.303262 -4.06146)
		(stroke
			(width 0.254)
			(type default)
		)
		(layer "In6.Cu")
	)
	(gr_line
		(start 388.303262 -1.497584)
		(end 388.303262 -3.961384)
		(stroke
			(width 0.254)
			(type default)
		)
		(layer "In6.Cu")
	)
	(gr_line
		(start 388.354062 -12.487148)
		(end 387.414262 -12.487148)
		(stroke
			(width 0.254)
			(type default)
		)
		(layer "In6.Cu")
	)
	(gr_line
		(start 388.354062 -12.387072)
		(end 387.414262 -12.387072)
		(stroke
			(width 0.254)
			(type default)
		)
		(layer "In6.Cu")
	)
	(gr_line
		(start 388.354062 -9.997948)
		(end 388.354062 -12.487148)
		(stroke
			(width 0.254)
			(type default)
		)
		(layer "In6.Cu")
	)
	(gr_line
		(start 388.354062 -9.897872)
		(end 388.354062 -12.387072)
		(stroke
			(width 0.254)
			(type default)
		)
		(layer "In6.Cu")
	)
	(gr_line
		(start 388.354062 -8.287004)
		(end 387.414262 -8.287004)
		(stroke
			(width 0.254)
			(type default)
		)
		(layer "In6.Cu")
	)
	(gr_line
		(start 388.354062 -8.186928)
		(end 387.414262 -8.186928)
		(stroke
			(width 0.254)
			(type default)
		)
		(layer "In6.Cu")
	)
	(gr_line
		(start 388.354062 -5.797804)
		(end 388.354062 -8.287004)
		(stroke
			(width 0.254)
			(type default)
		)
		(layer "In6.Cu")
	)
	(gr_line
		(start 388.354062 -5.697728)
		(end 388.354062 -8.186928)
		(stroke
			(width 0.254)
			(type default)
		)
		(layer "In6.Cu")
	)
	(gr_line
		(start 388.354062 -4.08686)
		(end 387.414262 -4.08686)
		(stroke
			(width 0.254)
			(type default)
		)
		(layer "In6.Cu")
	)
	(gr_line
		(start 388.354062 -3.986784)
		(end 387.414262 -3.986784)
		(stroke
			(width 0.254)
			(type default)
		)
		(layer "In6.Cu")
	)
	(gr_line
		(start 388.354062 -1.59766)
		(end 388.354062 -4.08686)
		(stroke
			(width 0.254)
			(type default)
		)
		(layer "In6.Cu")
	)
	(gr_line
		(start 388.354062 -1.497584)
		(end 388.354062 -3.986784)
		(stroke
			(width 0.254)
			(type default)
		)
		(layer "In6.Cu")
	)
	(gr_line
		(start 388.379462 -12.487148)
		(end 387.414262 -12.487148)
		(stroke
			(width 0.2032)
			(type default)
		)
		(layer "In6.Cu")
	)
	(gr_line
		(start 388.379462 -12.387072)
		(end 387.414262 -12.387072)
		(stroke
			(width 0.2032)
			(type default)
		)
		(layer "In6.Cu")
	)
	(gr_line
		(start 388.379462 -9.947148)
		(end 388.379462 -12.487148)
		(stroke
			(width 0.2032)
			(type default)
		)
		(layer "In6.Cu")
	)
	(gr_line
		(start 388.379462 -9.847072)
		(end 388.379462 -12.387072)
		(stroke
			(width 0.2032)
			(type default)
		)
		(layer "In6.Cu")
	)
	(gr_line
		(start 388.379462 -8.287004)
		(end 387.414262 -8.287004)
		(stroke
			(width 0.2032)
			(type default)
		)
		(layer "In6.Cu")
	)
	(gr_line
		(start 388.379462 -8.186928)
		(end 387.414262 -8.186928)
		(stroke
			(width 0.2032)
			(type default)
		)
		(layer "In6.Cu")
	)
	(gr_line
		(start 388.379462 -5.747004)
		(end 388.379462 -8.287004)
		(stroke
			(width 0.2032)
			(type default)
		)
		(layer "In6.Cu")
	)
	(gr_line
		(start 388.379462 -5.646928)
		(end 388.379462 -8.186928)
		(stroke
			(width 0.2032)
			(type default)
		)
		(layer "In6.Cu")
	)
	(gr_line
		(start 388.379462 -4.08686)
		(end 387.414262 -4.08686)
		(stroke
			(width 0.2032)
			(type default)
		)
		(layer "In6.Cu")
	)
	(gr_line
		(start 388.379462 -3.986784)
		(end 387.414262 -3.986784)
		(stroke
			(width 0.2032)
			(type default)
		)
		(layer "In6.Cu")
	)
	(gr_line
		(start 388.379462 -1.54686)
		(end 388.379462 -4.08686)
		(stroke
			(width 0.2032)
			(type default)
		)
		(layer "In6.Cu")
	)
	(gr_line
		(start 388.379462 -1.446784)
		(end 388.379462 -3.986784)
		(stroke
			(width 0.2032)
			(type default)
		)
		(layer "In6.Cu")
	)
	(gr_line
		(start 388.430262 -12.512548)
		(end 387.363462 -12.512548)
		(stroke
			(width 0.2032)
			(type default)
		)
		(layer "In6.Cu")
	)
	(gr_line
		(start 388.430262 -12.412472)
		(end 387.363462 -12.412472)
		(stroke
			(width 0.2032)
			(type default)
		)
		(layer "In6.Cu")
	)
	(gr_line
		(start 388.430262 -9.947148)
		(end 388.430262 -12.512548)
		(stroke
			(width 0.2032)
			(type default)
		)
		(layer "In6.Cu")
	)
	(gr_line
		(start 388.430262 -9.847072)
		(end 388.430262 -12.412472)
		(stroke
			(width 0.2032)
			(type default)
		)
		(layer "In6.Cu")
	)
	(gr_line
		(start 388.430262 -8.312404)
		(end 387.363462 -8.312404)
		(stroke
			(width 0.2032)
			(type default)
		)
		(layer "In6.Cu")
	)
	(gr_line
		(start 388.430262 -8.212328)
		(end 387.363462 -8.212328)
		(stroke
			(width 0.2032)
			(type default)
		)
		(layer "In6.Cu")
	)
	(gr_line
		(start 388.430262 -5.747004)
		(end 388.430262 -8.312404)
		(stroke
			(width 0.2032)
			(type default)
		)
		(layer "In6.Cu")
	)
	(gr_line
		(start 388.430262 -5.646928)
		(end 388.430262 -8.212328)
		(stroke
			(width 0.2032)
			(type default)
		)
		(layer "In6.Cu")
	)
	(gr_line
		(start 388.430262 -4.11226)
		(end 387.363462 -4.11226)
		(stroke
			(width 0.2032)
			(type default)
		)
		(layer "In6.Cu")
	)
	(gr_line
		(start 388.430262 -4.012184)
		(end 387.363462 -4.012184)
		(stroke
			(width 0.2032)
			(type default)
		)
		(layer "In6.Cu")
	)
	(gr_line
		(start 388.430262 -1.54686)
		(end 388.430262 -4.11226)
		(stroke
			(width 0.2032)
			(type default)
		)
		(layer "In6.Cu")
	)
	(gr_line
		(start 388.430262 -1.446784)
		(end 388.430262 -4.012184)
		(stroke
			(width 0.2032)
			(type default)
		)
		(layer "In6.Cu")
	)
	(gr_line
		(start 388.455662 -12.512548)
		(end 387.338062 -12.512548)
		(stroke
			(width 0.1016)
			(type default)
		)
		(layer "In6.Cu")
	)
	(gr_line
		(start 388.455662 -12.412472)
		(end 387.338062 -12.412472)
		(stroke
			(width 0.1016)
			(type default)
		)
		(layer "In6.Cu")
	)
	(gr_line
		(start 388.455662 -9.921748)
		(end 388.455662 -12.512548)
		(stroke
			(width 0.1016)
			(type default)
		)
		(layer "In6.Cu")
	)
	(gr_line
		(start 388.455662 -9.821672)
		(end 388.455662 -12.412472)
		(stroke
			(width 0.1016)
			(type default)
		)
		(layer "In6.Cu")
	)
	(gr_line
		(start 388.455662 -8.312404)
		(end 387.338062 -8.312404)
		(stroke
			(width 0.1016)
			(type default)
		)
		(layer "In6.Cu")
	)
	(gr_line
		(start 388.455662 -8.212328)
		(end 387.338062 -8.212328)
		(stroke
			(width 0.1016)
			(type default)
		)
		(layer "In6.Cu")
	)
	(gr_line
		(start 388.455662 -5.721604)
		(end 388.455662 -8.312404)
		(stroke
			(width 0.1016)
			(type default)
		)
		(layer "In6.Cu")
	)
	(gr_line
		(start 388.455662 -5.621528)
		(end 388.455662 -8.212328)
		(stroke
			(width 0.1016)
			(type default)
		)
		(layer "In6.Cu")
	)
	(gr_line
		(start 388.455662 -4.11226)
		(end 387.338062 -4.11226)
		(stroke
			(width 0.1016)
			(type default)
		)
		(layer "In6.Cu")
	)
	(gr_line
		(start 388.455662 -4.012184)
		(end 387.338062 -4.012184)
		(stroke
			(width 0.1016)
			(type default)
		)
		(layer "In6.Cu")
	)
	(gr_line
		(start 388.455662 -1.52146)
		(end 388.455662 -4.11226)
		(stroke
			(width 0.1016)
			(type default)
		)
		(layer "In6.Cu")
	)
	(gr_line
		(start 388.455662 -1.421384)
		(end 388.455662 -4.012184)
		(stroke
			(width 0.1016)
			(type default)
		)
		(layer "In6.Cu")
	)
	(gr_line
		(start 388.464806 -18.5166)
		(end 389.734806 -18.5166)
		(stroke
			(width 0.7874)
			(type default)
		)
		(layer "In6.Cu")
	)
	(gr_line
		(start 388.481062 -12.563348)
		(end 388.074662 -12.563348)
		(stroke
			(width 0.1016)
			(type default)
		)
		(layer "In6.Cu")
	)
	(gr_line
		(start 388.481062 -12.563348)
		(end 388.481062 -9.896348)
		(stroke
			(width 0.1016)
			(type default)
		)
		(layer "In6.Cu")
	)
	(gr_line
		(start 388.481062 -12.463272)
		(end 388.074662 -12.463272)
		(stroke
			(width 0.1016)
			(type default)
		)
		(layer "In6.Cu")
	)
	(gr_line
		(start 388.481062 -12.463272)
		(end 388.481062 -9.796272)
		(stroke
			(width 0.1016)
			(type default)
		)
		(layer "In6.Cu")
	)
	(gr_line
		(start 388.481062 -9.896348)
		(end 387.287262 -9.896348)
		(stroke
			(width 0.1016)
			(type default)
		)
		(layer "In6.Cu")
	)
	(gr_line
		(start 388.481062 -9.896348)
		(end 388.481062 -12.563348)
		(stroke
			(width 0.1016)
			(type default)
		)
		(layer "In6.Cu")
	)
	(gr_line
		(start 388.481062 -9.796272)
		(end 387.287262 -9.796272)
		(stroke
			(width 0.1016)
			(type default)
		)
		(layer "In6.Cu")
	)
	(gr_line
		(start 388.481062 -9.796272)
		(end 388.481062 -12.463272)
		(stroke
			(width 0.1016)
			(type default)
		)
		(layer "In6.Cu")
	)
	(gr_line
		(start 388.481062 -8.363204)
		(end 388.074662 -8.363204)
		(stroke
			(width 0.1016)
			(type default)
		)
		(layer "In6.Cu")
	)
	(gr_line
		(start 388.481062 -8.363204)
		(end 388.481062 -5.696204)
		(stroke
			(width 0.1016)
			(type default)
		)
		(layer "In6.Cu")
	)
	(gr_line
		(start 388.481062 -8.263128)
		(end 388.074662 -8.263128)
		(stroke
			(width 0.1016)
			(type default)
		)
		(layer "In6.Cu")
	)
	(gr_line
		(start 388.481062 -8.263128)
		(end 388.481062 -5.596128)
		(stroke
			(width 0.1016)
			(type default)
		)
		(layer "In6.Cu")
	)
	(gr_line
		(start 388.481062 -5.696204)
		(end 387.287262 -5.696204)
		(stroke
			(width 0.1016)
			(type default)
		)
		(layer "In6.Cu")
	)
	(gr_line
		(start 388.481062 -5.696204)
		(end 388.481062 -8.363204)
		(stroke
			(width 0.1016)
			(type default)
		)
		(layer "In6.Cu")
	)
	(gr_line
		(start 388.481062 -5.596128)
		(end 387.287262 -5.596128)
		(stroke
			(width 0.1016)
			(type default)
		)
		(layer "In6.Cu")
	)
	(gr_line
		(start 388.481062 -5.596128)
		(end 388.481062 -8.263128)
		(stroke
			(width 0.1016)
			(type default)
		)
		(layer "In6.Cu")
	)
	(gr_line
		(start 388.481062 -4.16306)
		(end 388.074662 -4.16306)
		(stroke
			(width 0.1016)
			(type default)
		)
		(layer "In6.Cu")
	)
	(gr_line
		(start 388.481062 -4.16306)
		(end 388.481062 -1.49606)
		(stroke
			(width 0.1016)
			(type default)
		)
		(layer "In6.Cu")
	)
	(gr_line
		(start 388.481062 -4.062984)
		(end 388.074662 -4.062984)
		(stroke
			(width 0.1016)
			(type default)
		)
		(layer "In6.Cu")
	)
	(gr_line
		(start 388.481062 -4.062984)
		(end 388.481062 -1.395984)
		(stroke
			(width 0.1016)
			(type default)
		)
		(layer "In6.Cu")
	)
	(gr_line
		(start 388.481062 -1.49606)
		(end 387.287262 -1.49606)
		(stroke
			(width 0.1016)
			(type default)
		)
		(layer "In6.Cu")
	)
	(gr_line
		(start 388.481062 -1.49606)
		(end 388.481062 -4.16306)
		(stroke
			(width 0.1016)
			(type default)
		)
		(layer "In6.Cu")
	)
	(gr_line
		(start 388.481062 -1.395984)
		(end 387.287262 -1.395984)
		(stroke
			(width 0.1016)
			(type default)
		)
		(layer "In6.Cu")
	)
	(gr_line
		(start 388.481062 -1.395984)
		(end 388.481062 -4.062984)
		(stroke
			(width 0.1016)
			(type default)
		)
		(layer "In6.Cu")
	)
	(gr_line
		(start 389.287258 -13.8176)
		(end 390.074658 -13.8176)
		(stroke
			(width 0.1016)
			(type default)
		)
		(layer "In6.Cu")
	)
	(gr_line
		(start 389.287258 -13.7668)
		(end 389.287258 -11.1506)
		(stroke
			(width 0.1016)
			(type default)
		)
		(layer "In6.Cu")
	)
	(gr_line
		(start 389.287258 -11.1506)
		(end 389.287258 -13.8176)
		(stroke
			(width 0.1016)
			(type default)
		)
		(layer "In6.Cu")
	)
	(gr_line
		(start 389.287258 -11.1506)
		(end 390.481058 -11.1506)
		(stroke
			(width 0.1016)
			(type default)
		)
		(layer "In6.Cu")
	)
	(gr_line
		(start 389.287258 -9.617456)
		(end 390.074658 -9.617456)
		(stroke
			(width 0.1016)
			(type default)
		)
		(layer "In6.Cu")
	)
	(gr_line
		(start 389.287258 -9.566656)
		(end 389.287258 -6.950456)
		(stroke
			(width 0.1016)
			(type default)
		)
		(layer "In6.Cu")
	)
	(gr_line
		(start 389.287258 -6.950456)
		(end 389.287258 -9.617456)
		(stroke
			(width 0.1016)
			(type default)
		)
		(layer "In6.Cu")
	)
	(gr_line
		(start 389.287258 -6.950456)
		(end 390.481058 -6.950456)
		(stroke
			(width 0.1016)
			(type default)
		)
		(layer "In6.Cu")
	)
	(gr_line
		(start 389.312658 -13.7668)
		(end 389.312658 -11.176)
		(stroke
			(width 0.1016)
			(type default)
		)
		(layer "In6.Cu")
	)
	(gr_line
		(start 389.312658 -11.176)
		(end 390.455658 -11.176)
		(stroke
			(width 0.1016)
			(type default)
		)
		(layer "In6.Cu")
	)
	(gr_line
		(start 389.312658 -9.566656)
		(end 389.312658 -6.975856)
		(stroke
			(width 0.1016)
			(type default)
		)
		(layer "In6.Cu")
	)
	(gr_line
		(start 389.312658 -6.975856)
		(end 390.455658 -6.975856)
		(stroke
			(width 0.1016)
			(type default)
		)
		(layer "In6.Cu")
	)
	(gr_line
		(start 389.338058 -13.7668)
		(end 389.338058 -11.2014)
		(stroke
			(width 0.1016)
			(type default)
		)
		(layer "In6.Cu")
	)
	(gr_line
		(start 389.338058 -11.2014)
		(end 389.592058 -11.2014)
		(stroke
			(width 0.1016)
			(type default)
		)
		(layer "In6.Cu")
	)
	(gr_line
		(start 389.338058 -9.566656)
		(end 389.338058 -7.001256)
		(stroke
			(width 0.1016)
			(type default)
		)
		(layer "In6.Cu")
	)
	(gr_line
		(start 389.338058 -7.001256)
		(end 389.592058 -7.001256)
		(stroke
			(width 0.1016)
			(type default)
		)
		(layer "In6.Cu")
	)
	(gr_line
		(start 389.363458 -13.7668)
		(end 389.363458 -11.2014)
		(stroke
			(width 0.2032)
			(type default)
		)
		(layer "In6.Cu")
	)
	(gr_line
		(start 389.363458 -11.2014)
		(end 390.379458 -11.2014)
		(stroke
			(width 0.2032)
			(type default)
		)
		(layer "In6.Cu")
	)
	(gr_line
		(start 389.363458 -9.566656)
		(end 389.363458 -7.001256)
		(stroke
			(width 0.2032)
			(type default)
		)
		(layer "In6.Cu")
	)
	(gr_line
		(start 389.363458 -7.001256)
		(end 390.379458 -7.001256)
		(stroke
			(width 0.2032)
			(type default)
		)
		(layer "In6.Cu")
	)
	(gr_line
		(start 389.414258 -13.7414)
		(end 389.414258 -11.2522)
		(stroke
			(width 0.2032)
			(type default)
		)
		(layer "In6.Cu")
	)
	(gr_line
		(start 389.414258 -13.7414)
		(end 389.414258 -11.2522)
		(stroke
			(width 0.254)
			(type default)
		)
		(layer "In6.Cu")
	)
	(gr_line
		(start 389.414258 -11.2522)
		(end 389.617458 -11.2522)
		(stroke
			(width 0.2032)
			(type default)
		)
		(layer "In6.Cu")
	)
	(gr_line
		(start 389.414258 -11.2522)
		(end 390.303258 -11.2522)
		(stroke
			(width 0.254)
			(type default)
		)
		(layer "In6.Cu")
	)
	(gr_line
		(start 389.414258 -9.541256)
		(end 389.414258 -7.052056)
		(stroke
			(width 0.2032)
			(type default)
		)
		(layer "In6.Cu")
	)
	(gr_line
		(start 389.414258 -9.541256)
		(end 389.414258 -7.052056)
		(stroke
			(width 0.254)
			(type default)
		)
		(layer "In6.Cu")
	)
	(gr_line
		(start 389.414258 -7.052056)
		(end 389.617458 -7.052056)
		(stroke
			(width 0.2032)
			(type default)
		)
		(layer "In6.Cu")
	)
	(gr_line
		(start 389.414258 -7.052056)
		(end 390.303258 -7.052056)
		(stroke
			(width 0.254)
			(type default)
		)
		(layer "In6.Cu")
	)
	(gr_line
		(start 389.439658 -13.716)
		(end 389.439658 -11.2776)
		(stroke
			(width 0.254)
			(type default)
		)
		(layer "In6.Cu")
	)
	(gr_line
		(start 389.439658 -11.2776)
		(end 390.277858 -11.2776)
		(stroke
			(width 0.254)
			(type default)
		)
		(layer "In6.Cu")
	)
	(gr_line
		(start 389.439658 -9.515856)
		(end 389.439658 -7.077456)
		(stroke
			(width 0.254)
			(type default)
		)
		(layer "In6.Cu")
	)
	(gr_line
		(start 389.439658 -7.077456)
		(end 390.277858 -7.077456)
		(stroke
			(width 0.254)
			(type default)
		)
		(layer "In6.Cu")
	)
	(gr_line
		(start 389.465058 -13.6906)
		(end 389.465058 -11.303)
		(stroke
			(width 0.254)
			(type default)
		)
		(layer "In6.Cu")
	)
	(gr_line
		(start 389.465058 -11.303)
		(end 390.252458 -11.303)
		(stroke
			(width 0.254)
			(type default)
		)
		(layer "In6.Cu")
	)
	(gr_line
		(start 389.465058 -9.490456)
		(end 389.465058 -7.102856)
		(stroke
			(width 0.254)
			(type default)
		)
		(layer "In6.Cu")
	)
	(gr_line
		(start 389.465058 -7.102856)
		(end 390.252458 -7.102856)
		(stroke
			(width 0.254)
			(type default)
		)
		(layer "In6.Cu")
	)
	(gr_line
		(start 389.490458 -13.6144)
		(end 390.125458 -13.6144)
		(stroke
			(width 0.508)
			(type default)
		)
		(layer "In6.Cu")
	)
	(gr_line
		(start 389.490458 -11.43)
		(end 390.125458 -11.43)
		(stroke
			(width 0.508)
			(type default)
		)
		(layer "In6.Cu")
	)
	(gr_line
		(start 389.490458 -11.3792)
		(end 390.125458 -11.3792)
		(stroke
			(width 0.508)
			(type default)
		)
		(layer "In6.Cu")
	)
	(gr_line
		(start 389.490458 -9.414256)
		(end 390.125458 -9.414256)
		(stroke
			(width 0.508)
			(type default)
		)
		(layer "In6.Cu")
	)
	(gr_line
		(start 389.490458 -7.229856)
		(end 390.125458 -7.229856)
		(stroke
			(width 0.508)
			(type default)
		)
		(layer "In6.Cu")
	)
	(gr_line
		(start 389.490458 -7.179056)
		(end 390.125458 -7.179056)
		(stroke
			(width 0.508)
			(type default)
		)
		(layer "In6.Cu")
	)
	(gr_line
		(start 389.515858 -11.684)
		(end 390.150858 -11.684)
		(stroke
			(width 0.508)
			(type default)
		)
		(layer "In6.Cu")
	)
	(gr_line
		(start 389.515858 -7.483856)
		(end 390.150858 -7.483856)
		(stroke
			(width 0.508)
			(type default)
		)
		(layer "In6.Cu")
	)
	(gr_line
		(start 389.541258 -13.6398)
		(end 389.541258 -11.3792)
		(stroke
			(width 0.254)
			(type default)
		)
		(layer "In6.Cu")
	)
	(gr_line
		(start 389.541258 -13.4874)
		(end 390.176258 -13.4874)
		(stroke
			(width 0.508)
			(type default)
		)
		(layer "In6.Cu")
	)
	(gr_line
		(start 389.541258 -11.3792)
		(end 390.176258 -11.3792)
		(stroke
			(width 0.254)
			(type default)
		)
		(layer "In6.Cu")
	)
	(gr_line
		(start 389.541258 -9.439656)
		(end 389.541258 -7.179056)
		(stroke
			(width 0.254)
			(type default)
		)
		(layer "In6.Cu")
	)
	(gr_line
		(start 389.541258 -9.287256)
		(end 390.176258 -9.287256)
		(stroke
			(width 0.508)
			(type default)
		)
		(layer "In6.Cu")
	)
	(gr_line
		(start 389.541258 -7.179056)
		(end 390.176258 -7.179056)
		(stroke
			(width 0.254)
			(type default)
		)
		(layer "In6.Cu")
	)
	(gr_line
		(start 389.566658 -13.335)
		(end 390.201658 -13.335)
		(stroke
			(width 0.508)
			(type default)
		)
		(layer "In6.Cu")
	)
	(gr_line
		(start 389.566658 -9.134856)
		(end 390.201658 -9.134856)
		(stroke
			(width 0.508)
			(type default)
		)
		(layer "In6.Cu")
	)
	(gr_line
		(start 389.592058 -13.6144)
		(end 390.227058 -13.6144)
		(stroke
			(width 0.508)
			(type default)
		)
		(layer "In6.Cu")
	)
	(gr_line
		(start 389.592058 -11.2014)
		(end 390.430258 -11.2014)
		(stroke
			(width 0.2032)
			(type default)
		)
		(layer "In6.Cu")
	)
	(gr_line
		(start 389.592058 -9.414256)
		(end 390.227058 -9.414256)
		(stroke
			(width 0.508)
			(type default)
		)
		(layer "In6.Cu")
	)
	(gr_line
		(start 389.592058 -7.001256)
		(end 390.430258 -7.001256)
		(stroke
			(width 0.2032)
			(type default)
		)
		(layer "In6.Cu")
	)
	(gr_line
		(start 389.617458 -13.6144)
		(end 389.617458 -11.43)
		(stroke
			(width 0.254)
			(type default)
		)
		(layer "In6.Cu")
	)
	(gr_line
		(start 389.617458 -11.43)
		(end 390.100058 -11.43)
		(stroke
			(width 0.254)
			(type default)
		)
		(layer "In6.Cu")
	)
	(gr_line
		(start 389.617458 -11.2522)
		(end 390.354058 -11.2522)
		(stroke
			(width 0.254)
			(type default)
		)
		(layer "In6.Cu")
	)
	(gr_line
		(start 389.617458 -9.414256)
		(end 389.617458 -7.229856)
		(stroke
			(width 0.254)
			(type default)
		)
		(layer "In6.Cu")
	)
	(gr_line
		(start 389.617458 -7.229856)
		(end 390.100058 -7.229856)
		(stroke
			(width 0.254)
			(type default)
		)
		(layer "In6.Cu")
	)
	(gr_line
		(start 389.617458 -7.052056)
		(end 390.354058 -7.052056)
		(stroke
			(width 0.254)
			(type default)
		)
		(layer "In6.Cu")
	)
	(gr_line
		(start 389.636 -11.36523)
		(end 390.271 -11.36523)
		(stroke
			(width 0.508)
			(type default)
		)
		(layer "In6.Cu")
	)
	(gr_line
		(start 389.636 -7.165086)
		(end 390.271 -7.165086)
		(stroke
			(width 0.508)
			(type default)
		)
		(layer "In6.Cu")
	)
	(gr_line
		(start 389.642858 -13.6144)
		(end 390.277858 -13.6144)
		(stroke
			(width 0.508)
			(type default)
		)
		(layer "In6.Cu")
	)
	(gr_line
		(start 389.642858 -13.4874)
		(end 389.642858 -11.5062)
		(stroke
			(width 0.762)
			(type default)
		)
		(layer "In6.Cu")
	)
	(gr_line
		(start 389.642858 -11.5062)
		(end 390.277858 -11.5062)
		(stroke
			(width 0.508)
			(type default)
		)
		(layer "In6.Cu")
	)
	(gr_line
		(start 389.642858 -9.414256)
		(end 390.277858 -9.414256)
		(stroke
			(width 0.508)
			(type default)
		)
		(layer "In6.Cu")
	)
	(gr_line
		(start 389.642858 -9.287256)
		(end 389.642858 -7.306056)
		(stroke
			(width 0.762)
			(type default)
		)
		(layer "In6.Cu")
	)
	(gr_line
		(start 389.642858 -7.306056)
		(end 390.277858 -7.306056)
		(stroke
			(width 0.508)
			(type default)
		)
		(layer "In6.Cu")
	)
	(gr_line
		(start 389.693658 -13.5382)
		(end 389.693658 -11.5062)
		(stroke
			(width 0.254)
			(type default)
		)
		(layer "In6.Cu")
	)
	(gr_line
		(start 389.693658 -11.5062)
		(end 390.023858 -11.5062)
		(stroke
			(width 0.254)
			(type default)
		)
		(layer "In6.Cu")
	)
	(gr_line
		(start 389.693658 -9.338056)
		(end 389.693658 -7.306056)
		(stroke
			(width 0.254)
			(type default)
		)
		(layer "In6.Cu")
	)
	(gr_line
		(start 389.693658 -7.306056)
		(end 390.023858 -7.306056)
		(stroke
			(width 0.254)
			(type default)
		)
		(layer "In6.Cu")
	)
	(gr_line
		(start 389.795258 -13.462)
		(end 389.795258 -11.6586)
		(stroke
			(width 0.254)
			(type default)
		)
		(layer "In6.Cu")
	)
	(gr_line
		(start 389.795258 -13.462)
		(end 389.795258 -11.4808)
		(stroke
			(width 0.762)
			(type default)
		)
		(layer "In6.Cu")
	)
	(gr_line
		(start 389.795258 -11.6586)
		(end 389.896858 -11.6586)
		(stroke
			(width 0.254)
			(type default)
		)
		(layer "In6.Cu")
	)
	(gr_line
		(start 389.795258 -9.261856)
		(end 389.795258 -7.458456)
		(stroke
			(width 0.254)
			(type default)
		)
		(layer "In6.Cu")
	)
	(gr_line
		(start 389.795258 -9.261856)
		(end 389.795258 -7.280656)
		(stroke
			(width 0.762)
			(type default)
		)
		(layer "In6.Cu")
	)
	(gr_line
		(start 389.795258 -7.458456)
		(end 389.896858 -7.458456)
		(stroke
			(width 0.254)
			(type default)
		)
		(layer "In6.Cu")
	)
	(gr_line
		(start 389.896858 -13.5636)
		(end 389.846058 -13.5636)
		(stroke
			(width 0.254)
			(type default)
		)
		(layer "In6.Cu")
	)
	(gr_line
		(start 389.896858 -11.6586)
		(end 389.896858 -13.5636)
		(stroke
			(width 0.254)
			(type default)
		)
		(layer "In6.Cu")
	)
	(gr_line
		(start 389.896858 -9.363456)
		(end 389.846058 -9.363456)
		(stroke
			(width 0.254)
			(type default)
		)
		(layer "In6.Cu")
	)
	(gr_line
		(start 389.896858 -7.458456)
		(end 389.896858 -9.363456)
		(stroke
			(width 0.254)
			(type default)
		)
		(layer "In6.Cu")
	)
	(gr_line
		(start 389.947658 -13.4874)
		(end 389.947658 -11.5062)
		(stroke
			(width 0.762)
			(type default)
		)
		(layer "In6.Cu")
	)
	(gr_line
		(start 389.947658 -9.287256)
		(end 389.947658 -7.306056)
		(stroke
			(width 0.762)
			(type default)
		)
		(layer "In6.Cu")
	)
	(gr_line
		(start 390.023858 -13.462)
		(end 389.795258 -13.462)
		(stroke
			(width 0.254)
			(type default)
		)
		(layer "In6.Cu")
	)
	(gr_line
		(start 390.023858 -11.5062)
		(end 390.023858 -13.462)
		(stroke
			(width 0.254)
			(type default)
		)
		(layer "In6.Cu")
	)
	(gr_line
		(start 390.023858 -9.261856)
		(end 389.795258 -9.261856)
		(stroke
			(width 0.254)
			(type default)
		)
		(layer "In6.Cu")
	)
	(gr_line
		(start 390.023858 -7.306056)
		(end 390.023858 -9.261856)
		(stroke
			(width 0.254)
			(type default)
		)
		(layer "In6.Cu")
	)
	(gr_line
		(start 390.074658 -13.8176)
		(end 390.074658 -13.7668)
		(stroke
			(width 0.1016)
			(type default)
		)
		(layer "In6.Cu")
	)
	(gr_line
		(start 390.074658 -13.8176)
		(end 390.481058 -13.8176)
		(stroke
			(width 0.1016)
			(type default)
		)
		(layer "In6.Cu")
	)
	(gr_line
		(start 390.074658 -13.7668)
		(end 389.312658 -13.7668)
		(stroke
			(width 0.1016)
			(type default)
		)
		(layer "In6.Cu")
	)
	(gr_line
		(start 390.074658 -13.4874)
		(end 390.074658 -11.5062)
		(stroke
			(width 0.762)
			(type default)
		)
		(layer "In6.Cu")
	)
	(gr_line
		(start 390.074658 -9.617456)
		(end 390.074658 -9.566656)
		(stroke
			(width 0.1016)
			(type default)
		)
		(layer "In6.Cu")
	)
	(gr_line
		(start 390.074658 -9.617456)
		(end 390.481058 -9.617456)
		(stroke
			(width 0.1016)
			(type default)
		)
		(layer "In6.Cu")
	)
	(gr_line
		(start 390.074658 -9.566656)
		(end 389.312658 -9.566656)
		(stroke
			(width 0.1016)
			(type default)
		)
		(layer "In6.Cu")
	)
	(gr_line
		(start 390.074658 -9.287256)
		(end 390.074658 -7.306056)
		(stroke
			(width 0.762)
			(type default)
		)
		(layer "In6.Cu")
	)
	(gr_line
		(start 390.100058 -13.5382)
		(end 389.693658 -13.5382)
		(stroke
			(width 0.254)
			(type default)
		)
		(layer "In6.Cu")
	)
	(gr_line
		(start 390.100058 -11.43)
		(end 390.100058 -13.5382)
		(stroke
			(width 0.254)
			(type default)
		)
		(layer "In6.Cu")
	)
	(gr_line
		(start 390.100058 -9.338056)
		(end 389.693658 -9.338056)
		(stroke
			(width 0.254)
			(type default)
		)
		(layer "In6.Cu")
	)
	(gr_line
		(start 390.100058 -7.229856)
		(end 390.100058 -9.338056)
		(stroke
			(width 0.254)
			(type default)
		)
		(layer "In6.Cu")
	)
	(gr_line
		(start 390.150858 -13.4874)
		(end 390.150858 -11.5062)
		(stroke
			(width 0.762)
			(type default)
		)
		(layer "In6.Cu")
	)
	(gr_line
		(start 390.150858 -9.287256)
		(end 390.150858 -7.306056)
		(stroke
			(width 0.762)
			(type default)
		)
		(layer "In6.Cu")
	)
	(gr_line
		(start 390.176258 -13.6144)
		(end 389.617458 -13.6144)
		(stroke
			(width 0.254)
			(type default)
		)
		(layer "In6.Cu")
	)
	(gr_line
		(start 390.176258 -11.3792)
		(end 390.176258 -13.6144)
		(stroke
			(width 0.254)
			(type default)
		)
		(layer "In6.Cu")
	)
	(gr_line
		(start 390.176258 -9.414256)
		(end 389.617458 -9.414256)
		(stroke
			(width 0.254)
			(type default)
		)
		(layer "In6.Cu")
	)
	(gr_line
		(start 390.176258 -7.179056)
		(end 390.176258 -9.414256)
		(stroke
			(width 0.254)
			(type default)
		)
		(layer "In6.Cu")
	)
	(gr_line
		(start 390.252458 -13.6398)
		(end 389.541258 -13.6398)
		(stroke
			(width 0.254)
			(type default)
		)
		(layer "In6.Cu")
	)
	(gr_line
		(start 390.252458 -11.303)
		(end 390.252458 -13.6398)
		(stroke
			(width 0.254)
			(type default)
		)
		(layer "In6.Cu")
	)
	(gr_line
		(start 390.252458 -9.439656)
		(end 389.541258 -9.439656)
		(stroke
			(width 0.254)
			(type default)
		)
		(layer "In6.Cu")
	)
	(gr_line
		(start 390.252458 -7.102856)
		(end 390.252458 -9.439656)
		(stroke
			(width 0.254)
			(type default)
		)
		(layer "In6.Cu")
	)
	(gr_line
		(start 390.277858 -13.7668)
		(end 389.287258 -13.7668)
		(stroke
			(width 0.1016)
			(type default)
		)
		(layer "In6.Cu")
	)
	(gr_line
		(start 390.277858 -13.6906)
		(end 389.465058 -13.6906)
		(stroke
			(width 0.254)
			(type default)
		)
		(layer "In6.Cu")
	)
	(gr_line
		(start 390.277858 -11.2776)
		(end 390.277858 -13.6906)
		(stroke
			(width 0.254)
			(type default)
		)
		(layer "In6.Cu")
	)
	(gr_line
		(start 390.277858 -9.566656)
		(end 389.287258 -9.566656)
		(stroke
			(width 0.1016)
			(type default)
		)
		(layer "In6.Cu")
	)
	(gr_line
		(start 390.277858 -9.490456)
		(end 389.465058 -9.490456)
		(stroke
			(width 0.254)
			(type default)
		)
		(layer "In6.Cu")
	)
	(gr_line
		(start 390.277858 -7.077456)
		(end 390.277858 -9.490456)
		(stroke
			(width 0.254)
			(type default)
		)
		(layer "In6.Cu")
	)
	(gr_line
		(start 390.303258 -13.716)
		(end 389.439658 -13.716)
		(stroke
			(width 0.254)
			(type default)
		)
		(layer "In6.Cu")
	)
	(gr_line
		(start 390.303258 -11.2522)
		(end 390.303258 -13.716)
		(stroke
			(width 0.254)
			(type default)
		)
		(layer "In6.Cu")
	)
	(gr_line
		(start 390.303258 -9.515856)
		(end 389.439658 -9.515856)
		(stroke
			(width 0.254)
			(type default)
		)
		(layer "In6.Cu")
	)
	(gr_line
		(start 390.303258 -7.052056)
		(end 390.303258 -9.515856)
		(stroke
			(width 0.254)
			(type default)
		)
		(layer "In6.Cu")
	)
	(gr_line
		(start 390.319768 -30.734)
		(end 389.049768 -30.734)
		(stroke
			(width 0.7874)
			(type default)
		)
		(layer "In6.Cu")
	)
	(gr_line
		(start 390.354058 -13.7414)
		(end 389.414258 -13.7414)
		(stroke
			(width 0.254)
			(type default)
		)
		(layer "In6.Cu")
	)
	(gr_line
		(start 390.354058 -11.2522)
		(end 390.354058 -13.7414)
		(stroke
			(width 0.254)
			(type default)
		)
		(layer "In6.Cu")
	)
	(gr_line
		(start 390.354058 -9.541256)
		(end 389.414258 -9.541256)
		(stroke
			(width 0.254)
			(type default)
		)
		(layer "In6.Cu")
	)
	(gr_line
		(start 390.354058 -7.052056)
		(end 390.354058 -9.541256)
		(stroke
			(width 0.254)
			(type default)
		)
		(layer "In6.Cu")
	)
	(gr_line
		(start 390.379458 -13.7414)
		(end 389.414258 -13.7414)
		(stroke
			(width 0.2032)
			(type default)
		)
		(layer "In6.Cu")
	)
	(gr_line
		(start 390.379458 -11.2014)
		(end 390.379458 -13.7414)
		(stroke
			(width 0.2032)
			(type default)
		)
		(layer "In6.Cu")
	)
	(gr_line
		(start 390.379458 -9.541256)
		(end 389.414258 -9.541256)
		(stroke
			(width 0.2032)
			(type default)
		)
		(layer "In6.Cu")
	)
	(gr_line
		(start 390.379458 -7.001256)
		(end 390.379458 -9.541256)
		(stroke
			(width 0.2032)
			(type default)
		)
		(layer "In6.Cu")
	)
	(gr_line
		(start 390.430258 -13.7668)
		(end 389.363458 -13.7668)
		(stroke
			(width 0.2032)
			(type default)
		)
		(layer "In6.Cu")
	)
	(gr_line
		(start 390.430258 -11.2014)
		(end 390.430258 -13.7668)
		(stroke
			(width 0.2032)
			(type default)
		)
		(layer "In6.Cu")
	)
	(gr_line
		(start 390.430258 -9.566656)
		(end 389.363458 -9.566656)
		(stroke
			(width 0.2032)
			(type default)
		)
		(layer "In6.Cu")
	)
	(gr_line
		(start 390.430258 -7.001256)
		(end 390.430258 -9.566656)
		(stroke
			(width 0.2032)
			(type default)
		)
		(layer "In6.Cu")
	)
	(gr_line
		(start 390.455658 -13.7668)
		(end 389.338058 -13.7668)
		(stroke
			(width 0.1016)
			(type default)
		)
		(layer "In6.Cu")
	)
	(gr_line
		(start 390.455658 -11.176)
		(end 390.455658 -13.7668)
		(stroke
			(width 0.1016)
			(type default)
		)
		(layer "In6.Cu")
	)
	(gr_line
		(start 390.455658 -9.566656)
		(end 389.338058 -9.566656)
		(stroke
			(width 0.1016)
			(type default)
		)
		(layer "In6.Cu")
	)
	(gr_line
		(start 390.455658 -6.975856)
		(end 390.455658 -9.566656)
		(stroke
			(width 0.1016)
			(type default)
		)
		(layer "In6.Cu")
	)
	(gr_line
		(start 390.481058 -13.8176)
		(end 390.074658 -13.8176)
		(stroke
			(width 0.1016)
			(type default)
		)
		(layer "In6.Cu")
	)
	(gr_line
		(start 390.481058 -13.8176)
		(end 390.481058 -11.1506)
		(stroke
			(width 0.1016)
			(type default)
		)
		(layer "In6.Cu")
	)
	(gr_line
		(start 390.481058 -11.1506)
		(end 389.287258 -11.1506)
		(stroke
			(width 0.1016)
			(type default)
		)
		(layer "In6.Cu")
	)
	(gr_line
		(start 390.481058 -11.1506)
		(end 390.481058 -13.8176)
		(stroke
			(width 0.1016)
			(type default)
		)
		(layer "In6.Cu")
	)
	(gr_line
		(start 390.481058 -9.617456)
		(end 390.074658 -9.617456)
		(stroke
			(width 0.1016)
			(type default)
		)
		(layer "In6.Cu")
	)
	(gr_line
		(start 390.481058 -9.617456)
		(end 390.481058 -6.950456)
		(stroke
			(width 0.1016)
			(type default)
		)
		(layer "In6.Cu")
	)
	(gr_line
		(start 390.481058 -6.950456)
		(end 389.287258 -6.950456)
		(stroke
			(width 0.1016)
			(type default)
		)
		(layer "In6.Cu")
	)
	(gr_line
		(start 390.481058 -6.950456)
		(end 390.481058 -9.617456)
		(stroke
			(width 0.1016)
			(type default)
		)
		(layer "In6.Cu")
	)
	(gr_line
		(start 391.287254 -12.563348)
		(end 392.074654 -12.563348)
		(stroke
			(width 0.1016)
			(type default)
		)
		(layer "In6.Cu")
	)
	(gr_line
		(start 391.287254 -12.512548)
		(end 391.287254 -9.896348)
		(stroke
			(width 0.1016)
			(type default)
		)
		(layer "In6.Cu")
	)
	(gr_line
		(start 391.287254 -12.463272)
		(end 392.074654 -12.463272)
		(stroke
			(width 0.1016)
			(type default)
		)
		(layer "In6.Cu")
	)
	(gr_line
		(start 391.287254 -12.412472)
		(end 391.287254 -9.796272)
		(stroke
			(width 0.1016)
			(type default)
		)
		(layer "In6.Cu")
	)
	(gr_line
		(start 391.287254 -9.896348)
		(end 391.287254 -12.563348)
		(stroke
			(width 0.1016)
			(type default)
		)
		(layer "In6.Cu")
	)
	(gr_line
		(start 391.287254 -9.896348)
		(end 392.481054 -9.896348)
		(stroke
			(width 0.1016)
			(type default)
		)
		(layer "In6.Cu")
	)
	(gr_line
		(start 391.287254 -9.796272)
		(end 391.287254 -12.463272)
		(stroke
			(width 0.1016)
			(type default)
		)
		(layer "In6.Cu")
	)
	(gr_line
		(start 391.287254 -9.796272)
		(end 392.481054 -9.796272)
		(stroke
			(width 0.1016)
			(type default)
		)
		(layer "In6.Cu")
	)
	(gr_line
		(start 391.287254 -8.363204)
		(end 392.074654 -8.363204)
		(stroke
			(width 0.1016)
			(type default)
		)
		(layer "In6.Cu")
	)
	(gr_line
		(start 391.287254 -8.312404)
		(end 391.287254 -5.696204)
		(stroke
			(width 0.1016)
			(type default)
		)
		(layer "In6.Cu")
	)
	(gr_line
		(start 391.287254 -8.263128)
		(end 392.074654 -8.263128)
		(stroke
			(width 0.1016)
			(type default)
		)
		(layer "In6.Cu")
	)
	(gr_line
		(start 391.287254 -8.212328)
		(end 391.287254 -5.596128)
		(stroke
			(width 0.1016)
			(type default)
		)
		(layer "In6.Cu")
	)
	(gr_line
		(start 391.287254 -5.696204)
		(end 391.287254 -8.363204)
		(stroke
			(width 0.1016)
			(type default)
		)
		(layer "In6.Cu")
	)
	(gr_line
		(start 391.287254 -5.696204)
		(end 392.481054 -5.696204)
		(stroke
			(width 0.1016)
			(type default)
		)
		(layer "In6.Cu")
	)
	(gr_line
		(start 391.287254 -5.596128)
		(end 391.287254 -8.263128)
		(stroke
			(width 0.1016)
			(type default)
		)
		(layer "In6.Cu")
	)
	(gr_line
		(start 391.287254 -5.596128)
		(end 392.481054 -5.596128)
		(stroke
			(width 0.1016)
			(type default)
		)
		(layer "In6.Cu")
	)
	(gr_line
		(start 391.312654 -12.512548)
		(end 391.312654 -9.921748)
		(stroke
			(width 0.1016)
			(type default)
		)
		(layer "In6.Cu")
	)
	(gr_line
		(start 391.312654 -12.412472)
		(end 391.312654 -9.821672)
		(stroke
			(width 0.1016)
			(type default)
		)
		(layer "In6.Cu")
	)
	(gr_line
		(start 391.312654 -9.921748)
		(end 392.455654 -9.921748)
		(stroke
			(width 0.1016)
			(type default)
		)
		(layer "In6.Cu")
	)
	(gr_line
		(start 391.312654 -9.821672)
		(end 392.455654 -9.821672)
		(stroke
			(width 0.1016)
			(type default)
		)
		(layer "In6.Cu")
	)
	(gr_line
		(start 391.312654 -8.312404)
		(end 391.312654 -5.721604)
		(stroke
			(width 0.1016)
			(type default)
		)
		(layer "In6.Cu")
	)
	(gr_line
		(start 391.312654 -8.212328)
		(end 391.312654 -5.621528)
		(stroke
			(width 0.1016)
			(type default)
		)
		(layer "In6.Cu")
	)
	(gr_line
		(start 391.312654 -5.721604)
		(end 392.455654 -5.721604)
		(stroke
			(width 0.1016)
			(type default)
		)
		(layer "In6.Cu")
	)
	(gr_line
		(start 391.312654 -5.621528)
		(end 392.455654 -5.621528)
		(stroke
			(width 0.1016)
			(type default)
		)
		(layer "In6.Cu")
	)
	(gr_line
		(start 391.338054 -12.512548)
		(end 391.338054 -9.947148)
		(stroke
			(width 0.1016)
			(type default)
		)
		(layer "In6.Cu")
	)
	(gr_line
		(start 391.338054 -12.412472)
		(end 391.338054 -9.847072)
		(stroke
			(width 0.1016)
			(type default)
		)
		(layer "In6.Cu")
	)
	(gr_line
		(start 391.338054 -9.947148)
		(end 391.592054 -9.947148)
		(stroke
			(width 0.1016)
			(type default)
		)
		(layer "In6.Cu")
	)
	(gr_line
		(start 391.338054 -9.847072)
		(end 391.592054 -9.847072)
		(stroke
			(width 0.1016)
			(type default)
		)
		(layer "In6.Cu")
	)
	(gr_line
		(start 391.338054 -8.312404)
		(end 391.338054 -5.747004)
		(stroke
			(width 0.1016)
			(type default)
		)
		(layer "In6.Cu")
	)
	(gr_line
		(start 391.338054 -8.212328)
		(end 391.338054 -5.646928)
		(stroke
			(width 0.1016)
			(type default)
		)
		(layer "In6.Cu")
	)
	(gr_line
		(start 391.338054 -5.747004)
		(end 391.592054 -5.747004)
		(stroke
			(width 0.1016)
			(type default)
		)
		(layer "In6.Cu")
	)
	(gr_line
		(start 391.338054 -5.646928)
		(end 391.592054 -5.646928)
		(stroke
			(width 0.1016)
			(type default)
		)
		(layer "In6.Cu")
	)
	(gr_line
		(start 391.363454 -12.512548)
		(end 391.363454 -9.947148)
		(stroke
			(width 0.2032)
			(type default)
		)
		(layer "In6.Cu")
	)
	(gr_line
		(start 391.363454 -12.412472)
		(end 391.363454 -9.847072)
		(stroke
			(width 0.2032)
			(type default)
		)
		(layer "In6.Cu")
	)
	(gr_line
		(start 391.363454 -9.947148)
		(end 392.379454 -9.947148)
		(stroke
			(width 0.2032)
			(type default)
		)
		(layer "In6.Cu")
	)
	(gr_line
		(start 391.363454 -9.847072)
		(end 392.379454 -9.847072)
		(stroke
			(width 0.2032)
			(type default)
		)
		(layer "In6.Cu")
	)
	(gr_line
		(start 391.363454 -8.312404)
		(end 391.363454 -5.747004)
		(stroke
			(width 0.2032)
			(type default)
		)
		(layer "In6.Cu")
	)
	(gr_line
		(start 391.363454 -8.212328)
		(end 391.363454 -5.646928)
		(stroke
			(width 0.2032)
			(type default)
		)
		(layer "In6.Cu")
	)
	(gr_line
		(start 391.363454 -5.747004)
		(end 392.379454 -5.747004)
		(stroke
			(width 0.2032)
			(type default)
		)
		(layer "In6.Cu")
	)
	(gr_line
		(start 391.363454 -5.646928)
		(end 392.379454 -5.646928)
		(stroke
			(width 0.2032)
			(type default)
		)
		(layer "In6.Cu")
	)
	(gr_line
		(start 391.414254 -12.487148)
		(end 391.414254 -9.997948)
		(stroke
			(width 0.2032)
			(type default)
		)
		(layer "In6.Cu")
	)
	(gr_line
		(start 391.414254 -12.487148)
		(end 391.414254 -9.997948)
		(stroke
			(width 0.254)
			(type default)
		)
		(layer "In6.Cu")
	)
	(gr_line
		(start 391.414254 -12.387072)
		(end 391.414254 -9.897872)
		(stroke
			(width 0.2032)
			(type default)
		)
		(layer "In6.Cu")
	)
	(gr_line
		(start 391.414254 -12.387072)
		(end 391.414254 -9.897872)
		(stroke
			(width 0.254)
			(type default)
		)
		(layer "In6.Cu")
	)
	(gr_line
		(start 391.414254 -9.997948)
		(end 391.617454 -9.997948)
		(stroke
			(width 0.2032)
			(type default)
		)
		(layer "In6.Cu")
	)
	(gr_line
		(start 391.414254 -9.997948)
		(end 392.303254 -9.997948)
		(stroke
			(width 0.254)
			(type default)
		)
		(layer "In6.Cu")
	)
	(gr_line
		(start 391.414254 -9.897872)
		(end 391.617454 -9.897872)
		(stroke
			(width 0.2032)
			(type default)
		)
		(layer "In6.Cu")
	)
	(gr_line
		(start 391.414254 -9.897872)
		(end 392.303254 -9.897872)
		(stroke
			(width 0.254)
			(type default)
		)
		(layer "In6.Cu")
	)
	(gr_line
		(start 391.414254 -8.287004)
		(end 391.414254 -5.797804)
		(stroke
			(width 0.2032)
			(type default)
		)
		(layer "In6.Cu")
	)
	(gr_line
		(start 391.414254 -8.287004)
		(end 391.414254 -5.797804)
		(stroke
			(width 0.254)
			(type default)
		)
		(layer "In6.Cu")
	)
	(gr_line
		(start 391.414254 -8.186928)
		(end 391.414254 -5.697728)
		(stroke
			(width 0.2032)
			(type default)
		)
		(layer "In6.Cu")
	)
	(gr_line
		(start 391.414254 -8.186928)
		(end 391.414254 -5.697728)
		(stroke
			(width 0.254)
			(type default)
		)
		(layer "In6.Cu")
	)
	(gr_line
		(start 391.414254 -5.797804)
		(end 391.617454 -5.797804)
		(stroke
			(width 0.2032)
			(type default)
		)
		(layer "In6.Cu")
	)
	(gr_line
		(start 391.414254 -5.797804)
		(end 392.303254 -5.797804)
		(stroke
			(width 0.254)
			(type default)
		)
		(layer "In6.Cu")
	)
	(gr_line
		(start 391.414254 -5.697728)
		(end 391.617454 -5.697728)
		(stroke
			(width 0.2032)
			(type default)
		)
		(layer "In6.Cu")
	)
	(gr_line
		(start 391.414254 -5.697728)
		(end 392.303254 -5.697728)
		(stroke
			(width 0.254)
			(type default)
		)
		(layer "In6.Cu")
	)
	(gr_line
		(start 391.439654 -12.461748)
		(end 391.439654 -10.023348)
		(stroke
			(width 0.254)
			(type default)
		)
		(layer "In6.Cu")
	)
	(gr_line
		(start 391.439654 -12.361672)
		(end 391.439654 -9.923272)
		(stroke
			(width 0.254)
			(type default)
		)
		(layer "In6.Cu")
	)
	(gr_line
		(start 391.439654 -10.023348)
		(end 392.277854 -10.023348)
		(stroke
			(width 0.254)
			(type default)
		)
		(layer "In6.Cu")
	)
	(gr_line
		(start 391.439654 -9.923272)
		(end 392.277854 -9.923272)
		(stroke
			(width 0.254)
			(type default)
		)
		(layer "In6.Cu")
	)
	(gr_line
		(start 391.439654 -8.261604)
		(end 391.439654 -5.823204)
		(stroke
			(width 0.254)
			(type default)
		)
		(layer "In6.Cu")
	)
	(gr_line
		(start 391.439654 -8.161528)
		(end 391.439654 -5.723128)
		(stroke
			(width 0.254)
			(type default)
		)
		(layer "In6.Cu")
	)
	(gr_line
		(start 391.439654 -5.823204)
		(end 392.277854 -5.823204)
		(stroke
			(width 0.254)
			(type default)
		)
		(layer "In6.Cu")
	)
	(gr_line
		(start 391.439654 -5.723128)
		(end 392.277854 -5.723128)
		(stroke
			(width 0.254)
			(type default)
		)
		(layer "In6.Cu")
	)
	(gr_line
		(start 391.465054 -12.436348)
		(end 391.465054 -10.048748)
		(stroke
			(width 0.254)
			(type default)
		)
		(layer "In6.Cu")
	)
	(gr_line
		(start 391.465054 -12.336272)
		(end 391.465054 -9.948672)
		(stroke
			(width 0.254)
			(type default)
		)
		(layer "In6.Cu")
	)
	(gr_line
		(start 391.465054 -10.048748)
		(end 392.252454 -10.048748)
		(stroke
			(width 0.254)
			(type default)
		)
		(layer "In6.Cu")
	)
	(gr_line
		(start 391.465054 -9.948672)
		(end 392.252454 -9.948672)
		(stroke
			(width 0.254)
			(type default)
		)
		(layer "In6.Cu")
	)
	(gr_line
		(start 391.465054 -8.236204)
		(end 391.465054 -5.848604)
		(stroke
			(width 0.254)
			(type default)
		)
		(layer "In6.Cu")
	)
	(gr_line
		(start 391.465054 -8.136128)
		(end 391.465054 -5.748528)
		(stroke
			(width 0.254)
			(type default)
		)
		(layer "In6.Cu")
	)
	(gr_line
		(start 391.465054 -5.848604)
		(end 392.252454 -5.848604)
		(stroke
			(width 0.254)
			(type default)
		)
		(layer "In6.Cu")
	)
	(gr_line
		(start 391.465054 -5.748528)
		(end 392.252454 -5.748528)
		(stroke
			(width 0.254)
			(type default)
		)
		(layer "In6.Cu")
	)
	(gr_line
		(start 391.490454 -12.360148)
		(end 392.125454 -12.360148)
		(stroke
			(width 0.508)
			(type default)
		)
		(layer "In6.Cu")
	)
	(gr_line
		(start 391.490454 -12.260072)
		(end 392.125454 -12.260072)
		(stroke
			(width 0.508)
			(type default)
		)
		(layer "In6.Cu")
	)
	(gr_line
		(start 391.490454 -10.175748)
		(end 392.125454 -10.175748)
		(stroke
			(width 0.508)
			(type default)
		)
		(layer "In6.Cu")
	)
	(gr_line
		(start 391.490454 -10.124948)
		(end 392.125454 -10.124948)
		(stroke
			(width 0.508)
			(type default)
		)
		(layer "In6.Cu")
	)
	(gr_line
		(start 391.490454 -10.075672)
		(end 392.125454 -10.075672)
		(stroke
			(width 0.508)
			(type default)
		)
		(layer "In6.Cu")
	)
	(gr_line
		(start 391.490454 -10.024872)
		(end 392.125454 -10.024872)
		(stroke
			(width 0.508)
			(type default)
		)
		(layer "In6.Cu")
	)
	(gr_line
		(start 391.490454 -8.160004)
		(end 392.125454 -8.160004)
		(stroke
			(width 0.508)
			(type default)
		)
		(layer "In6.Cu")
	)
	(gr_line
		(start 391.490454 -8.059928)
		(end 392.125454 -8.059928)
		(stroke
			(width 0.508)
			(type default)
		)
		(layer "In6.Cu")
	)
	(gr_line
		(start 391.490454 -5.975604)
		(end 392.125454 -5.975604)
		(stroke
			(width 0.508)
			(type default)
		)
		(layer "In6.Cu")
	)
	(gr_line
		(start 391.490454 -5.924804)
		(end 392.125454 -5.924804)
		(stroke
			(width 0.508)
			(type default)
		)
		(layer "In6.Cu")
	)
	(gr_line
		(start 391.490454 -5.875528)
		(end 392.125454 -5.875528)
		(stroke
			(width 0.508)
			(type default)
		)
		(layer "In6.Cu")
	)
	(gr_line
		(start 391.490454 -5.824728)
		(end 392.125454 -5.824728)
		(stroke
			(width 0.508)
			(type default)
		)
		(layer "In6.Cu")
	)
	(gr_line
		(start 391.515854 -10.429748)
		(end 392.150854 -10.429748)
		(stroke
			(width 0.508)
			(type default)
		)
		(layer "In6.Cu")
	)
	(gr_line
		(start 391.515854 -10.329672)
		(end 392.150854 -10.329672)
		(stroke
			(width 0.508)
			(type default)
		)
		(layer "In6.Cu")
	)
	(gr_line
		(start 391.515854 -6.229604)
		(end 392.150854 -6.229604)
		(stroke
			(width 0.508)
			(type default)
		)
		(layer "In6.Cu")
	)
	(gr_line
		(start 391.515854 -6.129528)
		(end 392.150854 -6.129528)
		(stroke
			(width 0.508)
			(type default)
		)
		(layer "In6.Cu")
	)
	(gr_line
		(start 391.541254 -12.385548)
		(end 391.541254 -10.124948)
		(stroke
			(width 0.254)
			(type default)
		)
		(layer "In6.Cu")
	)
	(gr_line
		(start 391.541254 -12.285472)
		(end 391.541254 -10.024872)
		(stroke
			(width 0.254)
			(type default)
		)
		(layer "In6.Cu")
	)
	(gr_line
		(start 391.541254 -12.233148)
		(end 392.176254 -12.233148)
		(stroke
			(width 0.508)
			(type default)
		)
		(layer "In6.Cu")
	)
	(gr_line
		(start 391.541254 -12.133072)
		(end 392.176254 -12.133072)
		(stroke
			(width 0.508)
			(type default)
		)
		(layer "In6.Cu")
	)
	(gr_line
		(start 391.541254 -10.124948)
		(end 392.176254 -10.124948)
		(stroke
			(width 0.254)
			(type default)
		)
		(layer "In6.Cu")
	)
	(gr_line
		(start 391.541254 -10.024872)
		(end 392.176254 -10.024872)
		(stroke
			(width 0.254)
			(type default)
		)
		(layer "In6.Cu")
	)
	(gr_line
		(start 391.541254 -8.185404)
		(end 391.541254 -5.924804)
		(stroke
			(width 0.254)
			(type default)
		)
		(layer "In6.Cu")
	)
	(gr_line
		(start 391.541254 -8.085328)
		(end 391.541254 -5.824728)
		(stroke
			(width 0.254)
			(type default)
		)
		(layer "In6.Cu")
	)
	(gr_line
		(start 391.541254 -8.033004)
		(end 392.176254 -8.033004)
		(stroke
			(width 0.508)
			(type default)
		)
		(layer "In6.Cu")
	)
	(gr_line
		(start 391.541254 -7.932928)
		(end 392.176254 -7.932928)
		(stroke
			(width 0.508)
			(type default)
		)
		(layer "In6.Cu")
	)
	(gr_line
		(start 391.541254 -5.924804)
		(end 392.176254 -5.924804)
		(stroke
			(width 0.254)
			(type default)
		)
		(layer "In6.Cu")
	)
	(gr_line
		(start 391.541254 -5.824728)
		(end 392.176254 -5.824728)
		(stroke
			(width 0.254)
			(type default)
		)
		(layer "In6.Cu")
	)
	(gr_line
		(start 391.566654 -12.080748)
		(end 392.201654 -12.080748)
		(stroke
			(width 0.508)
			(type default)
		)
		(layer "In6.Cu")
	)
	(gr_line
		(start 391.566654 -11.980672)
		(end 392.201654 -11.980672)
		(stroke
			(width 0.508)
			(type default)
		)
		(layer "In6.Cu")
	)
	(gr_line
		(start 391.566654 -7.880604)
		(end 392.201654 -7.880604)
		(stroke
			(width 0.508)
			(type default)
		)
		(layer "In6.Cu")
	)
	(gr_line
		(start 391.566654 -7.780528)
		(end 392.201654 -7.780528)
		(stroke
			(width 0.508)
			(type default)
		)
		(layer "In6.Cu")
	)
	(gr_line
		(start 391.592054 -12.360148)
		(end 392.227054 -12.360148)
		(stroke
			(width 0.508)
			(type default)
		)
		(layer "In6.Cu")
	)
	(gr_line
		(start 391.592054 -12.260072)
		(end 392.227054 -12.260072)
		(stroke
			(width 0.508)
			(type default)
		)
		(layer "In6.Cu")
	)
	(gr_line
		(start 391.592054 -9.947148)
		(end 392.430254 -9.947148)
		(stroke
			(width 0.2032)
			(type default)
		)
		(layer "In6.Cu")
	)
	(gr_line
		(start 391.592054 -9.847072)
		(end 392.430254 -9.847072)
		(stroke
			(width 0.2032)
			(type default)
		)
		(layer "In6.Cu")
	)
	(gr_line
		(start 391.592054 -8.160004)
		(end 392.227054 -8.160004)
		(stroke
			(width 0.508)
			(type default)
		)
		(layer "In6.Cu")
	)
	(gr_line
		(start 391.592054 -8.059928)
		(end 392.227054 -8.059928)
		(stroke
			(width 0.508)
			(type default)
		)
		(layer "In6.Cu")
	)
	(gr_line
		(start 391.592054 -5.747004)
		(end 392.430254 -5.747004)
		(stroke
			(width 0.2032)
			(type default)
		)
		(layer "In6.Cu")
	)
	(gr_line
		(start 391.592054 -5.646928)
		(end 392.430254 -5.646928)
		(stroke
			(width 0.2032)
			(type default)
		)
		(layer "In6.Cu")
	)
	(gr_line
		(start 391.617454 -12.360148)
		(end 391.617454 -10.175748)
		(stroke
			(width 0.254)
			(type default)
		)
		(layer "In6.Cu")
	)
	(gr_line
		(start 391.617454 -12.260072)
		(end 391.617454 -10.075672)
		(stroke
			(width 0.254)
			(type default)
		)
		(layer "In6.Cu")
	)
	(gr_line
		(start 391.617454 -10.175748)
		(end 392.100054 -10.175748)
		(stroke
			(width 0.254)
			(type default)
		)
		(layer "In6.Cu")
	)
	(gr_line
		(start 391.617454 -10.075672)
		(end 392.100054 -10.075672)
		(stroke
			(width 0.254)
			(type default)
		)
		(layer "In6.Cu")
	)
	(gr_line
		(start 391.617454 -9.997948)
		(end 392.354054 -9.997948)
		(stroke
			(width 0.254)
			(type default)
		)
		(layer "In6.Cu")
	)
	(gr_line
		(start 391.617454 -9.897872)
		(end 392.354054 -9.897872)
		(stroke
			(width 0.254)
			(type default)
		)
		(layer "In6.Cu")
	)
	(gr_line
		(start 391.617454 -8.160004)
		(end 391.617454 -5.975604)
		(stroke
			(width 0.254)
			(type default)
		)
		(layer "In6.Cu")
	)
	(gr_line
		(start 391.617454 -8.059928)
		(end 391.617454 -5.875528)
		(stroke
			(width 0.254)
			(type default)
		)
		(layer "In6.Cu")
	)
	(gr_line
		(start 391.617454 -5.975604)
		(end 392.100054 -5.975604)
		(stroke
			(width 0.254)
			(type default)
		)
		(layer "In6.Cu")
	)
	(gr_line
		(start 391.617454 -5.875528)
		(end 392.100054 -5.875528)
		(stroke
			(width 0.254)
			(type default)
		)
		(layer "In6.Cu")
	)
	(gr_line
		(start 391.617454 -5.797804)
		(end 392.354054 -5.797804)
		(stroke
			(width 0.254)
			(type default)
		)
		(layer "In6.Cu")
	)
	(gr_line
		(start 391.617454 -5.697728)
		(end 392.354054 -5.697728)
		(stroke
			(width 0.254)
			(type default)
		)
		(layer "In6.Cu")
	)
	(gr_line
		(start 391.635996 -10.110978)
		(end 392.270996 -10.110978)
		(stroke
			(width 0.508)
			(type default)
		)
		(layer "In6.Cu")
	)
	(gr_line
		(start 391.635996 -10.010902)
		(end 392.270996 -10.010902)
		(stroke
			(width 0.508)
			(type default)
		)
		(layer "In6.Cu")
	)
	(gr_line
		(start 391.635996 -5.910834)
		(end 392.270996 -5.910834)
		(stroke
			(width 0.508)
			(type default)
		)
		(layer "In6.Cu")
	)
	(gr_line
		(start 391.635996 -5.810758)
		(end 392.270996 -5.810758)
		(stroke
			(width 0.508)
			(type default)
		)
		(layer "In6.Cu")
	)
	(gr_line
		(start 391.642854 -12.360148)
		(end 392.277854 -12.360148)
		(stroke
			(width 0.508)
			(type default)
		)
		(layer "In6.Cu")
	)
	(gr_line
		(start 391.642854 -12.260072)
		(end 392.277854 -12.260072)
		(stroke
			(width 0.508)
			(type default)
		)
		(layer "In6.Cu")
	)
	(gr_line
		(start 391.642854 -12.233148)
		(end 391.642854 -10.251948)
		(stroke
			(width 0.762)
			(type default)
		)
		(layer "In6.Cu")
	)
	(gr_line
		(start 391.642854 -12.133072)
		(end 391.642854 -10.151872)
		(stroke
			(width 0.762)
			(type default)
		)
		(layer "In6.Cu")
	)
	(gr_line
		(start 391.642854 -10.251948)
		(end 392.277854 -10.251948)
		(stroke
			(width 0.508)
			(type default)
		)
		(layer "In6.Cu")
	)
	(gr_line
		(start 391.642854 -10.151872)
		(end 392.277854 -10.151872)
		(stroke
			(width 0.508)
			(type default)
		)
		(layer "In6.Cu")
	)
	(gr_line
		(start 391.642854 -8.160004)
		(end 392.277854 -8.160004)
		(stroke
			(width 0.508)
			(type default)
		)
		(layer "In6.Cu")
	)
	(gr_line
		(start 391.642854 -8.059928)
		(end 392.277854 -8.059928)
		(stroke
			(width 0.508)
			(type default)
		)
		(layer "In6.Cu")
	)
	(gr_line
		(start 391.642854 -8.033004)
		(end 391.642854 -6.051804)
		(stroke
			(width 0.762)
			(type default)
		)
		(layer "In6.Cu")
	)
	(gr_line
		(start 391.642854 -7.932928)
		(end 391.642854 -5.951728)
		(stroke
			(width 0.762)
			(type default)
		)
		(layer "In6.Cu")
	)
	(gr_line
		(start 391.642854 -6.051804)
		(end 392.277854 -6.051804)
		(stroke
			(width 0.508)
			(type default)
		)
		(layer "In6.Cu")
	)
	(gr_line
		(start 391.642854 -5.951728)
		(end 392.277854 -5.951728)
		(stroke
			(width 0.508)
			(type default)
		)
		(layer "In6.Cu")
	)
	(gr_line
		(start 391.693654 -12.283948)
		(end 391.693654 -10.251948)
		(stroke
			(width 0.254)
			(type default)
		)
		(layer "In6.Cu")
	)
	(gr_line
		(start 391.693654 -12.183872)
		(end 391.693654 -10.151872)
		(stroke
			(width 0.254)
			(type default)
		)
		(layer "In6.Cu")
	)
	(gr_line
		(start 391.693654 -10.251948)
		(end 392.023854 -10.251948)
		(stroke
			(width 0.254)
			(type default)
		)
		(layer "In6.Cu")
	)
	(gr_line
		(start 391.693654 -10.151872)
		(end 392.023854 -10.151872)
		(stroke
			(width 0.254)
			(type default)
		)
		(layer "In6.Cu")
	)
	(gr_line
		(start 391.693654 -8.083804)
		(end 391.693654 -6.051804)
		(stroke
			(width 0.254)
			(type default)
		)
		(layer "In6.Cu")
	)
	(gr_line
		(start 391.693654 -7.983728)
		(end 391.693654 -5.951728)
		(stroke
			(width 0.254)
			(type default)
		)
		(layer "In6.Cu")
	)
	(gr_line
		(start 391.693654 -6.051804)
		(end 392.023854 -6.051804)
		(stroke
			(width 0.254)
			(type default)
		)
		(layer "In6.Cu")
	)
	(gr_line
		(start 391.693654 -5.951728)
		(end 392.023854 -5.951728)
		(stroke
			(width 0.254)
			(type default)
		)
		(layer "In6.Cu")
	)
	(gr_line
		(start 391.795254 -12.207748)
		(end 391.795254 -10.404348)
		(stroke
			(width 0.254)
			(type default)
		)
		(layer "In6.Cu")
	)
	(gr_line
		(start 391.795254 -12.207748)
		(end 391.795254 -10.226548)
		(stroke
			(width 0.762)
			(type default)
		)
		(layer "In6.Cu")
	)
	(gr_line
		(start 391.795254 -12.107672)
		(end 391.795254 -10.304272)
		(stroke
			(width 0.254)
			(type default)
		)
		(layer "In6.Cu")
	)
	(gr_line
		(start 391.795254 -12.107672)
		(end 391.795254 -10.126472)
		(stroke
			(width 0.762)
			(type default)
		)
		(layer "In6.Cu")
	)
	(gr_line
		(start 391.795254 -10.404348)
		(end 391.896854 -10.404348)
		(stroke
			(width 0.254)
			(type default)
		)
		(layer "In6.Cu")
	)
	(gr_line
		(start 391.795254 -10.304272)
		(end 391.896854 -10.304272)
		(stroke
			(width 0.254)
			(type default)
		)
		(layer "In6.Cu")
	)
	(gr_line
		(start 391.795254 -8.007604)
		(end 391.795254 -6.204204)
		(stroke
			(width 0.254)
			(type default)
		)
		(layer "In6.Cu")
	)
	(gr_line
		(start 391.795254 -8.007604)
		(end 391.795254 -6.026404)
		(stroke
			(width 0.762)
			(type default)
		)
		(layer "In6.Cu")
	)
	(gr_line
		(start 391.795254 -7.907528)
		(end 391.795254 -6.104128)
		(stroke
			(width 0.254)
			(type default)
		)
		(layer "In6.Cu")
	)
	(gr_line
		(start 391.795254 -7.907528)
		(end 391.795254 -5.926328)
		(stroke
			(width 0.762)
			(type default)
		)
		(layer "In6.Cu")
	)
	(gr_line
		(start 391.795254 -6.204204)
		(end 391.896854 -6.204204)
		(stroke
			(width 0.254)
			(type default)
		)
		(layer "In6.Cu")
	)
	(gr_line
		(start 391.795254 -6.104128)
		(end 391.896854 -6.104128)
		(stroke
			(width 0.254)
			(type default)
		)
		(layer "In6.Cu")
	)
	(gr_line
		(start 391.850118 -23.69566)
		(end 393.120118 -23.69566)
		(stroke
			(width 0.7874)
			(type default)
		)
		(layer "In6.Cu")
	)
	(gr_line
		(start 391.896854 -12.309348)
		(end 391.846054 -12.309348)
		(stroke
			(width 0.254)
			(type default)
		)
		(layer "In6.Cu")
	)
	(gr_line
		(start 391.896854 -12.209272)
		(end 391.846054 -12.209272)
		(stroke
			(width 0.254)
			(type default)
		)
		(layer "In6.Cu")
	)
	(gr_line
		(start 391.896854 -10.404348)
		(end 391.896854 -12.309348)
		(stroke
			(width 0.254)
			(type default)
		)
		(layer "In6.Cu")
	)
	(gr_line
		(start 391.896854 -10.304272)
		(end 391.896854 -12.209272)
		(stroke
			(width 0.254)
			(type default)
		)
		(layer "In6.Cu")
	)
	(gr_line
		(start 391.896854 -8.109204)
		(end 391.846054 -8.109204)
		(stroke
			(width 0.254)
			(type default)
		)
		(layer "In6.Cu")
	)
	(gr_line
		(start 391.896854 -8.009128)
		(end 391.846054 -8.009128)
		(stroke
			(width 0.254)
			(type default)
		)
		(layer "In6.Cu")
	)
	(gr_line
		(start 391.896854 -6.204204)
		(end 391.896854 -8.109204)
		(stroke
			(width 0.254)
			(type default)
		)
		(layer "In6.Cu")
	)
	(gr_line
		(start 391.896854 -6.104128)
		(end 391.896854 -8.009128)
		(stroke
			(width 0.254)
			(type default)
		)
		(layer "In6.Cu")
	)
	(gr_line
		(start 391.947654 -12.233148)
		(end 391.947654 -10.251948)
		(stroke
			(width 0.762)
			(type default)
		)
		(layer "In6.Cu")
	)
	(gr_line
		(start 391.947654 -12.133072)
		(end 391.947654 -10.151872)
		(stroke
			(width 0.762)
			(type default)
		)
		(layer "In6.Cu")
	)
	(gr_line
		(start 391.947654 -8.033004)
		(end 391.947654 -6.051804)
		(stroke
			(width 0.762)
			(type default)
		)
		(layer "In6.Cu")
	)
	(gr_line
		(start 391.947654 -7.932928)
		(end 391.947654 -5.951728)
		(stroke
			(width 0.762)
			(type default)
		)
		(layer "In6.Cu")
	)
	(gr_line
		(start 392.023854 -12.207748)
		(end 391.795254 -12.207748)
		(stroke
			(width 0.254)
			(type default)
		)
		(layer "In6.Cu")
	)
	(gr_line
		(start 392.023854 -12.107672)
		(end 391.795254 -12.107672)
		(stroke
			(width 0.254)
			(type default)
		)
		(layer "In6.Cu")
	)
	(gr_line
		(start 392.023854 -10.251948)
		(end 392.023854 -12.207748)
		(stroke
			(width 0.254)
			(type default)
		)
		(layer "In6.Cu")
	)
	(gr_line
		(start 392.023854 -10.151872)
		(end 392.023854 -12.107672)
		(stroke
			(width 0.254)
			(type default)
		)
		(layer "In6.Cu")
	)
	(gr_line
		(start 392.023854 -8.007604)
		(end 391.795254 -8.007604)
		(stroke
			(width 0.254)
			(type default)
		)
		(layer "In6.Cu")
	)
	(gr_line
		(start 392.023854 -7.907528)
		(end 391.795254 -7.907528)
		(stroke
			(width 0.254)
			(type default)
		)
		(layer "In6.Cu")
	)
	(gr_line
		(start 392.023854 -6.051804)
		(end 392.023854 -8.007604)
		(stroke
			(width 0.254)
			(type default)
		)
		(layer "In6.Cu")
	)
	(gr_line
		(start 392.023854 -5.951728)
		(end 392.023854 -7.907528)
		(stroke
			(width 0.254)
			(type default)
		)
		(layer "In6.Cu")
	)
	(gr_line
		(start 392.074654 -12.563348)
		(end 392.074654 -12.512548)
		(stroke
			(width 0.1016)
			(type default)
		)
		(layer "In6.Cu")
	)
	(gr_line
		(start 392.074654 -12.563348)
		(end 392.481054 -12.563348)
		(stroke
			(width 0.1016)
			(type default)
		)
		(layer "In6.Cu")
	)
	(gr_line
		(start 392.074654 -12.512548)
		(end 391.312654 -12.512548)
		(stroke
			(width 0.1016)
			(type default)
		)
		(layer "In6.Cu")
	)
	(gr_line
		(start 392.074654 -12.463272)
		(end 392.074654 -12.412472)
		(stroke
			(width 0.1016)
			(type default)
		)
		(layer "In6.Cu")
	)
	(gr_line
		(start 392.074654 -12.463272)
		(end 392.481054 -12.463272)
		(stroke
			(width 0.1016)
			(type default)
		)
		(layer "In6.Cu")
	)
	(gr_line
		(start 392.074654 -12.412472)
		(end 391.312654 -12.412472)
		(stroke
			(width 0.1016)
			(type default)
		)
		(layer "In6.Cu")
	)
	(gr_line
		(start 392.074654 -12.233148)
		(end 392.074654 -10.251948)
		(stroke
			(width 0.762)
			(type default)
		)
		(layer "In6.Cu")
	)
	(gr_line
		(start 392.074654 -12.133072)
		(end 392.074654 -10.151872)
		(stroke
			(width 0.762)
			(type default)
		)
		(layer "In6.Cu")
	)
	(gr_line
		(start 392.074654 -8.363204)
		(end 392.074654 -8.312404)
		(stroke
			(width 0.1016)
			(type default)
		)
		(layer "In6.Cu")
	)
	(gr_line
		(start 392.074654 -8.363204)
		(end 392.481054 -8.363204)
		(stroke
			(width 0.1016)
			(type default)
		)
		(layer "In6.Cu")
	)
	(gr_line
		(start 392.074654 -8.312404)
		(end 391.312654 -8.312404)
		(stroke
			(width 0.1016)
			(type default)
		)
		(layer "In6.Cu")
	)
	(gr_line
		(start 392.074654 -8.263128)
		(end 392.074654 -8.212328)
		(stroke
			(width 0.1016)
			(type default)
		)
		(layer "In6.Cu")
	)
	(gr_line
		(start 392.074654 -8.263128)
		(end 392.481054 -8.263128)
		(stroke
			(width 0.1016)
			(type default)
		)
		(layer "In6.Cu")
	)
	(gr_line
		(start 392.074654 -8.212328)
		(end 391.312654 -8.212328)
		(stroke
			(width 0.1016)
			(type default)
		)
		(layer "In6.Cu")
	)
	(gr_line
		(start 392.074654 -8.033004)
		(end 392.074654 -6.051804)
		(stroke
			(width 0.762)
			(type default)
		)
		(layer "In6.Cu")
	)
	(gr_line
		(start 392.074654 -7.932928)
		(end 392.074654 -5.951728)
		(stroke
			(width 0.762)
			(type default)
		)
		(layer "In6.Cu")
	)
	(gr_line
		(start 392.100054 -12.283948)
		(end 391.693654 -12.283948)
		(stroke
			(width 0.254)
			(type default)
		)
		(layer "In6.Cu")
	)
	(gr_line
		(start 392.100054 -12.183872)
		(end 391.693654 -12.183872)
		(stroke
			(width 0.254)
			(type default)
		)
		(layer "In6.Cu")
	)
	(gr_line
		(start 392.100054 -10.175748)
		(end 392.100054 -12.283948)
		(stroke
			(width 0.254)
			(type default)
		)
		(layer "In6.Cu")
	)
	(gr_line
		(start 392.100054 -10.075672)
		(end 392.100054 -12.183872)
		(stroke
			(width 0.254)
			(type default)
		)
		(layer "In6.Cu")
	)
	(gr_line
		(start 392.100054 -8.083804)
		(end 391.693654 -8.083804)
		(stroke
			(width 0.254)
			(type default)
		)
		(layer "In6.Cu")
	)
	(gr_line
		(start 392.100054 -7.983728)
		(end 391.693654 -7.983728)
		(stroke
			(width 0.254)
			(type default)
		)
		(layer "In6.Cu")
	)
	(gr_line
		(start 392.100054 -5.975604)
		(end 392.100054 -8.083804)
		(stroke
			(width 0.254)
			(type default)
		)
		(layer "In6.Cu")
	)
	(gr_line
		(start 392.100054 -5.875528)
		(end 392.100054 -7.983728)
		(stroke
			(width 0.254)
			(type default)
		)
		(layer "In6.Cu")
	)
	(gr_line
		(start 392.150854 -12.233148)
		(end 392.150854 -10.251948)
		(stroke
			(width 0.762)
			(type default)
		)
		(layer "In6.Cu")
	)
	(gr_line
		(start 392.150854 -12.133072)
		(end 392.150854 -10.151872)
		(stroke
			(width 0.762)
			(type default)
		)
		(layer "In6.Cu")
	)
	(gr_line
		(start 392.150854 -8.033004)
		(end 392.150854 -6.051804)
		(stroke
			(width 0.762)
			(type default)
		)
		(layer "In6.Cu")
	)
	(gr_line
		(start 392.150854 -7.932928)
		(end 392.150854 -5.951728)
		(stroke
			(width 0.762)
			(type default)
		)
		(layer "In6.Cu")
	)
	(gr_line
		(start 392.176254 -12.360148)
		(end 391.617454 -12.360148)
		(stroke
			(width 0.254)
			(type default)
		)
		(layer "In6.Cu")
	)
	(gr_line
		(start 392.176254 -12.260072)
		(end 391.617454 -12.260072)
		(stroke
			(width 0.254)
			(type default)
		)
		(layer "In6.Cu")
	)
	(gr_line
		(start 392.176254 -10.124948)
		(end 392.176254 -12.360148)
		(stroke
			(width 0.254)
			(type default)
		)
		(layer "In6.Cu")
	)
	(gr_line
		(start 392.176254 -10.024872)
		(end 392.176254 -12.260072)
		(stroke
			(width 0.254)
			(type default)
		)
		(layer "In6.Cu")
	)
	(gr_line
		(start 392.176254 -8.160004)
		(end 391.617454 -8.160004)
		(stroke
			(width 0.254)
			(type default)
		)
		(layer "In6.Cu")
	)
	(gr_line
		(start 392.176254 -8.059928)
		(end 391.617454 -8.059928)
		(stroke
			(width 0.254)
			(type default)
		)
		(layer "In6.Cu")
	)
	(gr_line
		(start 392.176254 -5.924804)
		(end 392.176254 -8.160004)
		(stroke
			(width 0.254)
			(type default)
		)
		(layer "In6.Cu")
	)
	(gr_line
		(start 392.176254 -5.824728)
		(end 392.176254 -8.059928)
		(stroke
			(width 0.254)
			(type default)
		)
		(layer "In6.Cu")
	)
	(gr_line
		(start 392.252454 -12.385548)
		(end 391.541254 -12.385548)
		(stroke
			(width 0.254)
			(type default)
		)
		(layer "In6.Cu")
	)
	(gr_line
		(start 392.252454 -12.285472)
		(end 391.541254 -12.285472)
		(stroke
			(width 0.254)
			(type default)
		)
		(layer "In6.Cu")
	)
	(gr_line
		(start 392.252454 -10.048748)
		(end 392.252454 -12.385548)
		(stroke
			(width 0.254)
			(type default)
		)
		(layer "In6.Cu")
	)
	(gr_line
		(start 392.252454 -9.948672)
		(end 392.252454 -12.285472)
		(stroke
			(width 0.254)
			(type default)
		)
		(layer "In6.Cu")
	)
	(gr_line
		(start 392.252454 -8.185404)
		(end 391.541254 -8.185404)
		(stroke
			(width 0.254)
			(type default)
		)
		(layer "In6.Cu")
	)
	(gr_line
		(start 392.252454 -8.085328)
		(end 391.541254 -8.085328)
		(stroke
			(width 0.254)
			(type default)
		)
		(layer "In6.Cu")
	)
	(gr_line
		(start 392.252454 -5.848604)
		(end 392.252454 -8.185404)
		(stroke
			(width 0.254)
			(type default)
		)
		(layer "In6.Cu")
	)
	(gr_line
		(start 392.252454 -5.748528)
		(end 392.252454 -8.085328)
		(stroke
			(width 0.254)
			(type default)
		)
		(layer "In6.Cu")
	)
	(gr_line
		(start 392.277854 -12.512548)
		(end 391.287254 -12.512548)
		(stroke
			(width 0.1016)
			(type default)
		)
		(layer "In6.Cu")
	)
	(gr_line
		(start 392.277854 -12.436348)
		(end 391.465054 -12.436348)
		(stroke
			(width 0.254)
			(type default)
		)
		(layer "In6.Cu")
	)
	(gr_line
		(start 392.277854 -12.412472)
		(end 391.287254 -12.412472)
		(stroke
			(width 0.1016)
			(type default)
		)
		(layer "In6.Cu")
	)
	(gr_line
		(start 392.277854 -12.336272)
		(end 391.465054 -12.336272)
		(stroke
			(width 0.254)
			(type default)
		)
		(layer "In6.Cu")
	)
	(gr_line
		(start 392.277854 -10.023348)
		(end 392.277854 -12.436348)
		(stroke
			(width 0.254)
			(type default)
		)
		(layer "In6.Cu")
	)
	(gr_line
		(start 392.277854 -9.923272)
		(end 392.277854 -12.336272)
		(stroke
			(width 0.254)
			(type default)
		)
		(layer "In6.Cu")
	)
	(gr_line
		(start 392.277854 -8.312404)
		(end 391.287254 -8.312404)
		(stroke
			(width 0.1016)
			(type default)
		)
		(layer "In6.Cu")
	)
	(gr_line
		(start 392.277854 -8.236204)
		(end 391.465054 -8.236204)
		(stroke
			(width 0.254)
			(type default)
		)
		(layer "In6.Cu")
	)
	(gr_line
		(start 392.277854 -8.212328)
		(end 391.287254 -8.212328)
		(stroke
			(width 0.1016)
			(type default)
		)
		(layer "In6.Cu")
	)
	(gr_line
		(start 392.277854 -8.136128)
		(end 391.465054 -8.136128)
		(stroke
			(width 0.254)
			(type default)
		)
		(layer "In6.Cu")
	)
	(gr_line
		(start 392.277854 -5.823204)
		(end 392.277854 -8.236204)
		(stroke
			(width 0.254)
			(type default)
		)
		(layer "In6.Cu")
	)
	(gr_line
		(start 392.277854 -5.723128)
		(end 392.277854 -8.136128)
		(stroke
			(width 0.254)
			(type default)
		)
		(layer "In6.Cu")
	)
	(gr_line
		(start 392.303254 -12.461748)
		(end 391.439654 -12.461748)
		(stroke
			(width 0.254)
			(type default)
		)
		(layer "In6.Cu")
	)
	(gr_line
		(start 392.303254 -12.361672)
		(end 391.439654 -12.361672)
		(stroke
			(width 0.254)
			(type default)
		)
		(layer "In6.Cu")
	)
	(gr_line
		(start 392.303254 -9.997948)
		(end 392.303254 -12.461748)
		(stroke
			(width 0.254)
			(type default)
		)
		(layer "In6.Cu")
	)
	(gr_line
		(start 392.303254 -9.897872)
		(end 392.303254 -12.361672)
		(stroke
			(width 0.254)
			(type default)
		)
		(layer "In6.Cu")
	)
	(gr_line
		(start 392.303254 -8.261604)
		(end 391.439654 -8.261604)
		(stroke
			(width 0.254)
			(type default)
		)
		(layer "In6.Cu")
	)
	(gr_line
		(start 392.303254 -8.161528)
		(end 391.439654 -8.161528)
		(stroke
			(width 0.254)
			(type default)
		)
		(layer "In6.Cu")
	)
	(gr_line
		(start 392.303254 -5.797804)
		(end 392.303254 -8.261604)
		(stroke
			(width 0.254)
			(type default)
		)
		(layer "In6.Cu")
	)
	(gr_line
		(start 392.303254 -5.697728)
		(end 392.303254 -8.161528)
		(stroke
			(width 0.254)
			(type default)
		)
		(layer "In6.Cu")
	)
	(gr_line
		(start 392.354054 -12.487148)
		(end 391.414254 -12.487148)
		(stroke
			(width 0.254)
			(type default)
		)
		(layer "In6.Cu")
	)
	(gr_line
		(start 392.354054 -12.387072)
		(end 391.414254 -12.387072)
		(stroke
			(width 0.254)
			(type default)
		)
		(layer "In6.Cu")
	)
	(gr_line
		(start 392.354054 -9.997948)
		(end 392.354054 -12.487148)
		(stroke
			(width 0.254)
			(type default)
		)
		(layer "In6.Cu")
	)
	(gr_line
		(start 392.354054 -9.897872)
		(end 392.354054 -12.387072)
		(stroke
			(width 0.254)
			(type default)
		)
		(layer "In6.Cu")
	)
	(gr_line
		(start 392.354054 -8.287004)
		(end 391.414254 -8.287004)
		(stroke
			(width 0.254)
			(type default)
		)
		(layer "In6.Cu")
	)
	(gr_line
		(start 392.354054 -8.186928)
		(end 391.414254 -8.186928)
		(stroke
			(width 0.254)
			(type default)
		)
		(layer "In6.Cu")
	)
	(gr_line
		(start 392.354054 -5.797804)
		(end 392.354054 -8.287004)
		(stroke
			(width 0.254)
			(type default)
		)
		(layer "In6.Cu")
	)
	(gr_line
		(start 392.354054 -5.697728)
		(end 392.354054 -8.186928)
		(stroke
			(width 0.254)
			(type default)
		)
		(layer "In6.Cu")
	)
	(gr_line
		(start 392.379454 -12.487148)
		(end 391.414254 -12.487148)
		(stroke
			(width 0.2032)
			(type default)
		)
		(layer "In6.Cu")
	)
	(gr_line
		(start 392.379454 -12.387072)
		(end 391.414254 -12.387072)
		(stroke
			(width 0.2032)
			(type default)
		)
		(layer "In6.Cu")
	)
	(gr_line
		(start 392.379454 -9.947148)
		(end 392.379454 -12.487148)
		(stroke
			(width 0.2032)
			(type default)
		)
		(layer "In6.Cu")
	)
	(gr_line
		(start 392.379454 -9.847072)
		(end 392.379454 -12.387072)
		(stroke
			(width 0.2032)
			(type default)
		)
		(layer "In6.Cu")
	)
	(gr_line
		(start 392.379454 -8.287004)
		(end 391.414254 -8.287004)
		(stroke
			(width 0.2032)
			(type default)
		)
		(layer "In6.Cu")
	)
	(gr_line
		(start 392.379454 -8.186928)
		(end 391.414254 -8.186928)
		(stroke
			(width 0.2032)
			(type default)
		)
		(layer "In6.Cu")
	)
	(gr_line
		(start 392.379454 -5.747004)
		(end 392.379454 -8.287004)
		(stroke
			(width 0.2032)
			(type default)
		)
		(layer "In6.Cu")
	)
	(gr_line
		(start 392.379454 -5.646928)
		(end 392.379454 -8.186928)
		(stroke
			(width 0.2032)
			(type default)
		)
		(layer "In6.Cu")
	)
	(gr_line
		(start 392.430254 -12.512548)
		(end 391.363454 -12.512548)
		(stroke
			(width 0.2032)
			(type default)
		)
		(layer "In6.Cu")
	)
	(gr_line
		(start 392.430254 -12.412472)
		(end 391.363454 -12.412472)
		(stroke
			(width 0.2032)
			(type default)
		)
		(layer "In6.Cu")
	)
	(gr_line
		(start 392.430254 -9.947148)
		(end 392.430254 -12.512548)
		(stroke
			(width 0.2032)
			(type default)
		)
		(layer "In6.Cu")
	)
	(gr_line
		(start 392.430254 -9.847072)
		(end 392.430254 -12.412472)
		(stroke
			(width 0.2032)
			(type default)
		)
		(layer "In6.Cu")
	)
	(gr_line
		(start 392.430254 -8.312404)
		(end 391.363454 -8.312404)
		(stroke
			(width 0.2032)
			(type default)
		)
		(layer "In6.Cu")
	)
	(gr_line
		(start 392.430254 -8.212328)
		(end 391.363454 -8.212328)
		(stroke
			(width 0.2032)
			(type default)
		)
		(layer "In6.Cu")
	)
	(gr_line
		(start 392.430254 -5.747004)
		(end 392.430254 -8.312404)
		(stroke
			(width 0.2032)
			(type default)
		)
		(layer "In6.Cu")
	)
	(gr_line
		(start 392.430254 -5.646928)
		(end 392.430254 -8.212328)
		(stroke
			(width 0.2032)
			(type default)
		)
		(layer "In6.Cu")
	)
	(gr_line
		(start 392.455654 -12.512548)
		(end 391.338054 -12.512548)
		(stroke
			(width 0.1016)
			(type default)
		)
		(layer "In6.Cu")
	)
	(gr_line
		(start 392.455654 -12.412472)
		(end 391.338054 -12.412472)
		(stroke
			(width 0.1016)
			(type default)
		)
		(layer "In6.Cu")
	)
	(gr_line
		(start 392.455654 -9.921748)
		(end 392.455654 -12.512548)
		(stroke
			(width 0.1016)
			(type default)
		)
		(layer "In6.Cu")
	)
	(gr_line
		(start 392.455654 -9.821672)
		(end 392.455654 -12.412472)
		(stroke
			(width 0.1016)
			(type default)
		)
		(layer "In6.Cu")
	)
	(gr_line
		(start 392.455654 -8.312404)
		(end 391.338054 -8.312404)
		(stroke
			(width 0.1016)
			(type default)
		)
		(layer "In6.Cu")
	)
	(gr_line
		(start 392.455654 -8.212328)
		(end 391.338054 -8.212328)
		(stroke
			(width 0.1016)
			(type default)
		)
		(layer "In6.Cu")
	)
	(gr_line
		(start 392.455654 -5.721604)
		(end 392.455654 -8.312404)
		(stroke
			(width 0.1016)
			(type default)
		)
		(layer "In6.Cu")
	)
	(gr_line
		(start 392.455654 -5.621528)
		(end 392.455654 -8.212328)
		(stroke
			(width 0.1016)
			(type default)
		)
		(layer "In6.Cu")
	)
	(gr_line
		(start 392.481054 -12.563348)
		(end 392.074654 -12.563348)
		(stroke
			(width 0.1016)
			(type default)
		)
		(layer "In6.Cu")
	)
	(gr_line
		(start 392.481054 -12.563348)
		(end 392.481054 -9.896348)
		(stroke
			(width 0.1016)
			(type default)
		)
		(layer "In6.Cu")
	)
	(gr_line
		(start 392.481054 -12.463272)
		(end 392.074654 -12.463272)
		(stroke
			(width 0.1016)
			(type default)
		)
		(layer "In6.Cu")
	)
	(gr_line
		(start 392.481054 -12.463272)
		(end 392.481054 -9.796272)
		(stroke
			(width 0.1016)
			(type default)
		)
		(layer "In6.Cu")
	)
	(gr_line
		(start 392.481054 -9.896348)
		(end 391.287254 -9.896348)
		(stroke
			(width 0.1016)
			(type default)
		)
		(layer "In6.Cu")
	)
	(gr_line
		(start 392.481054 -9.896348)
		(end 392.481054 -12.563348)
		(stroke
			(width 0.1016)
			(type default)
		)
		(layer "In6.Cu")
	)
	(gr_line
		(start 392.481054 -9.796272)
		(end 391.287254 -9.796272)
		(stroke
			(width 0.1016)
			(type default)
		)
		(layer "In6.Cu")
	)
	(gr_line
		(start 392.481054 -9.796272)
		(end 392.481054 -12.463272)
		(stroke
			(width 0.1016)
			(type default)
		)
		(layer "In6.Cu")
	)
	(gr_line
		(start 392.481054 -8.363204)
		(end 392.074654 -8.363204)
		(stroke
			(width 0.1016)
			(type default)
		)
		(layer "In6.Cu")
	)
	(gr_line
		(start 392.481054 -8.363204)
		(end 392.481054 -5.696204)
		(stroke
			(width 0.1016)
			(type default)
		)
		(layer "In6.Cu")
	)
	(gr_line
		(start 392.481054 -8.263128)
		(end 392.074654 -8.263128)
		(stroke
			(width 0.1016)
			(type default)
		)
		(layer "In6.Cu")
	)
	(gr_line
		(start 392.481054 -8.263128)
		(end 392.481054 -5.596128)
		(stroke
			(width 0.1016)
			(type default)
		)
		(layer "In6.Cu")
	)
	(gr_line
		(start 392.481054 -5.696204)
		(end 391.287254 -5.696204)
		(stroke
			(width 0.1016)
			(type default)
		)
		(layer "In6.Cu")
	)
	(gr_line
		(start 392.481054 -5.696204)
		(end 392.481054 -8.363204)
		(stroke
			(width 0.1016)
			(type default)
		)
		(layer "In6.Cu")
	)
	(gr_line
		(start 392.481054 -5.596128)
		(end 391.287254 -5.596128)
		(stroke
			(width 0.1016)
			(type default)
		)
		(layer "In6.Cu")
	)
	(gr_line
		(start 392.481054 -5.596128)
		(end 392.481054 -8.263128)
		(stroke
			(width 0.1016)
			(type default)
		)
		(layer "In6.Cu")
	)
	(gr_line
		(start 392.719814 -31.98622)
		(end 391.449814 -31.98622)
		(stroke
			(width 0.7874)
			(type default)
		)
		(layer "In6.Cu")
	)
	(gr_line
		(start 393.28725 -13.8176)
		(end 394.07465 -13.8176)
		(stroke
			(width 0.1016)
			(type default)
		)
		(layer "In6.Cu")
	)
	(gr_line
		(start 393.28725 -13.7668)
		(end 393.28725 -11.1506)
		(stroke
			(width 0.1016)
			(type default)
		)
		(layer "In6.Cu")
	)
	(gr_line
		(start 393.28725 -11.1506)
		(end 393.28725 -13.8176)
		(stroke
			(width 0.1016)
			(type default)
		)
		(layer "In6.Cu")
	)
	(gr_line
		(start 393.28725 -11.1506)
		(end 394.48105 -11.1506)
		(stroke
			(width 0.1016)
			(type default)
		)
		(layer "In6.Cu")
	)
	(gr_line
		(start 393.28725 -9.617456)
		(end 394.07465 -9.617456)
		(stroke
			(width 0.1016)
			(type default)
		)
		(layer "In6.Cu")
	)
	(gr_line
		(start 393.28725 -9.566656)
		(end 393.28725 -6.950456)
		(stroke
			(width 0.1016)
			(type default)
		)
		(layer "In6.Cu")
	)
	(gr_line
		(start 393.28725 -6.950456)
		(end 393.28725 -9.617456)
		(stroke
			(width 0.1016)
			(type default)
		)
		(layer "In6.Cu")
	)
	(gr_line
		(start 393.28725 -6.950456)
		(end 394.48105 -6.950456)
		(stroke
			(width 0.1016)
			(type default)
		)
		(layer "In6.Cu")
	)
	(gr_line
		(start 393.28725 -5.417312)
		(end 394.07465 -5.417312)
		(stroke
			(width 0.1016)
			(type default)
		)
		(layer "In6.Cu")
	)
	(gr_line
		(start 393.28725 -5.366512)
		(end 393.28725 -2.750312)
		(stroke
			(width 0.1016)
			(type default)
		)
		(layer "In6.Cu")
	)
	(gr_line
		(start 393.28725 -2.750312)
		(end 393.28725 -5.417312)
		(stroke
			(width 0.1016)
			(type default)
		)
		(layer "In6.Cu")
	)
	(gr_line
		(start 393.28725 -2.750312)
		(end 394.48105 -2.750312)
		(stroke
			(width 0.1016)
			(type default)
		)
		(layer "In6.Cu")
	)
	(gr_line
		(start 393.31265 -13.7668)
		(end 393.31265 -11.176)
		(stroke
			(width 0.1016)
			(type default)
		)
		(layer "In6.Cu")
	)
	(gr_line
		(start 393.31265 -11.176)
		(end 394.45565 -11.176)
		(stroke
			(width 0.1016)
			(type default)
		)
		(layer "In6.Cu")
	)
	(gr_line
		(start 393.31265 -9.566656)
		(end 393.31265 -6.975856)
		(stroke
			(width 0.1016)
			(type default)
		)
		(layer "In6.Cu")
	)
	(gr_line
		(start 393.31265 -6.975856)
		(end 394.45565 -6.975856)
		(stroke
			(width 0.1016)
			(type default)
		)
		(layer "In6.Cu")
	)
	(gr_line
		(start 393.31265 -5.366512)
		(end 393.31265 -2.775712)
		(stroke
			(width 0.1016)
			(type default)
		)
		(layer "In6.Cu")
	)
	(gr_line
		(start 393.31265 -2.775712)
		(end 394.45565 -2.775712)
		(stroke
			(width 0.1016)
			(type default)
		)
		(layer "In6.Cu")
	)
	(gr_line
		(start 393.33805 -13.7668)
		(end 393.33805 -11.2014)
		(stroke
			(width 0.1016)
			(type default)
		)
		(layer "In6.Cu")
	)
	(gr_line
		(start 393.33805 -11.2014)
		(end 393.59205 -11.2014)
		(stroke
			(width 0.1016)
			(type default)
		)
		(layer "In6.Cu")
	)
	(gr_line
		(start 393.33805 -9.566656)
		(end 393.33805 -7.001256)
		(stroke
			(width 0.1016)
			(type default)
		)
		(layer "In6.Cu")
	)
	(gr_line
		(start 393.33805 -7.001256)
		(end 393.59205 -7.001256)
		(stroke
			(width 0.1016)
			(type default)
		)
		(layer "In6.Cu")
	)
	(gr_line
		(start 393.33805 -5.366512)
		(end 393.33805 -2.801112)
		(stroke
			(width 0.1016)
			(type default)
		)
		(layer "In6.Cu")
	)
	(gr_line
		(start 393.33805 -2.801112)
		(end 393.59205 -2.801112)
		(stroke
			(width 0.1016)
			(type default)
		)
		(layer "In6.Cu")
	)
	(gr_line
		(start 393.36345 -13.7668)
		(end 393.36345 -11.2014)
		(stroke
			(width 0.2032)
			(type default)
		)
		(layer "In6.Cu")
	)
	(gr_line
		(start 393.36345 -11.2014)
		(end 394.37945 -11.2014)
		(stroke
			(width 0.2032)
			(type default)
		)
		(layer "In6.Cu")
	)
	(gr_line
		(start 393.36345 -9.566656)
		(end 393.36345 -7.001256)
		(stroke
			(width 0.2032)
			(type default)
		)
		(layer "In6.Cu")
	)
	(gr_line
		(start 393.36345 -7.001256)
		(end 394.37945 -7.001256)
		(stroke
			(width 0.2032)
			(type default)
		)
		(layer "In6.Cu")
	)
	(gr_line
		(start 393.36345 -5.366512)
		(end 393.36345 -2.801112)
		(stroke
			(width 0.2032)
			(type default)
		)
		(layer "In6.Cu")
	)
	(gr_line
		(start 393.36345 -2.801112)
		(end 394.37945 -2.801112)
		(stroke
			(width 0.2032)
			(type default)
		)
		(layer "In6.Cu")
	)
	(gr_line
		(start 393.41425 -13.7414)
		(end 393.41425 -11.2522)
		(stroke
			(width 0.2032)
			(type default)
		)
		(layer "In6.Cu")
	)
	(gr_line
		(start 393.41425 -13.7414)
		(end 393.41425 -11.2522)
		(stroke
			(width 0.254)
			(type default)
		)
		(layer "In6.Cu")
	)
	(gr_line
		(start 393.41425 -11.2522)
		(end 393.61745 -11.2522)
		(stroke
			(width 0.2032)
			(type default)
		)
		(layer "In6.Cu")
	)
	(gr_line
		(start 393.41425 -11.2522)
		(end 394.30325 -11.2522)
		(stroke
			(width 0.254)
			(type default)
		)
		(layer "In6.Cu")
	)
	(gr_line
		(start 393.41425 -9.541256)
		(end 393.41425 -7.052056)
		(stroke
			(width 0.2032)
			(type default)
		)
		(layer "In6.Cu")
	)
	(gr_line
		(start 393.41425 -9.541256)
		(end 393.41425 -7.052056)
		(stroke
			(width 0.254)
			(type default)
		)
		(layer "In6.Cu")
	)
	(gr_line
		(start 393.41425 -7.052056)
		(end 393.61745 -7.052056)
		(stroke
			(width 0.2032)
			(type default)
		)
		(layer "In6.Cu")
	)
	(gr_line
		(start 393.41425 -7.052056)
		(end 394.30325 -7.052056)
		(stroke
			(width 0.254)
			(type default)
		)
		(layer "In6.Cu")
	)
	(gr_line
		(start 393.41425 -5.341112)
		(end 393.41425 -2.851912)
		(stroke
			(width 0.2032)
			(type default)
		)
		(layer "In6.Cu")
	)
	(gr_line
		(start 393.41425 -5.341112)
		(end 393.41425 -2.851912)
		(stroke
			(width 0.254)
			(type default)
		)
		(layer "In6.Cu")
	)
	(gr_line
		(start 393.41425 -2.851912)
		(end 393.61745 -2.851912)
		(stroke
			(width 0.2032)
			(type default)
		)
		(layer "In6.Cu")
	)
	(gr_line
		(start 393.41425 -2.851912)
		(end 394.30325 -2.851912)
		(stroke
			(width 0.254)
			(type default)
		)
		(layer "In6.Cu")
	)
	(gr_line
		(start 393.43965 -13.716)
		(end 393.43965 -11.2776)
		(stroke
			(width 0.254)
			(type default)
		)
		(layer "In6.Cu")
	)
	(gr_line
		(start 393.43965 -11.2776)
		(end 394.27785 -11.2776)
		(stroke
			(width 0.254)
			(type default)
		)
		(layer "In6.Cu")
	)
	(gr_line
		(start 393.43965 -9.515856)
		(end 393.43965 -7.077456)
		(stroke
			(width 0.254)
			(type default)
		)
		(layer "In6.Cu")
	)
	(gr_line
		(start 393.43965 -7.077456)
		(end 394.27785 -7.077456)
		(stroke
			(width 0.254)
			(type default)
		)
		(layer "In6.Cu")
	)
	(gr_line
		(start 393.43965 -5.315712)
		(end 393.43965 -2.877312)
		(stroke
			(width 0.254)
			(type default)
		)
		(layer "In6.Cu")
	)
	(gr_line
		(start 393.43965 -2.877312)
		(end 394.27785 -2.877312)
		(stroke
			(width 0.254)
			(type default)
		)
		(layer "In6.Cu")
	)
	(gr_line
		(start 393.46505 -13.6906)
		(end 393.46505 -11.303)
		(stroke
			(width 0.254)
			(type default)
		)
		(layer "In6.Cu")
	)
	(gr_line
		(start 393.46505 -11.303)
		(end 394.25245 -11.303)
		(stroke
			(width 0.254)
			(type default)
		)
		(layer "In6.Cu")
	)
	(gr_line
		(start 393.46505 -9.490456)
		(end 393.46505 -7.102856)
		(stroke
			(width 0.254)
			(type default)
		)
		(layer "In6.Cu")
	)
	(gr_line
		(start 393.46505 -7.102856)
		(end 394.25245 -7.102856)
		(stroke
			(width 0.254)
			(type default)
		)
		(layer "In6.Cu")
	)
	(gr_line
		(start 393.46505 -5.290312)
		(end 393.46505 -2.902712)
		(stroke
			(width 0.254)
			(type default)
		)
		(layer "In6.Cu")
	)
	(gr_line
		(start 393.46505 -2.902712)
		(end 394.25245 -2.902712)
		(stroke
			(width 0.254)
			(type default)
		)
		(layer "In6.Cu")
	)
	(gr_line
		(start 393.49045 -13.6144)
		(end 394.12545 -13.6144)
		(stroke
			(width 0.508)
			(type default)
		)
		(layer "In6.Cu")
	)
	(gr_line
		(start 393.49045 -11.43)
		(end 394.12545 -11.43)
		(stroke
			(width 0.508)
			(type default)
		)
		(layer "In6.Cu")
	)
	(gr_line
		(start 393.49045 -11.3792)
		(end 394.12545 -11.3792)
		(stroke
			(width 0.508)
			(type default)
		)
		(layer "In6.Cu")
	)
	(gr_line
		(start 393.49045 -9.414256)
		(end 394.12545 -9.414256)
		(stroke
			(width 0.508)
			(type default)
		)
		(layer "In6.Cu")
	)
	(gr_line
		(start 393.49045 -7.229856)
		(end 394.12545 -7.229856)
		(stroke
			(width 0.508)
			(type default)
		)
		(layer "In6.Cu")
	)
	(gr_line
		(start 393.49045 -7.179056)
		(end 394.12545 -7.179056)
		(stroke
			(width 0.508)
			(type default)
		)
		(layer "In6.Cu")
	)
	(gr_line
		(start 393.49045 -5.214112)
		(end 394.12545 -5.214112)
		(stroke
			(width 0.508)
			(type default)
		)
		(layer "In6.Cu")
	)
	(gr_line
		(start 393.49045 -3.029712)
		(end 394.12545 -3.029712)
		(stroke
			(width 0.508)
			(type default)
		)
		(layer "In6.Cu")
	)
	(gr_line
		(start 393.49045 -2.978912)
		(end 394.12545 -2.978912)
		(stroke
			(width 0.508)
			(type default)
		)
		(layer "In6.Cu")
	)
	(gr_line
		(start 393.51585 -11.684)
		(end 394.15085 -11.684)
		(stroke
			(width 0.508)
			(type default)
		)
		(layer "In6.Cu")
	)
	(gr_line
		(start 393.51585 -7.483856)
		(end 394.15085 -7.483856)
		(stroke
			(width 0.508)
			(type default)
		)
		(layer "In6.Cu")
	)
	(gr_line
		(start 393.51585 -3.283712)
		(end 394.15085 -3.283712)
		(stroke
			(width 0.508)
			(type default)
		)
		(layer "In6.Cu")
	)
	(gr_line
		(start 393.54125 -13.6398)
		(end 393.54125 -11.3792)
		(stroke
			(width 0.254)
			(type default)
		)
		(layer "In6.Cu")
	)
	(gr_line
		(start 393.54125 -13.4874)
		(end 394.17625 -13.4874)
		(stroke
			(width 0.508)
			(type default)
		)
		(layer "In6.Cu")
	)
	(gr_line
		(start 393.54125 -11.3792)
		(end 394.17625 -11.3792)
		(stroke
			(width 0.254)
			(type default)
		)
		(layer "In6.Cu")
	)
	(gr_line
		(start 393.54125 -9.439656)
		(end 393.54125 -7.179056)
		(stroke
			(width 0.254)
			(type default)
		)
		(layer "In6.Cu")
	)
	(gr_line
		(start 393.54125 -9.287256)
		(end 394.17625 -9.287256)
		(stroke
			(width 0.508)
			(type default)
		)
		(layer "In6.Cu")
	)
	(gr_line
		(start 393.54125 -7.179056)
		(end 394.17625 -7.179056)
		(stroke
			(width 0.254)
			(type default)
		)
		(layer "In6.Cu")
	)
	(gr_line
		(start 393.54125 -5.239512)
		(end 393.54125 -2.978912)
		(stroke
			(width 0.254)
			(type default)
		)
		(layer "In6.Cu")
	)
	(gr_line
		(start 393.54125 -5.087112)
		(end 394.17625 -5.087112)
		(stroke
			(width 0.508)
			(type default)
		)
		(layer "In6.Cu")
	)
	(gr_line
		(start 393.54125 -2.978912)
		(end 394.17625 -2.978912)
		(stroke
			(width 0.254)
			(type default)
		)
		(layer "In6.Cu")
	)
	(gr_line
		(start 393.56665 -13.335)
		(end 394.20165 -13.335)
		(stroke
			(width 0.508)
			(type default)
		)
		(layer "In6.Cu")
	)
	(gr_line
		(start 393.56665 -9.134856)
		(end 394.20165 -9.134856)
		(stroke
			(width 0.508)
			(type default)
		)
		(layer "In6.Cu")
	)
	(gr_line
		(start 393.56665 -4.934712)
		(end 394.20165 -4.934712)
		(stroke
			(width 0.508)
			(type default)
		)
		(layer "In6.Cu")
	)
	(gr_line
		(start 393.59205 -13.6144)
		(end 394.22705 -13.6144)
		(stroke
			(width 0.508)
			(type default)
		)
		(layer "In6.Cu")
	)
	(gr_line
		(start 393.59205 -11.2014)
		(end 394.43025 -11.2014)
		(stroke
			(width 0.2032)
			(type default)
		)
		(layer "In6.Cu")
	)
	(gr_line
		(start 393.59205 -9.414256)
		(end 394.22705 -9.414256)
		(stroke
			(width 0.508)
			(type default)
		)
		(layer "In6.Cu")
	)
	(gr_line
		(start 393.59205 -7.001256)
		(end 394.43025 -7.001256)
		(stroke
			(width 0.2032)
			(type default)
		)
		(layer "In6.Cu")
	)
	(gr_line
		(start 393.59205 -5.214112)
		(end 394.22705 -5.214112)
		(stroke
			(width 0.508)
			(type default)
		)
		(layer "In6.Cu")
	)
	(gr_line
		(start 393.59205 -2.801112)
		(end 394.43025 -2.801112)
		(stroke
			(width 0.2032)
			(type default)
		)
		(layer "In6.Cu")
	)
	(gr_line
		(start 393.61745 -13.6144)
		(end 393.61745 -11.43)
		(stroke
			(width 0.254)
			(type default)
		)
		(layer "In6.Cu")
	)
	(gr_line
		(start 393.61745 -11.43)
		(end 394.10005 -11.43)
		(stroke
			(width 0.254)
			(type default)
		)
		(layer "In6.Cu")
	)
	(gr_line
		(start 393.61745 -11.2522)
		(end 394.35405 -11.2522)
		(stroke
			(width 0.254)
			(type default)
		)
		(layer "In6.Cu")
	)
	(gr_line
		(start 393.61745 -9.414256)
		(end 393.61745 -7.229856)
		(stroke
			(width 0.254)
			(type default)
		)
		(layer "In6.Cu")
	)
	(gr_line
		(start 393.61745 -7.229856)
		(end 394.10005 -7.229856)
		(stroke
			(width 0.254)
			(type default)
		)
		(layer "In6.Cu")
	)
	(gr_line
		(start 393.61745 -7.052056)
		(end 394.35405 -7.052056)
		(stroke
			(width 0.254)
			(type default)
		)
		(layer "In6.Cu")
	)
	(gr_line
		(start 393.61745 -5.214112)
		(end 393.61745 -3.029712)
		(stroke
			(width 0.254)
			(type default)
		)
		(layer "In6.Cu")
	)
	(gr_line
		(start 393.61745 -3.029712)
		(end 394.10005 -3.029712)
		(stroke
			(width 0.254)
			(type default)
		)
		(layer "In6.Cu")
	)
	(gr_line
		(start 393.61745 -2.851912)
		(end 394.35405 -2.851912)
		(stroke
			(width 0.254)
			(type default)
		)
		(layer "In6.Cu")
	)
	(gr_line
		(start 393.635992 -11.36523)
		(end 394.270992 -11.36523)
		(stroke
			(width 0.508)
			(type default)
		)
		(layer "In6.Cu")
	)
	(gr_line
		(start 393.635992 -7.165086)
		(end 394.270992 -7.165086)
		(stroke
			(width 0.508)
			(type default)
		)
		(layer "In6.Cu")
	)
	(gr_line
		(start 393.635992 -2.964942)
		(end 394.270992 -2.964942)
		(stroke
			(width 0.508)
			(type default)
		)
		(layer "In6.Cu")
	)
	(gr_line
		(start 393.64285 -13.6144)
		(end 394.27785 -13.6144)
		(stroke
			(width 0.508)
			(type default)
		)
		(layer "In6.Cu")
	)
	(gr_line
		(start 393.64285 -13.4874)
		(end 393.64285 -11.5062)
		(stroke
			(width 0.762)
			(type default)
		)
		(layer "In6.Cu")
	)
	(gr_line
		(start 393.64285 -11.5062)
		(end 394.27785 -11.5062)
		(stroke
			(width 0.508)
			(type default)
		)
		(layer "In6.Cu")
	)
	(gr_line
		(start 393.64285 -9.414256)
		(end 394.27785 -9.414256)
		(stroke
			(width 0.508)
			(type default)
		)
		(layer "In6.Cu")
	)
	(gr_line
		(start 393.64285 -9.287256)
		(end 393.64285 -7.306056)
		(stroke
			(width 0.762)
			(type default)
		)
		(layer "In6.Cu")
	)
	(gr_line
		(start 393.64285 -7.306056)
		(end 394.27785 -7.306056)
		(stroke
			(width 0.508)
			(type default)
		)
		(layer "In6.Cu")
	)
	(gr_line
		(start 393.64285 -5.214112)
		(end 394.27785 -5.214112)
		(stroke
			(width 0.508)
			(type default)
		)
		(layer "In6.Cu")
	)
	(gr_line
		(start 393.64285 -5.087112)
		(end 393.64285 -3.105912)
		(stroke
			(width 0.762)
			(type default)
		)
		(layer "In6.Cu")
	)
	(gr_line
		(start 393.64285 -3.105912)
		(end 394.27785 -3.105912)
		(stroke
			(width 0.508)
			(type default)
		)
		(layer "In6.Cu")
	)
	(gr_line
		(start 393.69365 -13.5382)
		(end 393.69365 -11.5062)
		(stroke
			(width 0.254)
			(type default)
		)
		(layer "In6.Cu")
	)
	(gr_line
		(start 393.69365 -11.5062)
		(end 394.02385 -11.5062)
		(stroke
			(width 0.254)
			(type default)
		)
		(layer "In6.Cu")
	)
	(gr_line
		(start 393.69365 -9.338056)
		(end 393.69365 -7.306056)
		(stroke
			(width 0.254)
			(type default)
		)
		(layer "In6.Cu")
	)
	(gr_line
		(start 393.69365 -7.306056)
		(end 394.02385 -7.306056)
		(stroke
			(width 0.254)
			(type default)
		)
		(layer "In6.Cu")
	)
	(gr_line
		(start 393.69365 -5.137912)
		(end 393.69365 -3.105912)
		(stroke
			(width 0.254)
			(type default)
		)
		(layer "In6.Cu")
	)
	(gr_line
		(start 393.69365 -3.105912)
		(end 394.02385 -3.105912)
		(stroke
			(width 0.254)
			(type default)
		)
		(layer "In6.Cu")
	)
	(gr_line
		(start 393.79525 -13.462)
		(end 393.79525 -11.6586)
		(stroke
			(width 0.254)
			(type default)
		)
		(layer "In6.Cu")
	)
	(gr_line
		(start 393.79525 -13.462)
		(end 393.79525 -11.4808)
		(stroke
			(width 0.762)
			(type default)
		)
		(layer "In6.Cu")
	)
	(gr_line
		(start 393.79525 -11.6586)
		(end 393.89685 -11.6586)
		(stroke
			(width 0.254)
			(type default)
		)
		(layer "In6.Cu")
	)
	(gr_line
		(start 393.79525 -9.261856)
		(end 393.79525 -7.458456)
		(stroke
			(width 0.254)
			(type default)
		)
		(layer "In6.Cu")
	)
	(gr_line
		(start 393.79525 -9.261856)
		(end 393.79525 -7.280656)
		(stroke
			(width 0.762)
			(type default)
		)
		(layer "In6.Cu")
	)
	(gr_line
		(start 393.79525 -7.458456)
		(end 393.89685 -7.458456)
		(stroke
			(width 0.254)
			(type default)
		)
		(layer "In6.Cu")
	)
	(gr_line
		(start 393.79525 -5.061712)
		(end 393.79525 -3.258312)
		(stroke
			(width 0.254)
			(type default)
		)
		(layer "In6.Cu")
	)
	(gr_line
		(start 393.79525 -5.061712)
		(end 393.79525 -3.080512)
		(stroke
			(width 0.762)
			(type default)
		)
		(layer "In6.Cu")
	)
	(gr_line
		(start 393.79525 -3.258312)
		(end 393.89685 -3.258312)
		(stroke
			(width 0.254)
			(type default)
		)
		(layer "In6.Cu")
	)
	(gr_line
		(start 393.89685 -13.5636)
		(end 393.84605 -13.5636)
		(stroke
			(width 0.254)
			(type default)
		)
		(layer "In6.Cu")
	)
	(gr_line
		(start 393.89685 -11.6586)
		(end 393.89685 -13.5636)
		(stroke
			(width 0.254)
			(type default)
		)
		(layer "In6.Cu")
	)
	(gr_line
		(start 393.89685 -9.363456)
		(end 393.84605 -9.363456)
		(stroke
			(width 0.254)
			(type default)
		)
		(layer "In6.Cu")
	)
	(gr_line
		(start 393.89685 -7.458456)
		(end 393.89685 -9.363456)
		(stroke
			(width 0.254)
			(type default)
		)
		(layer "In6.Cu")
	)
	(gr_line
		(start 393.89685 -5.163312)
		(end 393.84605 -5.163312)
		(stroke
			(width 0.254)
			(type default)
		)
		(layer "In6.Cu")
	)
	(gr_line
		(start 393.89685 -3.258312)
		(end 393.89685 -5.163312)
		(stroke
			(width 0.254)
			(type default)
		)
		(layer "In6.Cu")
	)
	(gr_line
		(start 393.94765 -13.4874)
		(end 393.94765 -11.5062)
		(stroke
			(width 0.762)
			(type default)
		)
		(layer "In6.Cu")
	)
	(gr_line
		(start 393.94765 -9.287256)
		(end 393.94765 -7.306056)
		(stroke
			(width 0.762)
			(type default)
		)
		(layer "In6.Cu")
	)
	(gr_line
		(start 393.94765 -5.087112)
		(end 393.94765 -3.105912)
		(stroke
			(width 0.762)
			(type default)
		)
		(layer "In6.Cu")
	)
	(gr_line
		(start 394.02385 -13.462)
		(end 393.79525 -13.462)
		(stroke
			(width 0.254)
			(type default)
		)
		(layer "In6.Cu")
	)
	(gr_line
		(start 394.02385 -11.5062)
		(end 394.02385 -13.462)
		(stroke
			(width 0.254)
			(type default)
		)
		(layer "In6.Cu")
	)
	(gr_line
		(start 394.02385 -9.261856)
		(end 393.79525 -9.261856)
		(stroke
			(width 0.254)
			(type default)
		)
		(layer "In6.Cu")
	)
	(gr_line
		(start 394.02385 -7.306056)
		(end 394.02385 -9.261856)
		(stroke
			(width 0.254)
			(type default)
		)
		(layer "In6.Cu")
	)
	(gr_line
		(start 394.02385 -5.061712)
		(end 393.79525 -5.061712)
		(stroke
			(width 0.254)
			(type default)
		)
		(layer "In6.Cu")
	)
	(gr_line
		(start 394.02385 -3.105912)
		(end 394.02385 -5.061712)
		(stroke
			(width 0.254)
			(type default)
		)
		(layer "In6.Cu")
	)
	(gr_line
		(start 394.07465 -13.8176)
		(end 394.07465 -13.7668)
		(stroke
			(width 0.1016)
			(type default)
		)
		(layer "In6.Cu")
	)
	(gr_line
		(start 394.07465 -13.8176)
		(end 394.48105 -13.8176)
		(stroke
			(width 0.1016)
			(type default)
		)
		(layer "In6.Cu")
	)
	(gr_line
		(start 394.07465 -13.7668)
		(end 393.31265 -13.7668)
		(stroke
			(width 0.1016)
			(type default)
		)
		(layer "In6.Cu")
	)
	(gr_line
		(start 394.07465 -13.4874)
		(end 394.07465 -11.5062)
		(stroke
			(width 0.762)
			(type default)
		)
		(layer "In6.Cu")
	)
	(gr_line
		(start 394.07465 -9.617456)
		(end 394.07465 -9.566656)
		(stroke
			(width 0.1016)
			(type default)
		)
		(layer "In6.Cu")
	)
	(gr_line
		(start 394.07465 -9.617456)
		(end 394.48105 -9.617456)
		(stroke
			(width 0.1016)
			(type default)
		)
		(layer "In6.Cu")
	)
	(gr_line
		(start 394.07465 -9.566656)
		(end 393.31265 -9.566656)
		(stroke
			(width 0.1016)
			(type default)
		)
		(layer "In6.Cu")
	)
	(gr_line
		(start 394.07465 -9.287256)
		(end 394.07465 -7.306056)
		(stroke
			(width 0.762)
			(type default)
		)
		(layer "In6.Cu")
	)
	(gr_line
		(start 394.07465 -5.417312)
		(end 394.07465 -5.366512)
		(stroke
			(width 0.1016)
			(type default)
		)
		(layer "In6.Cu")
	)
	(gr_line
		(start 394.07465 -5.417312)
		(end 394.48105 -5.417312)
		(stroke
			(width 0.1016)
			(type default)
		)
		(layer "In6.Cu")
	)
	(gr_line
		(start 394.07465 -5.366512)
		(end 393.31265 -5.366512)
		(stroke
			(width 0.1016)
			(type default)
		)
		(layer "In6.Cu")
	)
	(gr_line
		(start 394.07465 -5.087112)
		(end 394.07465 -3.105912)
		(stroke
			(width 0.762)
			(type default)
		)
		(layer "In6.Cu")
	)
	(gr_line
		(start 394.10005 -13.5382)
		(end 393.69365 -13.5382)
		(stroke
			(width 0.254)
			(type default)
		)
		(layer "In6.Cu")
	)
	(gr_line
		(start 394.10005 -11.43)
		(end 394.10005 -13.5382)
		(stroke
			(width 0.254)
			(type default)
		)
		(layer "In6.Cu")
	)
	(gr_line
		(start 394.10005 -9.338056)
		(end 393.69365 -9.338056)
		(stroke
			(width 0.254)
			(type default)
		)
		(layer "In6.Cu")
	)
	(gr_line
		(start 394.10005 -7.229856)
		(end 394.10005 -9.338056)
		(stroke
			(width 0.254)
			(type default)
		)
		(layer "In6.Cu")
	)
	(gr_line
		(start 394.10005 -5.137912)
		(end 393.69365 -5.137912)
		(stroke
			(width 0.254)
			(type default)
		)
		(layer "In6.Cu")
	)
	(gr_line
		(start 394.10005 -3.029712)
		(end 394.10005 -5.137912)
		(stroke
			(width 0.254)
			(type default)
		)
		(layer "In6.Cu")
	)
	(gr_line
		(start 394.15085 -13.4874)
		(end 394.15085 -11.5062)
		(stroke
			(width 0.762)
			(type default)
		)
		(layer "In6.Cu")
	)
	(gr_line
		(start 394.15085 -9.287256)
		(end 394.15085 -7.306056)
		(stroke
			(width 0.762)
			(type default)
		)
		(layer "In6.Cu")
	)
	(gr_line
		(start 394.15085 -5.087112)
		(end 394.15085 -3.105912)
		(stroke
			(width 0.762)
			(type default)
		)
		(layer "In6.Cu")
	)
	(gr_line
		(start 394.17625 -13.6144)
		(end 393.61745 -13.6144)
		(stroke
			(width 0.254)
			(type default)
		)
		(layer "In6.Cu")
	)
	(gr_line
		(start 394.17625 -11.3792)
		(end 394.17625 -13.6144)
		(stroke
			(width 0.254)
			(type default)
		)
		(layer "In6.Cu")
	)
	(gr_line
		(start 394.17625 -9.414256)
		(end 393.61745 -9.414256)
		(stroke
			(width 0.254)
			(type default)
		)
		(layer "In6.Cu")
	)
	(gr_line
		(start 394.17625 -7.179056)
		(end 394.17625 -9.414256)
		(stroke
			(width 0.254)
			(type default)
		)
		(layer "In6.Cu")
	)
	(gr_line
		(start 394.17625 -5.214112)
		(end 393.61745 -5.214112)
		(stroke
			(width 0.254)
			(type default)
		)
		(layer "In6.Cu")
	)
	(gr_line
		(start 394.17625 -2.978912)
		(end 394.17625 -5.214112)
		(stroke
			(width 0.254)
			(type default)
		)
		(layer "In6.Cu")
	)
	(gr_line
		(start 394.25245 -13.6398)
		(end 393.54125 -13.6398)
		(stroke
			(width 0.254)
			(type default)
		)
		(layer "In6.Cu")
	)
	(gr_line
		(start 394.25245 -11.303)
		(end 394.25245 -13.6398)
		(stroke
			(width 0.254)
			(type default)
		)
		(layer "In6.Cu")
	)
	(gr_line
		(start 394.25245 -9.439656)
		(end 393.54125 -9.439656)
		(stroke
			(width 0.254)
			(type default)
		)
		(layer "In6.Cu")
	)
	(gr_line
		(start 394.25245 -7.102856)
		(end 394.25245 -9.439656)
		(stroke
			(width 0.254)
			(type default)
		)
		(layer "In6.Cu")
	)
	(gr_line
		(start 394.25245 -5.239512)
		(end 393.54125 -5.239512)
		(stroke
			(width 0.254)
			(type default)
		)
		(layer "In6.Cu")
	)
	(gr_line
		(start 394.25245 -2.902712)
		(end 394.25245 -5.239512)
		(stroke
			(width 0.254)
			(type default)
		)
		(layer "In6.Cu")
	)
	(gr_line
		(start 394.27785 -13.7668)
		(end 393.28725 -13.7668)
		(stroke
			(width 0.1016)
			(type default)
		)
		(layer "In6.Cu")
	)
	(gr_line
		(start 394.27785 -13.6906)
		(end 393.46505 -13.6906)
		(stroke
			(width 0.254)
			(type default)
		)
		(layer "In6.Cu")
	)
	(gr_line
		(start 394.27785 -11.2776)
		(end 394.27785 -13.6906)
		(stroke
			(width 0.254)
			(type default)
		)
		(layer "In6.Cu")
	)
	(gr_line
		(start 394.27785 -9.566656)
		(end 393.28725 -9.566656)
		(stroke
			(width 0.1016)
			(type default)
		)
		(layer "In6.Cu")
	)
	(gr_line
		(start 394.27785 -9.490456)
		(end 393.46505 -9.490456)
		(stroke
			(width 0.254)
			(type default)
		)
		(layer "In6.Cu")
	)
	(gr_line
		(start 394.27785 -7.077456)
		(end 394.27785 -9.490456)
		(stroke
			(width 0.254)
			(type default)
		)
		(layer "In6.Cu")
	)
	(gr_line
		(start 394.27785 -5.366512)
		(end 393.28725 -5.366512)
		(stroke
			(width 0.1016)
			(type default)
		)
		(layer "In6.Cu")
	)
	(gr_line
		(start 394.27785 -5.290312)
		(end 393.46505 -5.290312)
		(stroke
			(width 0.254)
			(type default)
		)
		(layer "In6.Cu")
	)
	(gr_line
		(start 394.27785 -2.877312)
		(end 394.27785 -5.290312)
		(stroke
			(width 0.254)
			(type default)
		)
		(layer "In6.Cu")
	)
	(gr_line
		(start 394.30325 -13.716)
		(end 393.43965 -13.716)
		(stroke
			(width 0.254)
			(type default)
		)
		(layer "In6.Cu")
	)
	(gr_line
		(start 394.30325 -11.2522)
		(end 394.30325 -13.716)
		(stroke
			(width 0.254)
			(type default)
		)
		(layer "In6.Cu")
	)
	(gr_line
		(start 394.30325 -9.515856)
		(end 393.43965 -9.515856)
		(stroke
			(width 0.254)
			(type default)
		)
		(layer "In6.Cu")
	)
	(gr_line
		(start 394.30325 -7.052056)
		(end 394.30325 -9.515856)
		(stroke
			(width 0.254)
			(type default)
		)
		(layer "In6.Cu")
	)
	(gr_line
		(start 394.30325 -5.315712)
		(end 393.43965 -5.315712)
		(stroke
			(width 0.254)
			(type default)
		)
		(layer "In6.Cu")
	)
	(gr_line
		(start 394.30325 -2.851912)
		(end 394.30325 -5.315712)
		(stroke
			(width 0.254)
			(type default)
		)
		(layer "In6.Cu")
	)
	(gr_line
		(start 394.35405 -13.7414)
		(end 393.41425 -13.7414)
		(stroke
			(width 0.254)
			(type default)
		)
		(layer "In6.Cu")
	)
	(gr_line
		(start 394.35405 -11.2522)
		(end 394.35405 -13.7414)
		(stroke
			(width 0.254)
			(type default)
		)
		(layer "In6.Cu")
	)
	(gr_line
		(start 394.35405 -9.541256)
		(end 393.41425 -9.541256)
		(stroke
			(width 0.254)
			(type default)
		)
		(layer "In6.Cu")
	)
	(gr_line
		(start 394.35405 -7.052056)
		(end 394.35405 -9.541256)
		(stroke
			(width 0.254)
			(type default)
		)
		(layer "In6.Cu")
	)
	(gr_line
		(start 394.35405 -5.341112)
		(end 393.41425 -5.341112)
		(stroke
			(width 0.254)
			(type default)
		)
		(layer "In6.Cu")
	)
	(gr_line
		(start 394.35405 -2.851912)
		(end 394.35405 -5.341112)
		(stroke
			(width 0.254)
			(type default)
		)
		(layer "In6.Cu")
	)
	(gr_line
		(start 394.37945 -13.7414)
		(end 393.41425 -13.7414)
		(stroke
			(width 0.2032)
			(type default)
		)
		(layer "In6.Cu")
	)
	(gr_line
		(start 394.37945 -11.2014)
		(end 394.37945 -13.7414)
		(stroke
			(width 0.2032)
			(type default)
		)
		(layer "In6.Cu")
	)
	(gr_line
		(start 394.37945 -9.541256)
		(end 393.41425 -9.541256)
		(stroke
			(width 0.2032)
			(type default)
		)
		(layer "In6.Cu")
	)
	(gr_line
		(start 394.37945 -7.001256)
		(end 394.37945 -9.541256)
		(stroke
			(width 0.2032)
			(type default)
		)
		(layer "In6.Cu")
	)
	(gr_line
		(start 394.37945 -5.341112)
		(end 393.41425 -5.341112)
		(stroke
			(width 0.2032)
			(type default)
		)
		(layer "In6.Cu")
	)
	(gr_line
		(start 394.37945 -2.801112)
		(end 394.37945 -5.341112)
		(stroke
			(width 0.2032)
			(type default)
		)
		(layer "In6.Cu")
	)
	(gr_line
		(start 394.43025 -13.7668)
		(end 393.36345 -13.7668)
		(stroke
			(width 0.2032)
			(type default)
		)
		(layer "In6.Cu")
	)
	(gr_line
		(start 394.43025 -11.2014)
		(end 394.43025 -13.7668)
		(stroke
			(width 0.2032)
			(type default)
		)
		(layer "In6.Cu")
	)
	(gr_line
		(start 394.43025 -9.566656)
		(end 393.36345 -9.566656)
		(stroke
			(width 0.2032)
			(type default)
		)
		(layer "In6.Cu")
	)
	(gr_line
		(start 394.43025 -7.001256)
		(end 394.43025 -9.566656)
		(stroke
			(width 0.2032)
			(type default)
		)
		(layer "In6.Cu")
	)
	(gr_line
		(start 394.43025 -5.366512)
		(end 393.36345 -5.366512)
		(stroke
			(width 0.2032)
			(type default)
		)
		(layer "In6.Cu")
	)
	(gr_line
		(start 394.43025 -2.801112)
		(end 394.43025 -5.366512)
		(stroke
			(width 0.2032)
			(type default)
		)
		(layer "In6.Cu")
	)
	(gr_line
		(start 394.45565 -13.7668)
		(end 393.33805 -13.7668)
		(stroke
			(width 0.1016)
			(type default)
		)
		(layer "In6.Cu")
	)
	(gr_line
		(start 394.45565 -11.176)
		(end 394.45565 -13.7668)
		(stroke
			(width 0.1016)
			(type default)
		)
		(layer "In6.Cu")
	)
	(gr_line
		(start 394.45565 -9.566656)
		(end 393.33805 -9.566656)
		(stroke
			(width 0.1016)
			(type default)
		)
		(layer "In6.Cu")
	)
	(gr_line
		(start 394.45565 -6.975856)
		(end 394.45565 -9.566656)
		(stroke
			(width 0.1016)
			(type default)
		)
		(layer "In6.Cu")
	)
	(gr_line
		(start 394.45565 -5.366512)
		(end 393.33805 -5.366512)
		(stroke
			(width 0.1016)
			(type default)
		)
		(layer "In6.Cu")
	)
	(gr_line
		(start 394.45565 -2.775712)
		(end 394.45565 -5.366512)
		(stroke
			(width 0.1016)
			(type default)
		)
		(layer "In6.Cu")
	)
	(gr_line
		(start 394.48105 -13.8176)
		(end 394.07465 -13.8176)
		(stroke
			(width 0.1016)
			(type default)
		)
		(layer "In6.Cu")
	)
	(gr_line
		(start 394.48105 -13.8176)
		(end 394.48105 -11.1506)
		(stroke
			(width 0.1016)
			(type default)
		)
		(layer "In6.Cu")
	)
	(gr_line
		(start 394.48105 -11.1506)
		(end 393.28725 -11.1506)
		(stroke
			(width 0.1016)
			(type default)
		)
		(layer "In6.Cu")
	)
	(gr_line
		(start 394.48105 -11.1506)
		(end 394.48105 -13.8176)
		(stroke
			(width 0.1016)
			(type default)
		)
		(layer "In6.Cu")
	)
	(gr_line
		(start 394.48105 -9.617456)
		(end 394.07465 -9.617456)
		(stroke
			(width 0.1016)
			(type default)
		)
		(layer "In6.Cu")
	)
	(gr_line
		(start 394.48105 -9.617456)
		(end 394.48105 -6.950456)
		(stroke
			(width 0.1016)
			(type default)
		)
		(layer "In6.Cu")
	)
	(gr_line
		(start 394.48105 -6.950456)
		(end 393.28725 -6.950456)
		(stroke
			(width 0.1016)
			(type default)
		)
		(layer "In6.Cu")
	)
	(gr_line
		(start 394.48105 -6.950456)
		(end 394.48105 -9.617456)
		(stroke
			(width 0.1016)
			(type default)
		)
		(layer "In6.Cu")
	)
	(gr_line
		(start 394.48105 -5.417312)
		(end 394.07465 -5.417312)
		(stroke
			(width 0.1016)
			(type default)
		)
		(layer "In6.Cu")
	)
	(gr_line
		(start 394.48105 -5.417312)
		(end 394.48105 -2.750312)
		(stroke
			(width 0.1016)
			(type default)
		)
		(layer "In6.Cu")
	)
	(gr_line
		(start 394.48105 -2.750312)
		(end 393.28725 -2.750312)
		(stroke
			(width 0.1016)
			(type default)
		)
		(layer "In6.Cu")
	)
	(gr_line
		(start 394.48105 -2.750312)
		(end 394.48105 -5.417312)
		(stroke
			(width 0.1016)
			(type default)
		)
		(layer "In6.Cu")
	)
	(gr_line
		(start 395.14526 -32.9184)
		(end 393.87526 -32.9184)
		(stroke
			(width 0.7874)
			(type default)
		)
		(layer "In6.Cu")
	)
	(gr_line
		(start 395.287246 -12.563348)
		(end 396.074646 -12.563348)
		(stroke
			(width 0.1016)
			(type default)
		)
		(layer "In6.Cu")
	)
	(gr_line
		(start 395.287246 -12.512548)
		(end 395.287246 -9.896348)
		(stroke
			(width 0.1016)
			(type default)
		)
		(layer "In6.Cu")
	)
	(gr_line
		(start 395.287246 -12.463272)
		(end 396.074646 -12.463272)
		(stroke
			(width 0.1016)
			(type default)
		)
		(layer "In6.Cu")
	)
	(gr_line
		(start 395.287246 -12.412472)
		(end 395.287246 -9.796272)
		(stroke
			(width 0.1016)
			(type default)
		)
		(layer "In6.Cu")
	)
	(gr_line
		(start 395.287246 -9.896348)
		(end 395.287246 -12.563348)
		(stroke
			(width 0.1016)
			(type default)
		)
		(layer "In6.Cu")
	)
	(gr_line
		(start 395.287246 -9.896348)
		(end 396.481046 -9.896348)
		(stroke
			(width 0.1016)
			(type default)
		)
		(layer "In6.Cu")
	)
	(gr_line
		(start 395.287246 -9.796272)
		(end 395.287246 -12.463272)
		(stroke
			(width 0.1016)
			(type default)
		)
		(layer "In6.Cu")
	)
	(gr_line
		(start 395.287246 -9.796272)
		(end 396.481046 -9.796272)
		(stroke
			(width 0.1016)
			(type default)
		)
		(layer "In6.Cu")
	)
	(gr_line
		(start 395.287246 -8.363204)
		(end 396.074646 -8.363204)
		(stroke
			(width 0.1016)
			(type default)
		)
		(layer "In6.Cu")
	)
	(gr_line
		(start 395.287246 -8.312404)
		(end 395.287246 -5.696204)
		(stroke
			(width 0.1016)
			(type default)
		)
		(layer "In6.Cu")
	)
	(gr_line
		(start 395.287246 -8.263128)
		(end 396.074646 -8.263128)
		(stroke
			(width 0.1016)
			(type default)
		)
		(layer "In6.Cu")
	)
	(gr_line
		(start 395.287246 -8.212328)
		(end 395.287246 -5.596128)
		(stroke
			(width 0.1016)
			(type default)
		)
		(layer "In6.Cu")
	)
	(gr_line
		(start 395.287246 -5.696204)
		(end 395.287246 -8.363204)
		(stroke
			(width 0.1016)
			(type default)
		)
		(layer "In6.Cu")
	)
	(gr_line
		(start 395.287246 -5.696204)
		(end 396.481046 -5.696204)
		(stroke
			(width 0.1016)
			(type default)
		)
		(layer "In6.Cu")
	)
	(gr_line
		(start 395.287246 -5.596128)
		(end 395.287246 -8.263128)
		(stroke
			(width 0.1016)
			(type default)
		)
		(layer "In6.Cu")
	)
	(gr_line
		(start 395.287246 -5.596128)
		(end 396.481046 -5.596128)
		(stroke
			(width 0.1016)
			(type default)
		)
		(layer "In6.Cu")
	)
	(gr_line
		(start 395.287246 -4.16306)
		(end 396.074646 -4.16306)
		(stroke
			(width 0.1016)
			(type default)
		)
		(layer "In6.Cu")
	)
	(gr_line
		(start 395.287246 -4.11226)
		(end 395.287246 -1.49606)
		(stroke
			(width 0.1016)
			(type default)
		)
		(layer "In6.Cu")
	)
	(gr_line
		(start 395.287246 -4.062984)
		(end 396.074646 -4.062984)
		(stroke
			(width 0.1016)
			(type default)
		)
		(layer "In6.Cu")
	)
	(gr_line
		(start 395.287246 -4.012184)
		(end 395.287246 -1.395984)
		(stroke
			(width 0.1016)
			(type default)
		)
		(layer "In6.Cu")
	)
	(gr_line
		(start 395.287246 -1.49606)
		(end 395.287246 -4.16306)
		(stroke
			(width 0.1016)
			(type default)
		)
		(layer "In6.Cu")
	)
	(gr_line
		(start 395.287246 -1.49606)
		(end 396.481046 -1.49606)
		(stroke
			(width 0.1016)
			(type default)
		)
		(layer "In6.Cu")
	)
	(gr_line
		(start 395.287246 -1.395984)
		(end 395.287246 -4.062984)
		(stroke
			(width 0.1016)
			(type default)
		)
		(layer "In6.Cu")
	)
	(gr_line
		(start 395.287246 -1.395984)
		(end 396.481046 -1.395984)
		(stroke
			(width 0.1016)
			(type default)
		)
		(layer "In6.Cu")
	)
	(gr_line
		(start 395.312646 -12.512548)
		(end 395.312646 -9.921748)
		(stroke
			(width 0.1016)
			(type default)
		)
		(layer "In6.Cu")
	)
	(gr_line
		(start 395.312646 -12.412472)
		(end 395.312646 -9.821672)
		(stroke
			(width 0.1016)
			(type default)
		)
		(layer "In6.Cu")
	)
	(gr_line
		(start 395.312646 -9.921748)
		(end 396.455646 -9.921748)
		(stroke
			(width 0.1016)
			(type default)
		)
		(layer "In6.Cu")
	)
	(gr_line
		(start 395.312646 -9.821672)
		(end 396.455646 -9.821672)
		(stroke
			(width 0.1016)
			(type default)
		)
		(layer "In6.Cu")
	)
	(gr_line
		(start 395.312646 -8.312404)
		(end 395.312646 -5.721604)
		(stroke
			(width 0.1016)
			(type default)
		)
		(layer "In6.Cu")
	)
	(gr_line
		(start 395.312646 -8.212328)
		(end 395.312646 -5.621528)
		(stroke
			(width 0.1016)
			(type default)
		)
		(layer "In6.Cu")
	)
	(gr_line
		(start 395.312646 -5.721604)
		(end 396.455646 -5.721604)
		(stroke
			(width 0.1016)
			(type default)
		)
		(layer "In6.Cu")
	)
	(gr_line
		(start 395.312646 -5.621528)
		(end 396.455646 -5.621528)
		(stroke
			(width 0.1016)
			(type default)
		)
		(layer "In6.Cu")
	)
	(gr_line
		(start 395.312646 -4.11226)
		(end 395.312646 -1.52146)
		(stroke
			(width 0.1016)
			(type default)
		)
		(layer "In6.Cu")
	)
	(gr_line
		(start 395.312646 -4.012184)
		(end 395.312646 -1.421384)
		(stroke
			(width 0.1016)
			(type default)
		)
		(layer "In6.Cu")
	)
	(gr_line
		(start 395.312646 -1.52146)
		(end 396.455646 -1.52146)
		(stroke
			(width 0.1016)
			(type default)
		)
		(layer "In6.Cu")
	)
	(gr_line
		(start 395.312646 -1.421384)
		(end 396.455646 -1.421384)
		(stroke
			(width 0.1016)
			(type default)
		)
		(layer "In6.Cu")
	)
	(gr_line
		(start 395.338046 -12.512548)
		(end 395.338046 -9.947148)
		(stroke
			(width 0.1016)
			(type default)
		)
		(layer "In6.Cu")
	)
	(gr_line
		(start 395.338046 -12.412472)
		(end 395.338046 -9.847072)
		(stroke
			(width 0.1016)
			(type default)
		)
		(layer "In6.Cu")
	)
	(gr_line
		(start 395.338046 -9.947148)
		(end 395.592046 -9.947148)
		(stroke
			(width 0.1016)
			(type default)
		)
		(layer "In6.Cu")
	)
	(gr_line
		(start 395.338046 -9.847072)
		(end 395.592046 -9.847072)
		(stroke
			(width 0.1016)
			(type default)
		)
		(layer "In6.Cu")
	)
	(gr_line
		(start 395.338046 -8.312404)
		(end 395.338046 -5.747004)
		(stroke
			(width 0.1016)
			(type default)
		)
		(layer "In6.Cu")
	)
	(gr_line
		(start 395.338046 -8.212328)
		(end 395.338046 -5.646928)
		(stroke
			(width 0.1016)
			(type default)
		)
		(layer "In6.Cu")
	)
	(gr_line
		(start 395.338046 -5.747004)
		(end 395.592046 -5.747004)
		(stroke
			(width 0.1016)
			(type default)
		)
		(layer "In6.Cu")
	)
	(gr_line
		(start 395.338046 -5.646928)
		(end 395.592046 -5.646928)
		(stroke
			(width 0.1016)
			(type default)
		)
		(layer "In6.Cu")
	)
	(gr_line
		(start 395.338046 -4.11226)
		(end 395.338046 -1.54686)
		(stroke
			(width 0.1016)
			(type default)
		)
		(layer "In6.Cu")
	)
	(gr_line
		(start 395.338046 -4.012184)
		(end 395.338046 -1.446784)
		(stroke
			(width 0.1016)
			(type default)
		)
		(layer "In6.Cu")
	)
	(gr_line
		(start 395.338046 -1.54686)
		(end 395.592046 -1.54686)
		(stroke
			(width 0.1016)
			(type default)
		)
		(layer "In6.Cu")
	)
	(gr_line
		(start 395.338046 -1.446784)
		(end 395.592046 -1.446784)
		(stroke
			(width 0.1016)
			(type default)
		)
		(layer "In6.Cu")
	)
	(gr_line
		(start 395.363446 -12.512548)
		(end 395.363446 -9.947148)
		(stroke
			(width 0.2032)
			(type default)
		)
		(layer "In6.Cu")
	)
	(gr_line
		(start 395.363446 -12.412472)
		(end 395.363446 -9.847072)
		(stroke
			(width 0.2032)
			(type default)
		)
		(layer "In6.Cu")
	)
	(gr_line
		(start 395.363446 -9.947148)
		(end 396.379446 -9.947148)
		(stroke
			(width 0.2032)
			(type default)
		)
		(layer "In6.Cu")
	)
	(gr_line
		(start 395.363446 -9.847072)
		(end 396.379446 -9.847072)
		(stroke
			(width 0.2032)
			(type default)
		)
		(layer "In6.Cu")
	)
	(gr_line
		(start 395.363446 -8.312404)
		(end 395.363446 -5.747004)
		(stroke
			(width 0.2032)
			(type default)
		)
		(layer "In6.Cu")
	)
	(gr_line
		(start 395.363446 -8.212328)
		(end 395.363446 -5.646928)
		(stroke
			(width 0.2032)
			(type default)
		)
		(layer "In6.Cu")
	)
	(gr_line
		(start 395.363446 -5.747004)
		(end 396.379446 -5.747004)
		(stroke
			(width 0.2032)
			(type default)
		)
		(layer "In6.Cu")
	)
	(gr_line
		(start 395.363446 -5.646928)
		(end 396.379446 -5.646928)
		(stroke
			(width 0.2032)
			(type default)
		)
		(layer "In6.Cu")
	)
	(gr_line
		(start 395.363446 -4.11226)
		(end 395.363446 -1.54686)
		(stroke
			(width 0.2032)
			(type default)
		)
		(layer "In6.Cu")
	)
	(gr_line
		(start 395.363446 -4.012184)
		(end 395.363446 -1.446784)
		(stroke
			(width 0.2032)
			(type default)
		)
		(layer "In6.Cu")
	)
	(gr_line
		(start 395.363446 -1.54686)
		(end 396.379446 -1.54686)
		(stroke
			(width 0.2032)
			(type default)
		)
		(layer "In6.Cu")
	)
	(gr_line
		(start 395.363446 -1.446784)
		(end 396.379446 -1.446784)
		(stroke
			(width 0.2032)
			(type default)
		)
		(layer "In6.Cu")
	)
	(gr_line
		(start 395.414246 -12.487148)
		(end 395.414246 -9.997948)
		(stroke
			(width 0.2032)
			(type default)
		)
		(layer "In6.Cu")
	)
	(gr_line
		(start 395.414246 -12.487148)
		(end 395.414246 -9.997948)
		(stroke
			(width 0.254)
			(type default)
		)
		(layer "In6.Cu")
	)
	(gr_line
		(start 395.414246 -12.387072)
		(end 395.414246 -9.897872)
		(stroke
			(width 0.2032)
			(type default)
		)
		(layer "In6.Cu")
	)
	(gr_line
		(start 395.414246 -12.387072)
		(end 395.414246 -9.897872)
		(stroke
			(width 0.254)
			(type default)
		)
		(layer "In6.Cu")
	)
	(gr_line
		(start 395.414246 -9.997948)
		(end 395.617446 -9.997948)
		(stroke
			(width 0.2032)
			(type default)
		)
		(layer "In6.Cu")
	)
	(gr_line
		(start 395.414246 -9.997948)
		(end 396.303246 -9.997948)
		(stroke
			(width 0.254)
			(type default)
		)
		(layer "In6.Cu")
	)
	(gr_line
		(start 395.414246 -9.897872)
		(end 395.617446 -9.897872)
		(stroke
			(width 0.2032)
			(type default)
		)
		(layer "In6.Cu")
	)
	(gr_line
		(start 395.414246 -9.897872)
		(end 396.303246 -9.897872)
		(stroke
			(width 0.254)
			(type default)
		)
		(layer "In6.Cu")
	)
	(gr_line
		(start 395.414246 -8.287004)
		(end 395.414246 -5.797804)
		(stroke
			(width 0.2032)
			(type default)
		)
		(layer "In6.Cu")
	)
	(gr_line
		(start 395.414246 -8.287004)
		(end 395.414246 -5.797804)
		(stroke
			(width 0.254)
			(type default)
		)
		(layer "In6.Cu")
	)
	(gr_line
		(start 395.414246 -8.186928)
		(end 395.414246 -5.697728)
		(stroke
			(width 0.2032)
			(type default)
		)
		(layer "In6.Cu")
	)
	(gr_line
		(start 395.414246 -8.186928)
		(end 395.414246 -5.697728)
		(stroke
			(width 0.254)
			(type default)
		)
		(layer "In6.Cu")
	)
	(gr_line
		(start 395.414246 -5.797804)
		(end 395.617446 -5.797804)
		(stroke
			(width 0.2032)
			(type default)
		)
		(layer "In6.Cu")
	)
	(gr_line
		(start 395.414246 -5.797804)
		(end 396.303246 -5.797804)
		(stroke
			(width 0.254)
			(type default)
		)
		(layer "In6.Cu")
	)
	(gr_line
		(start 395.414246 -5.697728)
		(end 395.617446 -5.697728)
		(stroke
			(width 0.2032)
			(type default)
		)
		(layer "In6.Cu")
	)
	(gr_line
		(start 395.414246 -5.697728)
		(end 396.303246 -5.697728)
		(stroke
			(width 0.254)
			(type default)
		)
		(layer "In6.Cu")
	)
	(gr_line
		(start 395.414246 -4.08686)
		(end 395.414246 -1.59766)
		(stroke
			(width 0.2032)
			(type default)
		)
		(layer "In6.Cu")
	)
	(gr_line
		(start 395.414246 -4.08686)
		(end 395.414246 -1.59766)
		(stroke
			(width 0.254)
			(type default)
		)
		(layer "In6.Cu")
	)
	(gr_line
		(start 395.414246 -3.986784)
		(end 395.414246 -1.497584)
		(stroke
			(width 0.2032)
			(type default)
		)
		(layer "In6.Cu")
	)
	(gr_line
		(start 395.414246 -3.986784)
		(end 395.414246 -1.497584)
		(stroke
			(width 0.254)
			(type default)
		)
		(layer "In6.Cu")
	)
	(gr_line
		(start 395.414246 -1.59766)
		(end 395.617446 -1.59766)
		(stroke
			(width 0.2032)
			(type default)
		)
		(layer "In6.Cu")
	)
	(gr_line
		(start 395.414246 -1.59766)
		(end 396.303246 -1.59766)
		(stroke
			(width 0.254)
			(type default)
		)
		(layer "In6.Cu")
	)
	(gr_line
		(start 395.414246 -1.497584)
		(end 395.617446 -1.497584)
		(stroke
			(width 0.2032)
			(type default)
		)
		(layer "In6.Cu")
	)
	(gr_line
		(start 395.414246 -1.497584)
		(end 396.303246 -1.497584)
		(stroke
			(width 0.254)
			(type default)
		)
		(layer "In6.Cu")
	)
	(gr_line
		(start 395.439646 -12.461748)
		(end 395.439646 -10.023348)
		(stroke
			(width 0.254)
			(type default)
		)
		(layer "In6.Cu")
	)
	(gr_line
		(start 395.439646 -12.361672)
		(end 395.439646 -9.923272)
		(stroke
			(width 0.254)
			(type default)
		)
		(layer "In6.Cu")
	)
	(gr_line
		(start 395.439646 -10.023348)
		(end 396.277846 -10.023348)
		(stroke
			(width 0.254)
			(type default)
		)
		(layer "In6.Cu")
	)
	(gr_line
		(start 395.439646 -9.923272)
		(end 396.277846 -9.923272)
		(stroke
			(width 0.254)
			(type default)
		)
		(layer "In6.Cu")
	)
	(gr_line
		(start 395.439646 -8.261604)
		(end 395.439646 -5.823204)
		(stroke
			(width 0.254)
			(type default)
		)
		(layer "In6.Cu")
	)
	(gr_line
		(start 395.439646 -8.161528)
		(end 395.439646 -5.723128)
		(stroke
			(width 0.254)
			(type default)
		)
		(layer "In6.Cu")
	)
	(gr_line
		(start 395.439646 -5.823204)
		(end 396.277846 -5.823204)
		(stroke
			(width 0.254)
			(type default)
		)
		(layer "In6.Cu")
	)
	(gr_line
		(start 395.439646 -5.723128)
		(end 396.277846 -5.723128)
		(stroke
			(width 0.254)
			(type default)
		)
		(layer "In6.Cu")
	)
	(gr_line
		(start 395.439646 -4.06146)
		(end 395.439646 -1.62306)
		(stroke
			(width 0.254)
			(type default)
		)
		(layer "In6.Cu")
	)
	(gr_line
		(start 395.439646 -3.961384)
		(end 395.439646 -1.522984)
		(stroke
			(width 0.254)
			(type default)
		)
		(layer "In6.Cu")
	)
	(gr_line
		(start 395.439646 -1.62306)
		(end 396.277846 -1.62306)
		(stroke
			(width 0.254)
			(type default)
		)
		(layer "In6.Cu")
	)
	(gr_line
		(start 395.439646 -1.522984)
		(end 396.277846 -1.522984)
		(stroke
			(width 0.254)
			(type default)
		)
		(layer "In6.Cu")
	)
	(gr_line
		(start 395.465046 -12.436348)
		(end 395.465046 -10.048748)
		(stroke
			(width 0.254)
			(type default)
		)
		(layer "In6.Cu")
	)
	(gr_line
		(start 395.465046 -12.336272)
		(end 395.465046 -9.948672)
		(stroke
			(width 0.254)
			(type default)
		)
		(layer "In6.Cu")
	)
	(gr_line
		(start 395.465046 -10.048748)
		(end 396.252446 -10.048748)
		(stroke
			(width 0.254)
			(type default)
		)
		(layer "In6.Cu")
	)
	(gr_line
		(start 395.465046 -9.948672)
		(end 396.252446 -9.948672)
		(stroke
			(width 0.254)
			(type default)
		)
		(layer "In6.Cu")
	)
	(gr_line
		(start 395.465046 -8.236204)
		(end 395.465046 -5.848604)
		(stroke
			(width 0.254)
			(type default)
		)
		(layer "In6.Cu")
	)
	(gr_line
		(start 395.465046 -8.136128)
		(end 395.465046 -5.748528)
		(stroke
			(width 0.254)
			(type default)
		)
		(layer "In6.Cu")
	)
	(gr_line
		(start 395.465046 -5.848604)
		(end 396.252446 -5.848604)
		(stroke
			(width 0.254)
			(type default)
		)
		(layer "In6.Cu")
	)
	(gr_line
		(start 395.465046 -5.748528)
		(end 396.252446 -5.748528)
		(stroke
			(width 0.254)
			(type default)
		)
		(layer "In6.Cu")
	)
	(gr_line
		(start 395.465046 -4.03606)
		(end 395.465046 -1.64846)
		(stroke
			(width 0.254)
			(type default)
		)
		(layer "In6.Cu")
	)
	(gr_line
		(start 395.465046 -3.935984)
		(end 395.465046 -1.548384)
		(stroke
			(width 0.254)
			(type default)
		)
		(layer "In6.Cu")
	)
	(gr_line
		(start 395.465046 -1.64846)
		(end 396.252446 -1.64846)
		(stroke
			(width 0.254)
			(type default)
		)
		(layer "In6.Cu")
	)
	(gr_line
		(start 395.465046 -1.548384)
		(end 396.252446 -1.548384)
		(stroke
			(width 0.254)
			(type default)
		)
		(layer "In6.Cu")
	)
	(gr_line
		(start 395.490446 -12.360148)
		(end 396.125446 -12.360148)
		(stroke
			(width 0.508)
			(type default)
		)
		(layer "In6.Cu")
	)
	(gr_line
		(start 395.490446 -12.260072)
		(end 396.125446 -12.260072)
		(stroke
			(width 0.508)
			(type default)
		)
		(layer "In6.Cu")
	)
	(gr_line
		(start 395.490446 -10.175748)
		(end 396.125446 -10.175748)
		(stroke
			(width 0.508)
			(type default)
		)
		(layer "In6.Cu")
	)
	(gr_line
		(start 395.490446 -10.124948)
		(end 396.125446 -10.124948)
		(stroke
			(width 0.508)
			(type default)
		)
		(layer "In6.Cu")
	)
	(gr_line
		(start 395.490446 -10.075672)
		(end 396.125446 -10.075672)
		(stroke
			(width 0.508)
			(type default)
		)
		(layer "In6.Cu")
	)
	(gr_line
		(start 395.490446 -10.024872)
		(end 396.125446 -10.024872)
		(stroke
			(width 0.508)
			(type default)
		)
		(layer "In6.Cu")
	)
	(gr_line
		(start 395.490446 -8.160004)
		(end 396.125446 -8.160004)
		(stroke
			(width 0.508)
			(type default)
		)
		(layer "In6.Cu")
	)
	(gr_line
		(start 395.490446 -8.059928)
		(end 396.125446 -8.059928)
		(stroke
			(width 0.508)
			(type default)
		)
		(layer "In6.Cu")
	)
	(gr_line
		(start 395.490446 -5.975604)
		(end 396.125446 -5.975604)
		(stroke
			(width 0.508)
			(type default)
		)
		(layer "In6.Cu")
	)
	(gr_line
		(start 395.490446 -5.924804)
		(end 396.125446 -5.924804)
		(stroke
			(width 0.508)
			(type default)
		)
		(layer "In6.Cu")
	)
	(gr_line
		(start 395.490446 -5.875528)
		(end 396.125446 -5.875528)
		(stroke
			(width 0.508)
			(type default)
		)
		(layer "In6.Cu")
	)
	(gr_line
		(start 395.490446 -5.824728)
		(end 396.125446 -5.824728)
		(stroke
			(width 0.508)
			(type default)
		)
		(layer "In6.Cu")
	)
	(gr_line
		(start 395.490446 -3.95986)
		(end 396.125446 -3.95986)
		(stroke
			(width 0.508)
			(type default)
		)
		(layer "In6.Cu")
	)
	(gr_line
		(start 395.490446 -3.859784)
		(end 396.125446 -3.859784)
		(stroke
			(width 0.508)
			(type default)
		)
		(layer "In6.Cu")
	)
	(gr_line
		(start 395.490446 -1.77546)
		(end 396.125446 -1.77546)
		(stroke
			(width 0.508)
			(type default)
		)
		(layer "In6.Cu")
	)
	(gr_line
		(start 395.490446 -1.72466)
		(end 396.125446 -1.72466)
		(stroke
			(width 0.508)
			(type default)
		)
		(layer "In6.Cu")
	)
	(gr_line
		(start 395.490446 -1.675384)
		(end 396.125446 -1.675384)
		(stroke
			(width 0.508)
			(type default)
		)
		(layer "In6.Cu")
	)
	(gr_line
		(start 395.490446 -1.624584)
		(end 396.125446 -1.624584)
		(stroke
			(width 0.508)
			(type default)
		)
		(layer "In6.Cu")
	)
	(gr_line
		(start 395.515846 -10.429748)
		(end 396.150846 -10.429748)
		(stroke
			(width 0.508)
			(type default)
		)
		(layer "In6.Cu")
	)
	(gr_line
		(start 395.515846 -10.329672)
		(end 396.150846 -10.329672)
		(stroke
			(width 0.508)
			(type default)
		)
		(layer "In6.Cu")
	)
	(gr_line
		(start 395.515846 -6.229604)
		(end 396.150846 -6.229604)
		(stroke
			(width 0.508)
			(type default)
		)
		(layer "In6.Cu")
	)
	(gr_line
		(start 395.515846 -6.129528)
		(end 396.150846 -6.129528)
		(stroke
			(width 0.508)
			(type default)
		)
		(layer "In6.Cu")
	)
	(gr_line
		(start 395.515846 -2.02946)
		(end 396.150846 -2.02946)
		(stroke
			(width 0.508)
			(type default)
		)
		(layer "In6.Cu")
	)
	(gr_line
		(start 395.515846 -1.929384)
		(end 396.150846 -1.929384)
		(stroke
			(width 0.508)
			(type default)
		)
		(layer "In6.Cu")
	)
	(gr_line
		(start 395.541246 -12.385548)
		(end 395.541246 -10.124948)
		(stroke
			(width 0.254)
			(type default)
		)
		(layer "In6.Cu")
	)
	(gr_line
		(start 395.541246 -12.285472)
		(end 395.541246 -10.024872)
		(stroke
			(width 0.254)
			(type default)
		)
		(layer "In6.Cu")
	)
	(gr_line
		(start 395.541246 -12.233148)
		(end 396.176246 -12.233148)
		(stroke
			(width 0.508)
			(type default)
		)
		(layer "In6.Cu")
	)
	(gr_line
		(start 395.541246 -12.133072)
		(end 396.176246 -12.133072)
		(stroke
			(width 0.508)
			(type default)
		)
		(layer "In6.Cu")
	)
	(gr_line
		(start 395.541246 -10.124948)
		(end 396.176246 -10.124948)
		(stroke
			(width 0.254)
			(type default)
		)
		(layer "In6.Cu")
	)
	(gr_line
		(start 395.541246 -10.024872)
		(end 396.176246 -10.024872)
		(stroke
			(width 0.254)
			(type default)
		)
		(layer "In6.Cu")
	)
	(gr_line
		(start 395.541246 -8.185404)
		(end 395.541246 -5.924804)
		(stroke
			(width 0.254)
			(type default)
		)
		(layer "In6.Cu")
	)
	(gr_line
		(start 395.541246 -8.085328)
		(end 395.541246 -5.824728)
		(stroke
			(width 0.254)
			(type default)
		)
		(layer "In6.Cu")
	)
	(gr_line
		(start 395.541246 -8.033004)
		(end 396.176246 -8.033004)
		(stroke
			(width 0.508)
			(type default)
		)
		(layer "In6.Cu")
	)
	(gr_line
		(start 395.541246 -7.932928)
		(end 396.176246 -7.932928)
		(stroke
			(width 0.508)
			(type default)
		)
		(layer "In6.Cu")
	)
	(gr_line
		(start 395.541246 -5.924804)
		(end 396.176246 -5.924804)
		(stroke
			(width 0.254)
			(type default)
		)
		(layer "In6.Cu")
	)
	(gr_line
		(start 395.541246 -5.824728)
		(end 396.176246 -5.824728)
		(stroke
			(width 0.254)
			(type default)
		)
		(layer "In6.Cu")
	)
	(gr_line
		(start 395.541246 -3.98526)
		(end 395.541246 -1.72466)
		(stroke
			(width 0.254)
			(type default)
		)
		(layer "In6.Cu")
	)
	(gr_line
		(start 395.541246 -3.885184)
		(end 395.541246 -1.624584)
		(stroke
			(width 0.254)
			(type default)
		)
		(layer "In6.Cu")
	)
	(gr_line
		(start 395.541246 -3.83286)
		(end 396.176246 -3.83286)
		(stroke
			(width 0.508)
			(type default)
		)
		(layer "In6.Cu")
	)
	(gr_line
		(start 395.541246 -3.732784)
		(end 396.176246 -3.732784)
		(stroke
			(width 0.508)
			(type default)
		)
		(layer "In6.Cu")
	)
	(gr_line
		(start 395.541246 -1.72466)
		(end 396.176246 -1.72466)
		(stroke
			(width 0.254)
			(type default)
		)
		(layer "In6.Cu")
	)
	(gr_line
		(start 395.541246 -1.624584)
		(end 396.176246 -1.624584)
		(stroke
			(width 0.254)
			(type default)
		)
		(layer "In6.Cu")
	)
	(gr_line
		(start 395.566646 -12.080748)
		(end 396.201646 -12.080748)
		(stroke
			(width 0.508)
			(type default)
		)
		(layer "In6.Cu")
	)
	(gr_line
		(start 395.566646 -11.980672)
		(end 396.201646 -11.980672)
		(stroke
			(width 0.508)
			(type default)
		)
		(layer "In6.Cu")
	)
	(gr_line
		(start 395.566646 -7.880604)
		(end 396.201646 -7.880604)
		(stroke
			(width 0.508)
			(type default)
		)
		(layer "In6.Cu")
	)
	(gr_line
		(start 395.566646 -7.780528)
		(end 396.201646 -7.780528)
		(stroke
			(width 0.508)
			(type default)
		)
		(layer "In6.Cu")
	)
	(gr_line
		(start 395.566646 -3.68046)
		(end 396.201646 -3.68046)
		(stroke
			(width 0.508)
			(type default)
		)
		(layer "In6.Cu")
	)
	(gr_line
		(start 395.566646 -3.580384)
		(end 396.201646 -3.580384)
		(stroke
			(width 0.508)
			(type default)
		)
		(layer "In6.Cu")
	)
	(gr_line
		(start 395.592046 -12.360148)
		(end 396.227046 -12.360148)
		(stroke
			(width 0.508)
			(type default)
		)
		(layer "In6.Cu")
	)
	(gr_line
		(start 395.592046 -12.260072)
		(end 396.227046 -12.260072)
		(stroke
			(width 0.508)
			(type default)
		)
		(layer "In6.Cu")
	)
	(gr_line
		(start 395.592046 -9.947148)
		(end 396.430246 -9.947148)
		(stroke
			(width 0.2032)
			(type default)
		)
		(layer "In6.Cu")
	)
	(gr_line
		(start 395.592046 -9.847072)
		(end 396.430246 -9.847072)
		(stroke
			(width 0.2032)
			(type default)
		)
		(layer "In6.Cu")
	)
	(gr_line
		(start 395.592046 -8.160004)
		(end 396.227046 -8.160004)
		(stroke
			(width 0.508)
			(type default)
		)
		(layer "In6.Cu")
	)
	(gr_line
		(start 395.592046 -8.059928)
		(end 396.227046 -8.059928)
		(stroke
			(width 0.508)
			(type default)
		)
		(layer "In6.Cu")
	)
	(gr_line
		(start 395.592046 -5.747004)
		(end 396.430246 -5.747004)
		(stroke
			(width 0.2032)
			(type default)
		)
		(layer "In6.Cu")
	)
	(gr_line
		(start 395.592046 -5.646928)
		(end 396.430246 -5.646928)
		(stroke
			(width 0.2032)
			(type default)
		)
		(layer "In6.Cu")
	)
	(gr_line
		(start 395.592046 -3.95986)
		(end 396.227046 -3.95986)
		(stroke
			(width 0.508)
			(type default)
		)
		(layer "In6.Cu")
	)
	(gr_line
		(start 395.592046 -3.859784)
		(end 396.227046 -3.859784)
		(stroke
			(width 0.508)
			(type default)
		)
		(layer "In6.Cu")
	)
	(gr_line
		(start 395.592046 -1.54686)
		(end 396.430246 -1.54686)
		(stroke
			(width 0.2032)
			(type default)
		)
		(layer "In6.Cu")
	)
	(gr_line
		(start 395.592046 -1.446784)
		(end 396.430246 -1.446784)
		(stroke
			(width 0.2032)
			(type default)
		)
		(layer "In6.Cu")
	)
	(gr_line
		(start 395.617446 -12.360148)
		(end 395.617446 -10.175748)
		(stroke
			(width 0.254)
			(type default)
		)
		(layer "In6.Cu")
	)
	(gr_line
		(start 395.617446 -12.260072)
		(end 395.617446 -10.075672)
		(stroke
			(width 0.254)
			(type default)
		)
		(layer "In6.Cu")
	)
	(gr_line
		(start 395.617446 -10.175748)
		(end 396.100046 -10.175748)
		(stroke
			(width 0.254)
			(type default)
		)
		(layer "In6.Cu")
	)
	(gr_line
		(start 395.617446 -10.075672)
		(end 396.100046 -10.075672)
		(stroke
			(width 0.254)
			(type default)
		)
		(layer "In6.Cu")
	)
	(gr_line
		(start 395.617446 -9.997948)
		(end 396.354046 -9.997948)
		(stroke
			(width 0.254)
			(type default)
		)
		(layer "In6.Cu")
	)
	(gr_line
		(start 395.617446 -9.897872)
		(end 396.354046 -9.897872)
		(stroke
			(width 0.254)
			(type default)
		)
		(layer "In6.Cu")
	)
	(gr_line
		(start 395.617446 -8.160004)
		(end 395.617446 -5.975604)
		(stroke
			(width 0.254)
			(type default)
		)
		(layer "In6.Cu")
	)
	(gr_line
		(start 395.617446 -8.059928)
		(end 395.617446 -5.875528)
		(stroke
			(width 0.254)
			(type default)
		)
		(layer "In6.Cu")
	)
	(gr_line
		(start 395.617446 -5.975604)
		(end 396.100046 -5.975604)
		(stroke
			(width 0.254)
			(type default)
		)
		(layer "In6.Cu")
	)
	(gr_line
		(start 395.617446 -5.875528)
		(end 396.100046 -5.875528)
		(stroke
			(width 0.254)
			(type default)
		)
		(layer "In6.Cu")
	)
	(gr_line
		(start 395.617446 -5.797804)
		(end 396.354046 -5.797804)
		(stroke
			(width 0.254)
			(type default)
		)
		(layer "In6.Cu")
	)
	(gr_line
		(start 395.617446 -5.697728)
		(end 396.354046 -5.697728)
		(stroke
			(width 0.254)
			(type default)
		)
		(layer "In6.Cu")
	)
	(gr_line
		(start 395.617446 -3.95986)
		(end 395.617446 -1.77546)
		(stroke
			(width 0.254)
			(type default)
		)
		(layer "In6.Cu")
	)
	(gr_line
		(start 395.617446 -3.859784)
		(end 395.617446 -1.675384)
		(stroke
			(width 0.254)
			(type default)
		)
		(layer "In6.Cu")
	)
	(gr_line
		(start 395.617446 -1.77546)
		(end 396.100046 -1.77546)
		(stroke
			(width 0.254)
			(type default)
		)
		(layer "In6.Cu")
	)
	(gr_line
		(start 395.617446 -1.675384)
		(end 396.100046 -1.675384)
		(stroke
			(width 0.254)
			(type default)
		)
		(layer "In6.Cu")
	)
	(gr_line
		(start 395.617446 -1.59766)
		(end 396.354046 -1.59766)
		(stroke
			(width 0.254)
			(type default)
		)
		(layer "In6.Cu")
	)
	(gr_line
		(start 395.617446 -1.497584)
		(end 396.354046 -1.497584)
		(stroke
			(width 0.254)
			(type default)
		)
		(layer "In6.Cu")
	)
	(gr_line
		(start 395.635988 -10.110978)
		(end 396.270988 -10.110978)
		(stroke
			(width 0.508)
			(type default)
		)
		(layer "In6.Cu")
	)
	(gr_line
		(start 395.635988 -10.010902)
		(end 396.270988 -10.010902)
		(stroke
			(width 0.508)
			(type default)
		)
		(layer "In6.Cu")
	)
	(gr_line
		(start 395.635988 -5.910834)
		(end 396.270988 -5.910834)
		(stroke
			(width 0.508)
			(type default)
		)
		(layer "In6.Cu")
	)
	(gr_line
		(start 395.635988 -5.810758)
		(end 396.270988 -5.810758)
		(stroke
			(width 0.508)
			(type default)
		)
		(layer "In6.Cu")
	)
	(gr_line
		(start 395.635988 -1.71069)
		(end 396.270988 -1.71069)
		(stroke
			(width 0.508)
			(type default)
		)
		(layer "In6.Cu")
	)
	(gr_line
		(start 395.635988 -1.610614)
		(end 396.270988 -1.610614)
		(stroke
			(width 0.508)
			(type default)
		)
		(layer "In6.Cu")
	)
	(gr_line
		(start 395.642846 -12.360148)
		(end 396.277846 -12.360148)
		(stroke
			(width 0.508)
			(type default)
		)
		(layer "In6.Cu")
	)
	(gr_line
		(start 395.642846 -12.260072)
		(end 396.277846 -12.260072)
		(stroke
			(width 0.508)
			(type default)
		)
		(layer "In6.Cu")
	)
	(gr_line
		(start 395.642846 -12.233148)
		(end 395.642846 -10.251948)
		(stroke
			(width 0.762)
			(type default)
		)
		(layer "In6.Cu")
	)
	(gr_line
		(start 395.642846 -12.133072)
		(end 395.642846 -10.151872)
		(stroke
			(width 0.762)
			(type default)
		)
		(layer "In6.Cu")
	)
	(gr_line
		(start 395.642846 -10.251948)
		(end 396.277846 -10.251948)
		(stroke
			(width 0.508)
			(type default)
		)
		(layer "In6.Cu")
	)
	(gr_line
		(start 395.642846 -10.151872)
		(end 396.277846 -10.151872)
		(stroke
			(width 0.508)
			(type default)
		)
		(layer "In6.Cu")
	)
	(gr_line
		(start 395.642846 -8.160004)
		(end 396.277846 -8.160004)
		(stroke
			(width 0.508)
			(type default)
		)
		(layer "In6.Cu")
	)
	(gr_line
		(start 395.642846 -8.059928)
		(end 396.277846 -8.059928)
		(stroke
			(width 0.508)
			(type default)
		)
		(layer "In6.Cu")
	)
	(gr_line
		(start 395.642846 -8.033004)
		(end 395.642846 -6.051804)
		(stroke
			(width 0.762)
			(type default)
		)
		(layer "In6.Cu")
	)
	(gr_line
		(start 395.642846 -7.932928)
		(end 395.642846 -5.951728)
		(stroke
			(width 0.762)
			(type default)
		)
		(layer "In6.Cu")
	)
	(gr_line
		(start 395.642846 -6.051804)
		(end 396.277846 -6.051804)
		(stroke
			(width 0.508)
			(type default)
		)
		(layer "In6.Cu")
	)
	(gr_line
		(start 395.642846 -5.951728)
		(end 396.277846 -5.951728)
		(stroke
			(width 0.508)
			(type default)
		)
		(layer "In6.Cu")
	)
	(gr_line
		(start 395.642846 -3.95986)
		(end 396.277846 -3.95986)
		(stroke
			(width 0.508)
			(type default)
		)
		(layer "In6.Cu")
	)
	(gr_line
		(start 395.642846 -3.859784)
		(end 396.277846 -3.859784)
		(stroke
			(width 0.508)
			(type default)
		)
		(layer "In6.Cu")
	)
	(gr_line
		(start 395.642846 -3.83286)
		(end 395.642846 -1.85166)
		(stroke
			(width 0.762)
			(type default)
		)
		(layer "In6.Cu")
	)
	(gr_line
		(start 395.642846 -3.732784)
		(end 395.642846 -1.751584)
		(stroke
			(width 0.762)
			(type default)
		)
		(layer "In6.Cu")
	)
	(gr_line
		(start 395.642846 -1.85166)
		(end 396.277846 -1.85166)
		(stroke
			(width 0.508)
			(type default)
		)
		(layer "In6.Cu")
	)
	(gr_line
		(start 395.642846 -1.751584)
		(end 396.277846 -1.751584)
		(stroke
			(width 0.508)
			(type default)
		)
		(layer "In6.Cu")
	)
	(gr_line
		(start 395.693646 -12.283948)
		(end 395.693646 -10.251948)
		(stroke
			(width 0.254)
			(type default)
		)
		(layer "In6.Cu")
	)
	(gr_line
		(start 395.693646 -12.183872)
		(end 395.693646 -10.151872)
		(stroke
			(width 0.254)
			(type default)
		)
		(layer "In6.Cu")
	)
	(gr_line
		(start 395.693646 -10.251948)
		(end 396.023846 -10.251948)
		(stroke
			(width 0.254)
			(type default)
		)
		(layer "In6.Cu")
	)
	(gr_line
		(start 395.693646 -10.151872)
		(end 396.023846 -10.151872)
		(stroke
			(width 0.254)
			(type default)
		)
		(layer "In6.Cu")
	)
	(gr_line
		(start 395.693646 -8.083804)
		(end 395.693646 -6.051804)
		(stroke
			(width 0.254)
			(type default)
		)
		(layer "In6.Cu")
	)
	(gr_line
		(start 395.693646 -7.983728)
		(end 395.693646 -5.951728)
		(stroke
			(width 0.254)
			(type default)
		)
		(layer "In6.Cu")
	)
	(gr_line
		(start 395.693646 -6.051804)
		(end 396.023846 -6.051804)
		(stroke
			(width 0.254)
			(type default)
		)
		(layer "In6.Cu")
	)
	(gr_line
		(start 395.693646 -5.951728)
		(end 396.023846 -5.951728)
		(stroke
			(width 0.254)
			(type default)
		)
		(layer "In6.Cu")
	)
	(gr_line
		(start 395.693646 -3.88366)
		(end 395.693646 -1.85166)
		(stroke
			(width 0.254)
			(type default)
		)
		(layer "In6.Cu")
	)
	(gr_line
		(start 395.693646 -3.783584)
		(end 395.693646 -1.751584)
		(stroke
			(width 0.254)
			(type default)
		)
		(layer "In6.Cu")
	)
	(gr_line
		(start 395.693646 -1.85166)
		(end 396.023846 -1.85166)
		(stroke
			(width 0.254)
			(type default)
		)
		(layer "In6.Cu")
	)
	(gr_line
		(start 395.693646 -1.751584)
		(end 396.023846 -1.751584)
		(stroke
			(width 0.254)
			(type default)
		)
		(layer "In6.Cu")
	)
	(gr_line
		(start 395.795246 -12.207748)
		(end 395.795246 -10.404348)
		(stroke
			(width 0.254)
			(type default)
		)
		(layer "In6.Cu")
	)
	(gr_line
		(start 395.795246 -12.207748)
		(end 395.795246 -10.226548)
		(stroke
			(width 0.762)
			(type default)
		)
		(layer "In6.Cu")
	)
	(gr_line
		(start 395.795246 -12.107672)
		(end 395.795246 -10.304272)
		(stroke
			(width 0.254)
			(type default)
		)
		(layer "In6.Cu")
	)
	(gr_line
		(start 395.795246 -12.107672)
		(end 395.795246 -10.126472)
		(stroke
			(width 0.762)
			(type default)
		)
		(layer "In6.Cu")
	)
	(gr_line
		(start 395.795246 -10.404348)
		(end 395.896846 -10.404348)
		(stroke
			(width 0.254)
			(type default)
		)
		(layer "In6.Cu")
	)
	(gr_line
		(start 395.795246 -10.304272)
		(end 395.896846 -10.304272)
		(stroke
			(width 0.254)
			(type default)
		)
		(layer "In6.Cu")
	)
	(gr_line
		(start 395.795246 -8.007604)
		(end 395.795246 -6.204204)
		(stroke
			(width 0.254)
			(type default)
		)
		(layer "In6.Cu")
	)
	(gr_line
		(start 395.795246 -8.007604)
		(end 395.795246 -6.026404)
		(stroke
			(width 0.762)
			(type default)
		)
		(layer "In6.Cu")
	)
	(gr_line
		(start 395.795246 -7.907528)
		(end 395.795246 -6.104128)
		(stroke
			(width 0.254)
			(type default)
		)
		(layer "In6.Cu")
	)
	(gr_line
		(start 395.795246 -7.907528)
		(end 395.795246 -5.926328)
		(stroke
			(width 0.762)
			(type default)
		)
		(layer "In6.Cu")
	)
	(gr_line
		(start 395.795246 -6.204204)
		(end 395.896846 -6.204204)
		(stroke
			(width 0.254)
			(type default)
		)
		(layer "In6.Cu")
	)
	(gr_line
		(start 395.795246 -6.104128)
		(end 395.896846 -6.104128)
		(stroke
			(width 0.254)
			(type default)
		)
		(layer "In6.Cu")
	)
	(gr_line
		(start 395.795246 -3.80746)
		(end 395.795246 -2.00406)
		(stroke
			(width 0.254)
			(type default)
		)
		(layer "In6.Cu")
	)
	(gr_line
		(start 395.795246 -3.80746)
		(end 395.795246 -1.82626)
		(stroke
			(width 0.762)
			(type default)
		)
		(layer "In6.Cu")
	)
	(gr_line
		(start 395.795246 -3.707384)
		(end 395.795246 -1.903984)
		(stroke
			(width 0.254)
			(type default)
		)
		(layer "In6.Cu")
	)
	(gr_line
		(start 395.795246 -3.707384)
		(end 395.795246 -1.726184)
		(stroke
			(width 0.762)
			(type default)
		)
		(layer "In6.Cu")
	)
	(gr_line
		(start 395.795246 -2.00406)
		(end 395.896846 -2.00406)
		(stroke
			(width 0.254)
			(type default)
		)
		(layer "In6.Cu")
	)
	(gr_line
		(start 395.795246 -1.903984)
		(end 395.896846 -1.903984)
		(stroke
			(width 0.254)
			(type default)
		)
		(layer "In6.Cu")
	)
	(gr_line
		(start 395.896846 -12.309348)
		(end 395.846046 -12.309348)
		(stroke
			(width 0.254)
			(type default)
		)
		(layer "In6.Cu")
	)
	(gr_line
		(start 395.896846 -12.209272)
		(end 395.846046 -12.209272)
		(stroke
			(width 0.254)
			(type default)
		)
		(layer "In6.Cu")
	)
	(gr_line
		(start 395.896846 -10.404348)
		(end 395.896846 -12.309348)
		(stroke
			(width 0.254)
			(type default)
		)
		(layer "In6.Cu")
	)
	(gr_line
		(start 395.896846 -10.304272)
		(end 395.896846 -12.209272)
		(stroke
			(width 0.254)
			(type default)
		)
		(layer "In6.Cu")
	)
	(gr_line
		(start 395.896846 -8.109204)
		(end 395.846046 -8.109204)
		(stroke
			(width 0.254)
			(type default)
		)
		(layer "In6.Cu")
	)
	(gr_line
		(start 395.896846 -8.009128)
		(end 395.846046 -8.009128)
		(stroke
			(width 0.254)
			(type default)
		)
		(layer "In6.Cu")
	)
	(gr_line
		(start 395.896846 -6.204204)
		(end 395.896846 -8.109204)
		(stroke
			(width 0.254)
			(type default)
		)
		(layer "In6.Cu")
	)
	(gr_line
		(start 395.896846 -6.104128)
		(end 395.896846 -8.009128)
		(stroke
			(width 0.254)
			(type default)
		)
		(layer "In6.Cu")
	)
	(gr_line
		(start 395.896846 -3.90906)
		(end 395.846046 -3.90906)
		(stroke
			(width 0.254)
			(type default)
		)
		(layer "In6.Cu")
	)
	(gr_line
		(start 395.896846 -3.808984)
		(end 395.846046 -3.808984)
		(stroke
			(width 0.254)
			(type default)
		)
		(layer "In6.Cu")
	)
	(gr_line
		(start 395.896846 -2.00406)
		(end 395.896846 -3.90906)
		(stroke
			(width 0.254)
			(type default)
		)
		(layer "In6.Cu")
	)
	(gr_line
		(start 395.896846 -1.903984)
		(end 395.896846 -3.808984)
		(stroke
			(width 0.254)
			(type default)
		)
		(layer "In6.Cu")
	)
	(gr_line
		(start 395.947646 -12.233148)
		(end 395.947646 -10.251948)
		(stroke
			(width 0.762)
			(type default)
		)
		(layer "In6.Cu")
	)
	(gr_line
		(start 395.947646 -12.133072)
		(end 395.947646 -10.151872)
		(stroke
			(width 0.762)
			(type default)
		)
		(layer "In6.Cu")
	)
	(gr_line
		(start 395.947646 -8.033004)
		(end 395.947646 -6.051804)
		(stroke
			(width 0.762)
			(type default)
		)
		(layer "In6.Cu")
	)
	(gr_line
		(start 395.947646 -7.932928)
		(end 395.947646 -5.951728)
		(stroke
			(width 0.762)
			(type default)
		)
		(layer "In6.Cu")
	)
	(gr_line
		(start 395.947646 -3.83286)
		(end 395.947646 -1.85166)
		(stroke
			(width 0.762)
			(type default)
		)
		(layer "In6.Cu")
	)
	(gr_line
		(start 395.947646 -3.732784)
		(end 395.947646 -1.751584)
		(stroke
			(width 0.762)
			(type default)
		)
		(layer "In6.Cu")
	)
	(gr_line
		(start 396.023846 -12.207748)
		(end 395.795246 -12.207748)
		(stroke
			(width 0.254)
			(type default)
		)
		(layer "In6.Cu")
	)
	(gr_line
		(start 396.023846 -12.107672)
		(end 395.795246 -12.107672)
		(stroke
			(width 0.254)
			(type default)
		)
		(layer "In6.Cu")
	)
	(gr_line
		(start 396.023846 -10.251948)
		(end 396.023846 -12.207748)
		(stroke
			(width 0.254)
			(type default)
		)
		(layer "In6.Cu")
	)
	(gr_line
		(start 396.023846 -10.151872)
		(end 396.023846 -12.107672)
		(stroke
			(width 0.254)
			(type default)
		)
		(layer "In6.Cu")
	)
	(gr_line
		(start 396.023846 -8.007604)
		(end 395.795246 -8.007604)
		(stroke
			(width 0.254)
			(type default)
		)
		(layer "In6.Cu")
	)
	(gr_line
		(start 396.023846 -7.907528)
		(end 395.795246 -7.907528)
		(stroke
			(width 0.254)
			(type default)
		)
		(layer "In6.Cu")
	)
	(gr_line
		(start 396.023846 -6.051804)
		(end 396.023846 -8.007604)
		(stroke
			(width 0.254)
			(type default)
		)
		(layer "In6.Cu")
	)
	(gr_line
		(start 396.023846 -5.951728)
		(end 396.023846 -7.907528)
		(stroke
			(width 0.254)
			(type default)
		)
		(layer "In6.Cu")
	)
	(gr_line
		(start 396.023846 -3.80746)
		(end 395.795246 -3.80746)
		(stroke
			(width 0.254)
			(type default)
		)
		(layer "In6.Cu")
	)
	(gr_line
		(start 396.023846 -3.707384)
		(end 395.795246 -3.707384)
		(stroke
			(width 0.254)
			(type default)
		)
		(layer "In6.Cu")
	)
	(gr_line
		(start 396.023846 -1.85166)
		(end 396.023846 -3.80746)
		(stroke
			(width 0.254)
			(type default)
		)
		(layer "In6.Cu")
	)
	(gr_line
		(start 396.023846 -1.751584)
		(end 396.023846 -3.707384)
		(stroke
			(width 0.254)
			(type default)
		)
		(layer "In6.Cu")
	)
	(gr_line
		(start 396.074646 -12.563348)
		(end 396.074646 -12.512548)
		(stroke
			(width 0.1016)
			(type default)
		)
		(layer "In6.Cu")
	)
	(gr_line
		(start 396.074646 -12.563348)
		(end 396.481046 -12.563348)
		(stroke
			(width 0.1016)
			(type default)
		)
		(layer "In6.Cu")
	)
	(gr_line
		(start 396.074646 -12.512548)
		(end 395.312646 -12.512548)
		(stroke
			(width 0.1016)
			(type default)
		)
		(layer "In6.Cu")
	)
	(gr_line
		(start 396.074646 -12.463272)
		(end 396.074646 -12.412472)
		(stroke
			(width 0.1016)
			(type default)
		)
		(layer "In6.Cu")
	)
	(gr_line
		(start 396.074646 -12.463272)
		(end 396.481046 -12.463272)
		(stroke
			(width 0.1016)
			(type default)
		)
		(layer "In6.Cu")
	)
	(gr_line
		(start 396.074646 -12.412472)
		(end 395.312646 -12.412472)
		(stroke
			(width 0.1016)
			(type default)
		)
		(layer "In6.Cu")
	)
	(gr_line
		(start 396.074646 -12.233148)
		(end 396.074646 -10.251948)
		(stroke
			(width 0.762)
			(type default)
		)
		(layer "In6.Cu")
	)
	(gr_line
		(start 396.074646 -12.133072)
		(end 396.074646 -10.151872)
		(stroke
			(width 0.762)
			(type default)
		)
		(layer "In6.Cu")
	)
	(gr_line
		(start 396.074646 -8.363204)
		(end 396.074646 -8.312404)
		(stroke
			(width 0.1016)
			(type default)
		)
		(layer "In6.Cu")
	)
	(gr_line
		(start 396.074646 -8.363204)
		(end 396.481046 -8.363204)
		(stroke
			(width 0.1016)
			(type default)
		)
		(layer "In6.Cu")
	)
	(gr_line
		(start 396.074646 -8.312404)
		(end 395.312646 -8.312404)
		(stroke
			(width 0.1016)
			(type default)
		)
		(layer "In6.Cu")
	)
	(gr_line
		(start 396.074646 -8.263128)
		(end 396.074646 -8.212328)
		(stroke
			(width 0.1016)
			(type default)
		)
		(layer "In6.Cu")
	)
	(gr_line
		(start 396.074646 -8.263128)
		(end 396.481046 -8.263128)
		(stroke
			(width 0.1016)
			(type default)
		)
		(layer "In6.Cu")
	)
	(gr_line
		(start 396.074646 -8.212328)
		(end 395.312646 -8.212328)
		(stroke
			(width 0.1016)
			(type default)
		)
		(layer "In6.Cu")
	)
	(gr_line
		(start 396.074646 -8.033004)
		(end 396.074646 -6.051804)
		(stroke
			(width 0.762)
			(type default)
		)
		(layer "In6.Cu")
	)
	(gr_line
		(start 396.074646 -7.932928)
		(end 396.074646 -5.951728)
		(stroke
			(width 0.762)
			(type default)
		)
		(layer "In6.Cu")
	)
	(gr_line
		(start 396.074646 -4.16306)
		(end 396.074646 -4.11226)
		(stroke
			(width 0.1016)
			(type default)
		)
		(layer "In6.Cu")
	)
	(gr_line
		(start 396.074646 -4.16306)
		(end 396.481046 -4.16306)
		(stroke
			(width 0.1016)
			(type default)
		)
		(layer "In6.Cu")
	)
	(gr_line
		(start 396.074646 -4.11226)
		(end 395.312646 -4.11226)
		(stroke
			(width 0.1016)
			(type default)
		)
		(layer "In6.Cu")
	)
	(gr_line
		(start 396.074646 -4.062984)
		(end 396.074646 -4.012184)
		(stroke
			(width 0.1016)
			(type default)
		)
		(layer "In6.Cu")
	)
	(gr_line
		(start 396.074646 -4.062984)
		(end 396.481046 -4.062984)
		(stroke
			(width 0.1016)
			(type default)
		)
		(layer "In6.Cu")
	)
	(gr_line
		(start 396.074646 -4.012184)
		(end 395.312646 -4.012184)
		(stroke
			(width 0.1016)
			(type default)
		)
		(layer "In6.Cu")
	)
	(gr_line
		(start 396.074646 -3.83286)
		(end 396.074646 -1.85166)
		(stroke
			(width 0.762)
			(type default)
		)
		(layer "In6.Cu")
	)
	(gr_line
		(start 396.074646 -3.732784)
		(end 396.074646 -1.751584)
		(stroke
			(width 0.762)
			(type default)
		)
		(layer "In6.Cu")
	)
	(gr_line
		(start 396.100046 -12.283948)
		(end 395.693646 -12.283948)
		(stroke
			(width 0.254)
			(type default)
		)
		(layer "In6.Cu")
	)
	(gr_line
		(start 396.100046 -12.183872)
		(end 395.693646 -12.183872)
		(stroke
			(width 0.254)
			(type default)
		)
		(layer "In6.Cu")
	)
	(gr_line
		(start 396.100046 -10.175748)
		(end 396.100046 -12.283948)
		(stroke
			(width 0.254)
			(type default)
		)
		(layer "In6.Cu")
	)
	(gr_line
		(start 396.100046 -10.075672)
		(end 396.100046 -12.183872)
		(stroke
			(width 0.254)
			(type default)
		)
		(layer "In6.Cu")
	)
	(gr_line
		(start 396.100046 -8.083804)
		(end 395.693646 -8.083804)
		(stroke
			(width 0.254)
			(type default)
		)
		(layer "In6.Cu")
	)
	(gr_line
		(start 396.100046 -7.983728)
		(end 395.693646 -7.983728)
		(stroke
			(width 0.254)
			(type default)
		)
		(layer "In6.Cu")
	)
	(gr_line
		(start 396.100046 -5.975604)
		(end 396.100046 -8.083804)
		(stroke
			(width 0.254)
			(type default)
		)
		(layer "In6.Cu")
	)
	(gr_line
		(start 396.100046 -5.875528)
		(end 396.100046 -7.983728)
		(stroke
			(width 0.254)
			(type default)
		)
		(layer "In6.Cu")
	)
	(gr_line
		(start 396.100046 -3.88366)
		(end 395.693646 -3.88366)
		(stroke
			(width 0.254)
			(type default)
		)
		(layer "In6.Cu")
	)
	(gr_line
		(start 396.100046 -3.783584)
		(end 395.693646 -3.783584)
		(stroke
			(width 0.254)
			(type default)
		)
		(layer "In6.Cu")
	)
	(gr_line
		(start 396.100046 -1.77546)
		(end 396.100046 -3.88366)
		(stroke
			(width 0.254)
			(type default)
		)
		(layer "In6.Cu")
	)
	(gr_line
		(start 396.100046 -1.675384)
		(end 396.100046 -3.783584)
		(stroke
			(width 0.254)
			(type default)
		)
		(layer "In6.Cu")
	)
	(gr_line
		(start 396.150846 -12.233148)
		(end 396.150846 -10.251948)
		(stroke
			(width 0.762)
			(type default)
		)
		(layer "In6.Cu")
	)
	(gr_line
		(start 396.150846 -12.133072)
		(end 396.150846 -10.151872)
		(stroke
			(width 0.762)
			(type default)
		)
		(layer "In6.Cu")
	)
	(gr_line
		(start 396.150846 -8.033004)
		(end 396.150846 -6.051804)
		(stroke
			(width 0.762)
			(type default)
		)
		(layer "In6.Cu")
	)
	(gr_line
		(start 396.150846 -7.932928)
		(end 396.150846 -5.951728)
		(stroke
			(width 0.762)
			(type default)
		)
		(layer "In6.Cu")
	)
	(gr_line
		(start 396.150846 -3.83286)
		(end 396.150846 -1.85166)
		(stroke
			(width 0.762)
			(type default)
		)
		(layer "In6.Cu")
	)
	(gr_line
		(start 396.150846 -3.732784)
		(end 396.150846 -1.751584)
		(stroke
			(width 0.762)
			(type default)
		)
		(layer "In6.Cu")
	)
	(gr_line
		(start 396.176246 -12.360148)
		(end 395.617446 -12.360148)
		(stroke
			(width 0.254)
			(type default)
		)
		(layer "In6.Cu")
	)
	(gr_line
		(start 396.176246 -12.260072)
		(end 395.617446 -12.260072)
		(stroke
			(width 0.254)
			(type default)
		)
		(layer "In6.Cu")
	)
	(gr_line
		(start 396.176246 -10.124948)
		(end 396.176246 -12.360148)
		(stroke
			(width 0.254)
			(type default)
		)
		(layer "In6.Cu")
	)
	(gr_line
		(start 396.176246 -10.024872)
		(end 396.176246 -12.260072)
		(stroke
			(width 0.254)
			(type default)
		)
		(layer "In6.Cu")
	)
	(gr_line
		(start 396.176246 -8.160004)
		(end 395.617446 -8.160004)
		(stroke
			(width 0.254)
			(type default)
		)
		(layer "In6.Cu")
	)
	(gr_line
		(start 396.176246 -8.059928)
		(end 395.617446 -8.059928)
		(stroke
			(width 0.254)
			(type default)
		)
		(layer "In6.Cu")
	)
	(gr_line
		(start 396.176246 -5.924804)
		(end 396.176246 -8.160004)
		(stroke
			(width 0.254)
			(type default)
		)
		(layer "In6.Cu")
	)
	(gr_line
		(start 396.176246 -5.824728)
		(end 396.176246 -8.059928)
		(stroke
			(width 0.254)
			(type default)
		)
		(layer "In6.Cu")
	)
	(gr_line
		(start 396.176246 -3.95986)
		(end 395.617446 -3.95986)
		(stroke
			(width 0.254)
			(type default)
		)
		(layer "In6.Cu")
	)
	(gr_line
		(start 396.176246 -3.859784)
		(end 395.617446 -3.859784)
		(stroke
			(width 0.254)
			(type default)
		)
		(layer "In6.Cu")
	)
	(gr_line
		(start 396.176246 -1.72466)
		(end 396.176246 -3.95986)
		(stroke
			(width 0.254)
			(type default)
		)
		(layer "In6.Cu")
	)
	(gr_line
		(start 396.176246 -1.624584)
		(end 396.176246 -3.859784)
		(stroke
			(width 0.254)
			(type default)
		)
		(layer "In6.Cu")
	)
	(gr_line
		(start 396.252446 -12.385548)
		(end 395.541246 -12.385548)
		(stroke
			(width 0.254)
			(type default)
		)
		(layer "In6.Cu")
	)
	(gr_line
		(start 396.252446 -12.285472)
		(end 395.541246 -12.285472)
		(stroke
			(width 0.254)
			(type default)
		)
		(layer "In6.Cu")
	)
	(gr_line
		(start 396.252446 -10.048748)
		(end 396.252446 -12.385548)
		(stroke
			(width 0.254)
			(type default)
		)
		(layer "In6.Cu")
	)
	(gr_line
		(start 396.252446 -9.948672)
		(end 396.252446 -12.285472)
		(stroke
			(width 0.254)
			(type default)
		)
		(layer "In6.Cu")
	)
	(gr_line
		(start 396.252446 -8.185404)
		(end 395.541246 -8.185404)
		(stroke
			(width 0.254)
			(type default)
		)
		(layer "In6.Cu")
	)
	(gr_line
		(start 396.252446 -8.085328)
		(end 395.541246 -8.085328)
		(stroke
			(width 0.254)
			(type default)
		)
		(layer "In6.Cu")
	)
	(gr_line
		(start 396.252446 -5.848604)
		(end 396.252446 -8.185404)
		(stroke
			(width 0.254)
			(type default)
		)
		(layer "In6.Cu")
	)
	(gr_line
		(start 396.252446 -5.748528)
		(end 396.252446 -8.085328)
		(stroke
			(width 0.254)
			(type default)
		)
		(layer "In6.Cu")
	)
	(gr_line
		(start 396.252446 -3.98526)
		(end 395.541246 -3.98526)
		(stroke
			(width 0.254)
			(type default)
		)
		(layer "In6.Cu")
	)
	(gr_line
		(start 396.252446 -3.885184)
		(end 395.541246 -3.885184)
		(stroke
			(width 0.254)
			(type default)
		)
		(layer "In6.Cu")
	)
	(gr_line
		(start 396.252446 -1.64846)
		(end 396.252446 -3.98526)
		(stroke
			(width 0.254)
			(type default)
		)
		(layer "In6.Cu")
	)
	(gr_line
		(start 396.252446 -1.548384)
		(end 396.252446 -3.885184)
		(stroke
			(width 0.254)
			(type default)
		)
		(layer "In6.Cu")
	)
	(gr_line
		(start 396.277846 -12.512548)
		(end 395.287246 -12.512548)
		(stroke
			(width 0.1016)
			(type default)
		)
		(layer "In6.Cu")
	)
	(gr_line
		(start 396.277846 -12.436348)
		(end 395.465046 -12.436348)
		(stroke
			(width 0.254)
			(type default)
		)
		(layer "In6.Cu")
	)
	(gr_line
		(start 396.277846 -12.412472)
		(end 395.287246 -12.412472)
		(stroke
			(width 0.1016)
			(type default)
		)
		(layer "In6.Cu")
	)
	(gr_line
		(start 396.277846 -12.336272)
		(end 395.465046 -12.336272)
		(stroke
			(width 0.254)
			(type default)
		)
		(layer "In6.Cu")
	)
	(gr_line
		(start 396.277846 -10.023348)
		(end 396.277846 -12.436348)
		(stroke
			(width 0.254)
			(type default)
		)
		(layer "In6.Cu")
	)
	(gr_line
		(start 396.277846 -9.923272)
		(end 396.277846 -12.336272)
		(stroke
			(width 0.254)
			(type default)
		)
		(layer "In6.Cu")
	)
	(gr_line
		(start 396.277846 -8.312404)
		(end 395.287246 -8.312404)
		(stroke
			(width 0.1016)
			(type default)
		)
		(layer "In6.Cu")
	)
	(gr_line
		(start 396.277846 -8.236204)
		(end 395.465046 -8.236204)
		(stroke
			(width 0.254)
			(type default)
		)
		(layer "In6.Cu")
	)
	(gr_line
		(start 396.277846 -8.212328)
		(end 395.287246 -8.212328)
		(stroke
			(width 0.1016)
			(type default)
		)
		(layer "In6.Cu")
	)
	(gr_line
		(start 396.277846 -8.136128)
		(end 395.465046 -8.136128)
		(stroke
			(width 0.254)
			(type default)
		)
		(layer "In6.Cu")
	)
	(gr_line
		(start 396.277846 -5.823204)
		(end 396.277846 -8.236204)
		(stroke
			(width 0.254)
			(type default)
		)
		(layer "In6.Cu")
	)
	(gr_line
		(start 396.277846 -5.723128)
		(end 396.277846 -8.136128)
		(stroke
			(width 0.254)
			(type default)
		)
		(layer "In6.Cu")
	)
	(gr_line
		(start 396.277846 -4.11226)
		(end 395.287246 -4.11226)
		(stroke
			(width 0.1016)
			(type default)
		)
		(layer "In6.Cu")
	)
	(gr_line
		(start 396.277846 -4.03606)
		(end 395.465046 -4.03606)
		(stroke
			(width 0.254)
			(type default)
		)
		(layer "In6.Cu")
	)
	(gr_line
		(start 396.277846 -4.012184)
		(end 395.287246 -4.012184)
		(stroke
			(width 0.1016)
			(type default)
		)
		(layer "In6.Cu")
	)
	(gr_line
		(start 396.277846 -3.935984)
		(end 395.465046 -3.935984)
		(stroke
			(width 0.254)
			(type default)
		)
		(layer "In6.Cu")
	)
	(gr_line
		(start 396.277846 -1.62306)
		(end 396.277846 -4.03606)
		(stroke
			(width 0.254)
			(type default)
		)
		(layer "In6.Cu")
	)
	(gr_line
		(start 396.277846 -1.522984)
		(end 396.277846 -3.935984)
		(stroke
			(width 0.254)
			(type default)
		)
		(layer "In6.Cu")
	)
	(gr_line
		(start 396.303246 -12.461748)
		(end 395.439646 -12.461748)
		(stroke
			(width 0.254)
			(type default)
		)
		(layer "In6.Cu")
	)
	(gr_line
		(start 396.303246 -12.361672)
		(end 395.439646 -12.361672)
		(stroke
			(width 0.254)
			(type default)
		)
		(layer "In6.Cu")
	)
	(gr_line
		(start 396.303246 -9.997948)
		(end 396.303246 -12.461748)
		(stroke
			(width 0.254)
			(type default)
		)
		(layer "In6.Cu")
	)
	(gr_line
		(start 396.303246 -9.897872)
		(end 396.303246 -12.361672)
		(stroke
			(width 0.254)
			(type default)
		)
		(layer "In6.Cu")
	)
	(gr_line
		(start 396.303246 -8.261604)
		(end 395.439646 -8.261604)
		(stroke
			(width 0.254)
			(type default)
		)
		(layer "In6.Cu")
	)
	(gr_line
		(start 396.303246 -8.161528)
		(end 395.439646 -8.161528)
		(stroke
			(width 0.254)
			(type default)
		)
		(layer "In6.Cu")
	)
	(gr_line
		(start 396.303246 -5.797804)
		(end 396.303246 -8.261604)
		(stroke
			(width 0.254)
			(type default)
		)
		(layer "In6.Cu")
	)
	(gr_line
		(start 396.303246 -5.697728)
		(end 396.303246 -8.161528)
		(stroke
			(width 0.254)
			(type default)
		)
		(layer "In6.Cu")
	)
	(gr_line
		(start 396.303246 -4.06146)
		(end 395.439646 -4.06146)
		(stroke
			(width 0.254)
			(type default)
		)
		(layer "In6.Cu")
	)
	(gr_line
		(start 396.303246 -3.961384)
		(end 395.439646 -3.961384)
		(stroke
			(width 0.254)
			(type default)
		)
		(layer "In6.Cu")
	)
	(gr_line
		(start 396.303246 -1.59766)
		(end 396.303246 -4.06146)
		(stroke
			(width 0.254)
			(type default)
		)
		(layer "In6.Cu")
	)
	(gr_line
		(start 396.303246 -1.497584)
		(end 396.303246 -3.961384)
		(stroke
			(width 0.254)
			(type default)
		)
		(layer "In6.Cu")
	)
	(gr_line
		(start 396.354046 -12.487148)
		(end 395.414246 -12.487148)
		(stroke
			(width 0.254)
			(type default)
		)
		(layer "In6.Cu")
	)
	(gr_line
		(start 396.354046 -12.387072)
		(end 395.414246 -12.387072)
		(stroke
			(width 0.254)
			(type default)
		)
		(layer "In6.Cu")
	)
	(gr_line
		(start 396.354046 -9.997948)
		(end 396.354046 -12.487148)
		(stroke
			(width 0.254)
			(type default)
		)
		(layer "In6.Cu")
	)
	(gr_line
		(start 396.354046 -9.897872)
		(end 396.354046 -12.387072)
		(stroke
			(width 0.254)
			(type default)
		)
		(layer "In6.Cu")
	)
	(gr_line
		(start 396.354046 -8.287004)
		(end 395.414246 -8.287004)
		(stroke
			(width 0.254)
			(type default)
		)
		(layer "In6.Cu")
	)
	(gr_line
		(start 396.354046 -8.186928)
		(end 395.414246 -8.186928)
		(stroke
			(width 0.254)
			(type default)
		)
		(layer "In6.Cu")
	)
	(gr_line
		(start 396.354046 -5.797804)
		(end 396.354046 -8.287004)
		(stroke
			(width 0.254)
			(type default)
		)
		(layer "In6.Cu")
	)
	(gr_line
		(start 396.354046 -5.697728)
		(end 396.354046 -8.186928)
		(stroke
			(width 0.254)
			(type default)
		)
		(layer "In6.Cu")
	)
	(gr_line
		(start 396.354046 -4.08686)
		(end 395.414246 -4.08686)
		(stroke
			(width 0.254)
			(type default)
		)
		(layer "In6.Cu")
	)
	(gr_line
		(start 396.354046 -3.986784)
		(end 395.414246 -3.986784)
		(stroke
			(width 0.254)
			(type default)
		)
		(layer "In6.Cu")
	)
	(gr_line
		(start 396.354046 -1.59766)
		(end 396.354046 -4.08686)
		(stroke
			(width 0.254)
			(type default)
		)
		(layer "In6.Cu")
	)
	(gr_line
		(start 396.354046 -1.497584)
		(end 396.354046 -3.986784)
		(stroke
			(width 0.254)
			(type default)
		)
		(layer "In6.Cu")
	)
	(gr_line
		(start 396.379446 -12.487148)
		(end 395.414246 -12.487148)
		(stroke
			(width 0.2032)
			(type default)
		)
		(layer "In6.Cu")
	)
	(gr_line
		(start 396.379446 -12.387072)
		(end 395.414246 -12.387072)
		(stroke
			(width 0.2032)
			(type default)
		)
		(layer "In6.Cu")
	)
	(gr_line
		(start 396.379446 -9.947148)
		(end 396.379446 -12.487148)
		(stroke
			(width 0.2032)
			(type default)
		)
		(layer "In6.Cu")
	)
	(gr_line
		(start 396.379446 -9.847072)
		(end 396.379446 -12.387072)
		(stroke
			(width 0.2032)
			(type default)
		)
		(layer "In6.Cu")
	)
	(gr_line
		(start 396.379446 -8.287004)
		(end 395.414246 -8.287004)
		(stroke
			(width 0.2032)
			(type default)
		)
		(layer "In6.Cu")
	)
	(gr_line
		(start 396.379446 -8.186928)
		(end 395.414246 -8.186928)
		(stroke
			(width 0.2032)
			(type default)
		)
		(layer "In6.Cu")
	)
	(gr_line
		(start 396.379446 -5.747004)
		(end 396.379446 -8.287004)
		(stroke
			(width 0.2032)
			(type default)
		)
		(layer "In6.Cu")
	)
	(gr_line
		(start 396.379446 -5.646928)
		(end 396.379446 -8.186928)
		(stroke
			(width 0.2032)
			(type default)
		)
		(layer "In6.Cu")
	)
	(gr_line
		(start 396.379446 -4.08686)
		(end 395.414246 -4.08686)
		(stroke
			(width 0.2032)
			(type default)
		)
		(layer "In6.Cu")
	)
	(gr_line
		(start 396.379446 -3.986784)
		(end 395.414246 -3.986784)
		(stroke
			(width 0.2032)
			(type default)
		)
		(layer "In6.Cu")
	)
	(gr_line
		(start 396.379446 -1.54686)
		(end 396.379446 -4.08686)
		(stroke
			(width 0.2032)
			(type default)
		)
		(layer "In6.Cu")
	)
	(gr_line
		(start 396.379446 -1.446784)
		(end 396.379446 -3.986784)
		(stroke
			(width 0.2032)
			(type default)
		)
		(layer "In6.Cu")
	)
	(gr_line
		(start 396.430246 -12.512548)
		(end 395.363446 -12.512548)
		(stroke
			(width 0.2032)
			(type default)
		)
		(layer "In6.Cu")
	)
	(gr_line
		(start 396.430246 -12.412472)
		(end 395.363446 -12.412472)
		(stroke
			(width 0.2032)
			(type default)
		)
		(layer "In6.Cu")
	)
	(gr_line
		(start 396.430246 -9.947148)
		(end 396.430246 -12.512548)
		(stroke
			(width 0.2032)
			(type default)
		)
		(layer "In6.Cu")
	)
	(gr_line
		(start 396.430246 -9.847072)
		(end 396.430246 -12.412472)
		(stroke
			(width 0.2032)
			(type default)
		)
		(layer "In6.Cu")
	)
	(gr_line
		(start 396.430246 -8.312404)
		(end 395.363446 -8.312404)
		(stroke
			(width 0.2032)
			(type default)
		)
		(layer "In6.Cu")
	)
	(gr_line
		(start 396.430246 -8.212328)
		(end 395.363446 -8.212328)
		(stroke
			(width 0.2032)
			(type default)
		)
		(layer "In6.Cu")
	)
	(gr_line
		(start 396.430246 -5.747004)
		(end 396.430246 -8.312404)
		(stroke
			(width 0.2032)
			(type default)
		)
		(layer "In6.Cu")
	)
	(gr_line
		(start 396.430246 -5.646928)
		(end 396.430246 -8.212328)
		(stroke
			(width 0.2032)
			(type default)
		)
		(layer "In6.Cu")
	)
	(gr_line
		(start 396.430246 -4.11226)
		(end 395.363446 -4.11226)
		(stroke
			(width 0.2032)
			(type default)
		)
		(layer "In6.Cu")
	)
	(gr_line
		(start 396.430246 -4.012184)
		(end 395.363446 -4.012184)
		(stroke
			(width 0.2032)
			(type default)
		)
		(layer "In6.Cu")
	)
	(gr_line
		(start 396.430246 -1.54686)
		(end 396.430246 -4.11226)
		(stroke
			(width 0.2032)
			(type default)
		)
		(layer "In6.Cu")
	)
	(gr_line
		(start 396.430246 -1.446784)
		(end 396.430246 -4.012184)
		(stroke
			(width 0.2032)
			(type default)
		)
		(layer "In6.Cu")
	)
	(gr_line
		(start 396.455646 -12.512548)
		(end 395.338046 -12.512548)
		(stroke
			(width 0.1016)
			(type default)
		)
		(layer "In6.Cu")
	)
	(gr_line
		(start 396.455646 -12.412472)
		(end 395.338046 -12.412472)
		(stroke
			(width 0.1016)
			(type default)
		)
		(layer "In6.Cu")
	)
	(gr_line
		(start 396.455646 -9.921748)
		(end 396.455646 -12.512548)
		(stroke
			(width 0.1016)
			(type default)
		)
		(layer "In6.Cu")
	)
	(gr_line
		(start 396.455646 -9.821672)
		(end 396.455646 -12.412472)
		(stroke
			(width 0.1016)
			(type default)
		)
		(layer "In6.Cu")
	)
	(gr_line
		(start 396.455646 -8.312404)
		(end 395.338046 -8.312404)
		(stroke
			(width 0.1016)
			(type default)
		)
		(layer "In6.Cu")
	)
	(gr_line
		(start 396.455646 -8.212328)
		(end 395.338046 -8.212328)
		(stroke
			(width 0.1016)
			(type default)
		)
		(layer "In6.Cu")
	)
	(gr_line
		(start 396.455646 -5.721604)
		(end 396.455646 -8.312404)
		(stroke
			(width 0.1016)
			(type default)
		)
		(layer "In6.Cu")
	)
	(gr_line
		(start 396.455646 -5.621528)
		(end 396.455646 -8.212328)
		(stroke
			(width 0.1016)
			(type default)
		)
		(layer "In6.Cu")
	)
	(gr_line
		(start 396.455646 -4.11226)
		(end 395.338046 -4.11226)
		(stroke
			(width 0.1016)
			(type default)
		)
		(layer "In6.Cu")
	)
	(gr_line
		(start 396.455646 -4.012184)
		(end 395.338046 -4.012184)
		(stroke
			(width 0.1016)
			(type default)
		)
		(layer "In6.Cu")
	)
	(gr_line
		(start 396.455646 -1.52146)
		(end 396.455646 -4.11226)
		(stroke
			(width 0.1016)
			(type default)
		)
		(layer "In6.Cu")
	)
	(gr_line
		(start 396.455646 -1.421384)
		(end 396.455646 -4.012184)
		(stroke
			(width 0.1016)
			(type default)
		)
		(layer "In6.Cu")
	)
	(gr_line
		(start 396.481046 -12.563348)
		(end 396.074646 -12.563348)
		(stroke
			(width 0.1016)
			(type default)
		)
		(layer "In6.Cu")
	)
	(gr_line
		(start 396.481046 -12.563348)
		(end 396.481046 -9.896348)
		(stroke
			(width 0.1016)
			(type default)
		)
		(layer "In6.Cu")
	)
	(gr_line
		(start 396.481046 -12.463272)
		(end 396.074646 -12.463272)
		(stroke
			(width 0.1016)
			(type default)
		)
		(layer "In6.Cu")
	)
	(gr_line
		(start 396.481046 -12.463272)
		(end 396.481046 -9.796272)
		(stroke
			(width 0.1016)
			(type default)
		)
		(layer "In6.Cu")
	)
	(gr_line
		(start 396.481046 -9.896348)
		(end 395.287246 -9.896348)
		(stroke
			(width 0.1016)
			(type default)
		)
		(layer "In6.Cu")
	)
	(gr_line
		(start 396.481046 -9.896348)
		(end 396.481046 -12.563348)
		(stroke
			(width 0.1016)
			(type default)
		)
		(layer "In6.Cu")
	)
	(gr_line
		(start 396.481046 -9.796272)
		(end 395.287246 -9.796272)
		(stroke
			(width 0.1016)
			(type default)
		)
		(layer "In6.Cu")
	)
	(gr_line
		(start 396.481046 -9.796272)
		(end 396.481046 -12.463272)
		(stroke
			(width 0.1016)
			(type default)
		)
		(layer "In6.Cu")
	)
	(gr_line
		(start 396.481046 -8.363204)
		(end 396.074646 -8.363204)
		(stroke
			(width 0.1016)
			(type default)
		)
		(layer "In6.Cu")
	)
	(gr_line
		(start 396.481046 -8.363204)
		(end 396.481046 -5.696204)
		(stroke
			(width 0.1016)
			(type default)
		)
		(layer "In6.Cu")
	)
	(gr_line
		(start 396.481046 -8.263128)
		(end 396.074646 -8.263128)
		(stroke
			(width 0.1016)
			(type default)
		)
		(layer "In6.Cu")
	)
	(gr_line
		(start 396.481046 -8.263128)
		(end 396.481046 -5.596128)
		(stroke
			(width 0.1016)
			(type default)
		)
		(layer "In6.Cu")
	)
	(gr_line
		(start 396.481046 -5.696204)
		(end 395.287246 -5.696204)
		(stroke
			(width 0.1016)
			(type default)
		)
		(layer "In6.Cu")
	)
	(gr_line
		(start 396.481046 -5.696204)
		(end 396.481046 -8.363204)
		(stroke
			(width 0.1016)
			(type default)
		)
		(layer "In6.Cu")
	)
	(gr_line
		(start 396.481046 -5.596128)
		(end 395.287246 -5.596128)
		(stroke
			(width 0.1016)
			(type default)
		)
		(layer "In6.Cu")
	)
	(gr_line
		(start 396.481046 -5.596128)
		(end 396.481046 -8.263128)
		(stroke
			(width 0.1016)
			(type default)
		)
		(layer "In6.Cu")
	)
	(gr_line
		(start 396.481046 -4.16306)
		(end 396.074646 -4.16306)
		(stroke
			(width 0.1016)
			(type default)
		)
		(layer "In6.Cu")
	)
	(gr_line
		(start 396.481046 -4.16306)
		(end 396.481046 -1.49606)
		(stroke
			(width 0.1016)
			(type default)
		)
		(layer "In6.Cu")
	)
	(gr_line
		(start 396.481046 -4.062984)
		(end 396.074646 -4.062984)
		(stroke
			(width 0.1016)
			(type default)
		)
		(layer "In6.Cu")
	)
	(gr_line
		(start 396.481046 -4.062984)
		(end 396.481046 -1.395984)
		(stroke
			(width 0.1016)
			(type default)
		)
		(layer "In6.Cu")
	)
	(gr_line
		(start 396.481046 -1.49606)
		(end 395.287246 -1.49606)
		(stroke
			(width 0.1016)
			(type default)
		)
		(layer "In6.Cu")
	)
	(gr_line
		(start 396.481046 -1.49606)
		(end 396.481046 -4.16306)
		(stroke
			(width 0.1016)
			(type default)
		)
		(layer "In6.Cu")
	)
	(gr_line
		(start 396.481046 -1.395984)
		(end 395.287246 -1.395984)
		(stroke
			(width 0.1016)
			(type default)
		)
		(layer "In6.Cu")
	)
	(gr_line
		(start 396.481046 -1.395984)
		(end 396.481046 -4.062984)
		(stroke
			(width 0.1016)
			(type default)
		)
		(layer "In6.Cu")
	)
	(gr_line
		(start 397.519906 -30.99562)
		(end 396.249906 -30.99562)
		(stroke
			(width 0.7874)
			(type default)
		)
		(layer "In6.Cu")
	)
	(gr_line
		(start 399.224246 -24.6634)
		(end 399.224246 -23.3934)
		(stroke
			(width 0.7874)
			(type default)
		)
		(layer "In6.Cu")
	)
	(gr_line
		(start 404.997412 -26.8224)
		(end 406.267412 -26.8224)
		(stroke
			(width 0.7874)
			(type default)
		)
		(layer "In6.Cu")
	)
	(gr_line
		(start 405.228552 -29.30906)
		(end 406.498552 -29.30906)
		(stroke
			(width 0.7874)
			(type default)
		)
		(layer "In6.Cu")
	)
	(gr_line
		(start 410.459682 -30.594808)
		(end 411.729682 -30.594808)
		(stroke
			(width 0.7874)
			(type default)
		)
		(layer "In6.Cu")
	)
	(gr_line
		(start 410.859986 -23.57882)
		(end 412.129986 -23.57882)
		(stroke
			(width 0.7874)
			(type default)
		)
		(layer "In6.Cu")
	)
	(gr_line
		(start 412.873952 -31.68142)
		(end 414.143952 -31.68142)
		(stroke
			(width 0.7874)
			(type default)
		)
		(layer "In6.Cu")
	)
	(gr_line
		(start 413.260032 -18.5166)
		(end 414.530032 -18.5166)
		(stroke
			(width 0.7874)
			(type default)
		)
		(layer "In6.Cu")
	)
	(gr_line
		(start 415.259774 -30.56382)
		(end 416.529774 -30.56382)
		(stroke
			(width 0.7874)
			(type default)
		)
		(layer "In6.Cu")
	)
	(gr_line
		(start 418.662866 -24.67102)
		(end 418.662866 -23.40102)
		(stroke
			(width 0.7874)
			(type default)
		)
		(layer "In6.Cu")
	)
	(gr_arc
		(start 425.010072 -41.000172)
		(mid 425.156481 -41.353635)
		(end 425.509944 -41.500044)
		(stroke
			(width 1.016)
			(type default)
		)
		(layer "In6.Cu")
	)
	(gr_line
		(start 425.010072 -31.999936)
		(end 425.010072 -41.000172)
		(stroke
			(width 1.016)
			(type default)
		)
		(layer "In6.Cu")
	)
	(gr_line
		(start 425.509944 -41.500044)
		(end 427.110144 -41.500044)
		(stroke
			(width 1.016)
			(type default)
		)
		(layer "In6.Cu")
	)
	(gr_arc
		(start 425.509944 -31.500064)
		(mid 425.156481 -31.646473)
		(end 425.010072 -31.999936)
		(stroke
			(width 1.016)
			(type default)
		)
		(layer "In6.Cu")
	)
	(gr_line
		(start 425.61002 -50.390044)
		(end 381.990092 -50.390044)
		(stroke
			(width 1.016)
			(type default)
		)
		(layer "In6.Cu")
	)
	(gr_arc
		(start 425.61002 -50.390044)
		(mid 427.024235 -49.804255)
		(end 427.610016 -48.390048)
		(stroke
			(width 1.016)
			(type default)
		)
		(layer "In6.Cu")
	)
	(gr_line
		(start 427.10989 -31.500064)
		(end 425.509944 -31.500064)
		(stroke
			(width 1.016)
			(type default)
		)
		(layer "In6.Cu")
	)
	(gr_arc
		(start 427.10989 -31.500064)
		(mid 427.463552 -31.353586)
		(end 427.610016 -30.999938)
		(stroke
			(width 1.016)
			(type default)
		)
		(layer "In6.Cu")
	)
	(gr_arc
		(start 427.610016 -41.999916)
		(mid 427.463615 -41.646427)
		(end 427.110144 -41.500044)
		(stroke
			(width 1.016)
			(type default)
		)
		(layer "In6.Cu")
	)
	(gr_line
		(start 427.610016 -41.999916)
		(end 427.610016 -48.390048)
		(stroke
			(width 1.016)
			(type default)
		)
		(layer "In6.Cu")
	)
	(gr_line
		(start 427.610016 -10.999978)
		(end 427.610016 -30.999938)
		(stroke
			(width 1.016)
			(type default)
		)
		(layer "In6.Cu")
	)
	(gr_arc
		(start 428.109888 -10.500106)
		(mid 427.756425 -10.646515)
		(end 427.610016 -10.999978)
		(stroke
			(width 1.016)
			(type default)
		)
		(layer "In6.Cu")
	)
	(gr_line
		(start 428.309786 -10.500106)
		(end 428.109888 -10.500106)
		(stroke
			(width 1.016)
			(type default)
		)
		(layer "In6.Cu")
	)
	(gr_arc
		(start 428.309786 -10.500106)
		(mid 428.66343 -10.353626)
		(end 428.809912 -9.99998)
		(stroke
			(width 1.016)
			(type default)
		)
		(layer "In6.Cu")
	)
	(gr_arc
		(start 428.809912 -1.999996)
		(mid 428.224126 -0.585782)
		(end 426.809916 0)
		(stroke
			(width 1.016)
			(type default)
		)
		(layer "In6.Cu")
	)
	(gr_line
		(start 428.809912 -1.999996)
		(end 428.809912 -9.99998)
		(stroke
			(width 1.016)
			(type default)
		)
		(layer "In6.Cu")
	)
	(gr_line
		(start 0 -51.799998)
		(end 0 -1.999996)
		(stroke
			(width 0.05)
			(type default)
		)
		(layer "Edge.Cuts")
	)
	(gr_line
		(start 0.999998 -52.799996)
		(end 0 -51.799998)
		(stroke
			(width 0.05)
			(type default)
		)
		(layer "Edge.Cuts")
	)
	(gr_line
		(start 1.500124 -53.299868)
		(end 0.999998 -52.799996)
		(stroke
			(width 0.05)
			(type default)
		)
		(layer "Edge.Cuts")
	)
	(gr_arc
		(start 1.999996 0)
		(mid 0.585785 -0.585785)
		(end 0 -1.999996)
		(stroke
			(width 0.05)
			(type default)
		)
		(layer "Edge.Cuts")
	)
	(gr_line
		(start 1.999996 0)
		(end 426.809916 0)
		(stroke
			(width 0.05)
			(type default)
		)
		(layer "Edge.Cuts")
	)
	(gr_arc
		(start 2.649982 -32.638238)
		(mid 4.500218 -38.000029)
		(end 6.35 -32.638238)
		(stroke
			(width 0.05)
			(type default)
		)
		(layer "Edge.Cuts")
	)
	(gr_line
		(start 2.649982 -28.999942)
		(end 2.649982 -32.638238)
		(stroke
			(width 0.05)
			(type default)
		)
		(layer "Edge.Cuts")
	)
	(gr_line
		(start 6.35 -32.638238)
		(end 6.35 -28.999942)
		(stroke
			(width 0.05)
			(type default)
		)
		(layer "Edge.Cuts")
	)
	(gr_arc
		(start 6.35 -28.999942)
		(mid 4.500118 -27.15006)
		(end 2.649982 -28.999942)
		(stroke
			(width 0.05)
			(type default)
		)
		(layer "Edge.Cuts")
	)
	(gr_line
		(start 8.949944 -53.299868)
		(end 1.500124 -53.299868)
		(stroke
			(width 0.05)
			(type default)
		)
		(layer "Edge.Cuts")
	)
	(gr_line
		(start 9.45007 -52.799996)
		(end 8.949944 -53.299868)
		(stroke
			(width 0.05)
			(type default)
		)
		(layer "Edge.Cuts")
	)
	(gr_line
		(start 10.450068 -51.799998)
		(end 9.45007 -52.799996)
		(stroke
			(width 0.05)
			(type default)
		)
		(layer "Edge.Cuts")
	)
	(gr_line
		(start 10.450068 -42.649902)
		(end 10.450068 -51.799998)
		(stroke
			(width 0.05)
			(type default)
		)
		(layer "Edge.Cuts")
	)
	(gr_line
		(start 11.150092 -51.799998)
		(end 11.150092 -42.649902)
		(stroke
			(width 0.05)
			(type default)
		)
		(layer "Edge.Cuts")
	)
	(gr_arc
		(start 11.150092 -42.649902)
		(mid 10.80008 -42.29989)
		(end 10.450068 -42.649902)
		(stroke
			(width 0.05)
			(type default)
		)
		(layer "Edge.Cuts")
	)
	(gr_line
		(start 12.649962 -53.299868)
		(end 11.150092 -51.799998)
		(stroke
			(width 0.05)
			(type default)
		)
		(layer "Edge.Cuts")
	)
	(gr_line
		(start 50.580036 -53.299868)
		(end 12.649962 -53.299868)
		(stroke
			(width 0.05)
			(type default)
		)
		(layer "Edge.Cuts")
	)
	(gr_line
		(start 52.079906 -51.799998)
		(end 50.580036 -53.299868)
		(stroke
			(width 0.05)
			(type default)
		)
		(layer "Edge.Cuts")
	)
	(gr_line
		(start 52.079906 -43.319954)
		(end 52.079906 -51.799998)
		(stroke
			(width 0.05)
			(type default)
		)
		(layer "Edge.Cuts")
	)
	(gr_arc
		(start 53.079904 -42.319956)
		(mid 52.372799 -42.612849)
		(end 52.079906 -43.319954)
		(stroke
			(width 0.05)
			(type default)
		)
		(layer "Edge.Cuts")
	)
	(gr_line
		(start 55.0799 -42.319956)
		(end 53.079904 -42.319956)
		(stroke
			(width 0.05)
			(type default)
		)
		(layer "Edge.Cuts")
	)
	(gr_line
		(start 56.079898 -50.31994)
		(end 56.079898 -43.319954)
		(stroke
			(width 0.05)
			(type default)
		)
		(layer "Edge.Cuts")
	)
	(gr_arc
		(start 56.079898 -50.31994)
		(mid 56.665697 -51.734127)
		(end 58.079894 -52.319936)
		(stroke
			(width 0.05)
			(type default)
		)
		(layer "Edge.Cuts")
	)
	(gr_arc
		(start 56.079898 -43.319954)
		(mid 55.787005 -42.612849)
		(end 55.0799 -42.319956)
		(stroke
			(width 0.05)
			(type default)
		)
		(layer "Edge.Cuts")
	)
	(gr_arc
		(start 77.959966 -45.13834)
		(mid 79.810202 -50.500131)
		(end 81.659984 -45.13834)
		(stroke
			(width 0.05)
			(type default)
		)
		(layer "Edge.Cuts")
	)
	(gr_line
		(start 77.959966 -41.500044)
		(end 77.959966 -45.13834)
		(stroke
			(width 0.05)
			(type default)
		)
		(layer "Edge.Cuts")
	)
	(gr_line
		(start 81.659984 -45.13834)
		(end 81.659984 -41.500044)
		(stroke
			(width 0.05)
			(type default)
		)
		(layer "Edge.Cuts")
	)
	(gr_arc
		(start 81.659984 -41.500044)
		(mid 79.810102 -39.650162)
		(end 77.959966 -41.500044)
		(stroke
			(width 0.05)
			(type default)
		)
		(layer "Edge.Cuts")
	)
	(gr_line
		(start 95.069914 -52.319936)
		(end 58.079894 -52.319936)
		(stroke
			(width 0.05)
			(type default)
		)
		(layer "Edge.Cuts")
	)
	(gr_arc
		(start 95.069914 -52.319936)
		(mid 95.777024 -52.027041)
		(end 96.069912 -51.319938)
		(stroke
			(width 0.05)
			(type default)
		)
		(layer "Edge.Cuts")
	)
	(gr_line
		(start 96.069912 -50.8)
		(end 96.069912 -51.319938)
		(stroke
			(width 0.05)
			(type default)
		)
		(layer "Edge.Cuts")
	)
	(gr_arc
		(start 97.06991 -49.800002)
		(mid 96.362805 -50.092895)
		(end 96.069912 -50.8)
		(stroke
			(width 0.05)
			(type default)
		)
		(layer "Edge.Cuts")
	)
	(gr_line
		(start 112.06988 -49.800002)
		(end 97.06991 -49.800002)
		(stroke
			(width 0.05)
			(type default)
		)
		(layer "Edge.Cuts")
	)
	(gr_line
		(start 113.069878 -51.319938)
		(end 113.069878 -50.8)
		(stroke
			(width 0.05)
			(type default)
		)
		(layer "Edge.Cuts")
	)
	(gr_arc
		(start 113.069878 -51.319938)
		(mid 113.362783 -52.027027)
		(end 114.069876 -52.319936)
		(stroke
			(width 0.05)
			(type default)
		)
		(layer "Edge.Cuts")
	)
	(gr_arc
		(start 113.069878 -50.8)
		(mid 112.776985 -50.092895)
		(end 112.06988 -49.800002)
		(stroke
			(width 0.05)
			(type default)
		)
		(layer "Edge.Cuts")
	)
	(gr_line
		(start 132.990082 -52.319936)
		(end 114.069876 -52.319936)
		(stroke
			(width 0.05)
			(type default)
		)
		(layer "Edge.Cuts")
	)
	(gr_arc
		(start 132.990082 -52.319936)
		(mid 133.697212 -52.027052)
		(end 133.99008 -51.319938)
		(stroke
			(width 0.05)
			(type default)
		)
		(layer "Edge.Cuts")
	)
	(gr_line
		(start 133.99008 -50.8)
		(end 133.99008 -51.319938)
		(stroke
			(width 0.05)
			(type default)
		)
		(layer "Edge.Cuts")
	)
	(gr_arc
		(start 134.990078 -49.800002)
		(mid 134.282973 -50.092895)
		(end 133.99008 -50.8)
		(stroke
			(width 0.05)
			(type default)
		)
		(layer "Edge.Cuts")
	)
	(gr_line
		(start 149.990048 -49.800002)
		(end 134.990078 -49.800002)
		(stroke
			(width 0.05)
			(type default)
		)
		(layer "Edge.Cuts")
	)
	(gr_line
		(start 150.990046 -51.319938)
		(end 150.990046 -50.8)
		(stroke
			(width 0.05)
			(type default)
		)
		(layer "Edge.Cuts")
	)
	(gr_arc
		(start 150.990046 -51.319938)
		(mid 151.282955 -52.027003)
		(end 151.990044 -52.319936)
		(stroke
			(width 0.05)
			(type default)
		)
		(layer "Edge.Cuts")
	)
	(gr_arc
		(start 150.990046 -50.8)
		(mid 150.697153 -50.092895)
		(end 149.990048 -49.800002)
		(stroke
			(width 0.05)
			(type default)
		)
		(layer "Edge.Cuts")
	)
	(gr_line
		(start 158.99003 -52.319936)
		(end 151.990044 -52.319936)
		(stroke
			(width 0.05)
			(type default)
		)
		(layer "Edge.Cuts")
	)
	(gr_line
		(start 159.372554 -52.24399)
		(end 158.99003 -52.319936)
		(stroke
			(width 0.05)
			(type default)
		)
		(layer "Edge.Cuts")
	)
	(gr_line
		(start 159.697166 -52.027074)
		(end 159.372554 -52.24399)
		(stroke
			(width 0.05)
			(type default)
		)
		(layer "Edge.Cuts")
	)
	(gr_line
		(start 159.913828 -51.702716)
		(end 159.697166 -52.027074)
		(stroke
			(width 0.05)
			(type default)
		)
		(layer "Edge.Cuts")
	)
	(gr_line
		(start 159.982154 -51.376072)
		(end 159.913828 -51.702716)
		(stroke
			(width 0.05)
			(type default)
		)
		(layer "Edge.Cuts")
	)
	(gr_line
		(start 160.0708 -50.996088)
		(end 159.982154 -51.376072)
		(stroke
			(width 0.05)
			(type default)
		)
		(layer "Edge.Cuts")
	)
	(gr_line
		(start 160.288732 -50.677064)
		(end 160.0708 -50.996088)
		(stroke
			(width 0.05)
			(type default)
		)
		(layer "Edge.Cuts")
	)
	(gr_line
		(start 160.611058 -50.464466)
		(end 160.288732 -50.677064)
		(stroke
			(width 0.05)
			(type default)
		)
		(layer "Edge.Cuts")
	)
	(gr_line
		(start 160.990026 -50.390044)
		(end 160.611058 -50.464466)
		(stroke
			(width 0.05)
			(type default)
		)
		(layer "Edge.Cuts")
	)
	(gr_arc
		(start 197.300088 -8.263382)
		(mid 199.050251 -13.699977)
		(end 200.799954 -8.263382)
		(stroke
			(width 0.05)
			(type default)
		)
		(layer "Edge.Cuts")
	)
	(gr_line
		(start 197.300088 -4.700016)
		(end 197.300088 -8.263382)
		(stroke
			(width 0.05)
			(type default)
		)
		(layer "Edge.Cuts")
	)
	(gr_line
		(start 200.799954 -8.263382)
		(end 200.799954 -4.700016)
		(stroke
			(width 0.05)
			(type default)
		)
		(layer "Edge.Cuts")
	)
	(gr_arc
		(start 200.799954 -4.700016)
		(mid 199.050148 -2.95021)
		(end 197.300088 -4.700016)
		(stroke
			(width 0.05)
			(type default)
		)
		(layer "Edge.Cuts")
	)
	(gr_line
		(start 202.989942 -50.390044)
		(end 160.990026 -50.390044)
		(stroke
			(width 0.05)
			(type default)
		)
		(layer "Edge.Cuts")
	)
	(gr_line
		(start 203.36891 -50.464466)
		(end 202.989942 -50.390044)
		(stroke
			(width 0.05)
			(type default)
		)
		(layer "Edge.Cuts")
	)
	(gr_line
		(start 203.691236 -50.677064)
		(end 203.36891 -50.464466)
		(stroke
			(width 0.05)
			(type default)
		)
		(layer "Edge.Cuts")
	)
	(gr_line
		(start 203.909168 -50.996088)
		(end 203.691236 -50.677064)
		(stroke
			(width 0.05)
			(type default)
		)
		(layer "Edge.Cuts")
	)
	(gr_line
		(start 203.997814 -51.376072)
		(end 203.909168 -50.996088)
		(stroke
			(width 0.05)
			(type default)
		)
		(layer "Edge.Cuts")
	)
	(gr_line
		(start 204.06614 -51.702716)
		(end 203.997814 -51.376072)
		(stroke
			(width 0.05)
			(type default)
		)
		(layer "Edge.Cuts")
	)
	(gr_line
		(start 204.282802 -52.027074)
		(end 204.06614 -51.702716)
		(stroke
			(width 0.05)
			(type default)
		)
		(layer "Edge.Cuts")
	)
	(gr_line
		(start 204.607414 -52.24399)
		(end 204.282802 -52.027074)
		(stroke
			(width 0.05)
			(type default)
		)
		(layer "Edge.Cuts")
	)
	(gr_line
		(start 204.989938 -52.319936)
		(end 204.607414 -52.24399)
		(stroke
			(width 0.05)
			(type default)
		)
		(layer "Edge.Cuts")
	)
	(gr_arc
		(start 208.060036 -45.06341)
		(mid 209.810199 -50.500005)
		(end 211.559902 -45.06341)
		(stroke
			(width 0.05)
			(type default)
		)
		(layer "Edge.Cuts")
	)
	(gr_line
		(start 208.060036 -41.500044)
		(end 208.060036 -45.06341)
		(stroke
			(width 0.05)
			(type default)
		)
		(layer "Edge.Cuts")
	)
	(gr_line
		(start 211.559902 -45.06341)
		(end 211.559902 -41.500044)
		(stroke
			(width 0.05)
			(type default)
		)
		(layer "Edge.Cuts")
	)
	(gr_arc
		(start 211.559902 -41.500044)
		(mid 209.810096 -39.750238)
		(end 208.060036 -41.500044)
		(stroke
			(width 0.05)
			(type default)
		)
		(layer "Edge.Cuts")
	)
	(gr_arc
		(start 277.960074 -8.338312)
		(mid 279.81031 -13.700103)
		(end 281.660092 -8.338312)
		(stroke
			(width 0.05)
			(type default)
		)
		(layer "Edge.Cuts")
	)
	(gr_line
		(start 277.960074 -4.700016)
		(end 277.960074 -8.338312)
		(stroke
			(width 0.05)
			(type default)
		)
		(layer "Edge.Cuts")
	)
	(gr_line
		(start 281.660092 -8.338312)
		(end 281.660092 -4.700016)
		(stroke
			(width 0.05)
			(type default)
		)
		(layer "Edge.Cuts")
	)
	(gr_arc
		(start 281.660092 -4.700016)
		(mid 279.81021 -2.850134)
		(end 277.960074 -4.700016)
		(stroke
			(width 0.05)
			(type default)
		)
		(layer "Edge.Cuts")
	)
	(gr_arc
		(start 298.960032 -45.13834)
		(mid 300.810268 -50.500131)
		(end 302.66005 -45.13834)
		(stroke
			(width 0.05)
			(type default)
		)
		(layer "Edge.Cuts")
	)
	(gr_line
		(start 298.960032 -41.500044)
		(end 298.960032 -45.13834)
		(stroke
			(width 0.05)
			(type default)
		)
		(layer "Edge.Cuts")
	)
	(gr_line
		(start 302.66005 -45.13834)
		(end 302.66005 -41.500044)
		(stroke
			(width 0.05)
			(type default)
		)
		(layer "Edge.Cuts")
	)
	(gr_arc
		(start 302.66005 -41.500044)
		(mid 300.810168 -39.650162)
		(end 298.960032 -41.500044)
		(stroke
			(width 0.05)
			(type default)
		)
		(layer "Edge.Cuts")
	)
	(gr_line
		(start 316.06998 -52.319936)
		(end 204.989938 -52.319936)
		(stroke
			(width 0.05)
			(type default)
		)
		(layer "Edge.Cuts")
	)
	(gr_arc
		(start 316.06998 -52.319936)
		(mid 316.777112 -52.027053)
		(end 317.069978 -51.319938)
		(stroke
			(width 0.05)
			(type default)
		)
		(layer "Edge.Cuts")
	)
	(gr_line
		(start 317.069978 -50.8)
		(end 317.069978 -51.319938)
		(stroke
			(width 0.05)
			(type default)
		)
		(layer "Edge.Cuts")
	)
	(gr_arc
		(start 318.069976 -49.800002)
		(mid 317.362871 -50.092895)
		(end 317.069978 -50.8)
		(stroke
			(width 0.05)
			(type default)
		)
		(layer "Edge.Cuts")
	)
	(gr_line
		(start 333.069946 -49.800002)
		(end 318.069976 -49.800002)
		(stroke
			(width 0.05)
			(type default)
		)
		(layer "Edge.Cuts")
	)
	(gr_line
		(start 334.069944 -51.319938)
		(end 334.069944 -50.8)
		(stroke
			(width 0.05)
			(type default)
		)
		(layer "Edge.Cuts")
	)
	(gr_arc
		(start 334.069944 -51.319938)
		(mid 334.362853 -52.027004)
		(end 335.069942 -52.319936)
		(stroke
			(width 0.05)
			(type default)
		)
		(layer "Edge.Cuts")
	)
	(gr_arc
		(start 334.069944 -50.8)
		(mid 333.777051 -50.092895)
		(end 333.069946 -49.800002)
		(stroke
			(width 0.05)
			(type default)
		)
		(layer "Edge.Cuts")
	)
	(gr_line
		(start 353.989894 -52.319936)
		(end 335.069942 -52.319936)
		(stroke
			(width 0.05)
			(type default)
		)
		(layer "Edge.Cuts")
	)
	(gr_arc
		(start 353.989894 -52.319936)
		(mid 354.697017 -52.027048)
		(end 354.989892 -51.319938)
		(stroke
			(width 0.05)
			(type default)
		)
		(layer "Edge.Cuts")
	)
	(gr_line
		(start 354.989892 -50.8)
		(end 354.989892 -51.319938)
		(stroke
			(width 0.05)
			(type default)
		)
		(layer "Edge.Cuts")
	)
	(gr_arc
		(start 355.98989 -49.800002)
		(mid 355.282785 -50.092895)
		(end 354.989892 -50.8)
		(stroke
			(width 0.05)
			(type default)
		)
		(layer "Edge.Cuts")
	)
	(gr_line
		(start 370.990114 -49.800002)
		(end 355.98989 -49.800002)
		(stroke
			(width 0.05)
			(type default)
		)
		(layer "Edge.Cuts")
	)
	(gr_line
		(start 371.990112 -51.319938)
		(end 371.990112 -50.8)
		(stroke
			(width 0.05)
			(type default)
		)
		(layer "Edge.Cuts")
	)
	(gr_arc
		(start 371.990112 -51.319938)
		(mid 372.283019 -52.027015)
		(end 372.99011 -52.319936)
		(stroke
			(width 0.05)
			(type default)
		)
		(layer "Edge.Cuts")
	)
	(gr_arc
		(start 371.990112 -50.8)
		(mid 371.697219 -50.092895)
		(end 370.990114 -49.800002)
		(stroke
			(width 0.05)
			(type default)
		)
		(layer "Edge.Cuts")
	)
	(gr_line
		(start 379.990096 -52.319936)
		(end 372.99011 -52.319936)
		(stroke
			(width 0.05)
			(type default)
		)
		(layer "Edge.Cuts")
	)
	(gr_line
		(start 380.37262 -52.24399)
		(end 379.990096 -52.319936)
		(stroke
			(width 0.05)
			(type default)
		)
		(layer "Edge.Cuts")
	)
	(gr_line
		(start 380.697232 -52.027074)
		(end 380.37262 -52.24399)
		(stroke
			(width 0.05)
			(type default)
		)
		(layer "Edge.Cuts")
	)
	(gr_line
		(start 380.913894 -51.702716)
		(end 380.697232 -52.027074)
		(stroke
			(width 0.05)
			(type default)
		)
		(layer "Edge.Cuts")
	)
	(gr_line
		(start 380.98222 -51.376072)
		(end 380.913894 -51.702716)
		(stroke
			(width 0.05)
			(type default)
		)
		(layer "Edge.Cuts")
	)
	(gr_line
		(start 381.070866 -50.996088)
		(end 380.98222 -51.376072)
		(stroke
			(width 0.05)
			(type default)
		)
		(layer "Edge.Cuts")
	)
	(gr_line
		(start 381.288798 -50.677064)
		(end 381.070866 -50.996088)
		(stroke
			(width 0.05)
			(type default)
		)
		(layer "Edge.Cuts")
	)
	(gr_line
		(start 381.611124 -50.464466)
		(end 381.288798 -50.677064)
		(stroke
			(width 0.05)
			(type default)
		)
		(layer "Edge.Cuts")
	)
	(gr_line
		(start 381.990092 -50.390044)
		(end 381.611124 -50.464466)
		(stroke
			(width 0.05)
			(type default)
		)
		(layer "Edge.Cuts")
	)
	(gr_arc
		(start 425.010072 -40.999918)
		(mid 425.156391 -41.353545)
		(end 425.509944 -41.500044)
		(stroke
			(width 0.05)
			(type default)
		)
		(layer "Edge.Cuts")
	)
	(gr_line
		(start 425.010072 -31.999936)
		(end 425.010072 -40.999918)
		(stroke
			(width 0.05)
			(type default)
		)
		(layer "Edge.Cuts")
	)
	(gr_line
		(start 425.509944 -41.500044)
		(end 427.10989 -41.500044)
		(stroke
			(width 0.05)
			(type default)
		)
		(layer "Edge.Cuts")
	)
	(gr_arc
		(start 425.509944 -31.500064)
		(mid 425.156481 -31.646473)
		(end 425.010072 -31.999936)
		(stroke
			(width 0.05)
			(type default)
		)
		(layer "Edge.Cuts")
	)
	(gr_line
		(start 425.61002 -50.390044)
		(end 381.990092 -50.390044)
		(stroke
			(width 0.05)
			(type default)
		)
		(layer "Edge.Cuts")
	)
	(gr_arc
		(start 425.61002 -50.390044)
		(mid 427.024235 -49.804255)
		(end 427.610016 -48.390048)
		(stroke
			(width 0.05)
			(type default)
		)
		(layer "Edge.Cuts")
	)
	(gr_line
		(start 427.10989 -31.500064)
		(end 425.509944 -31.500064)
		(stroke
			(width 0.05)
			(type default)
		)
		(layer "Edge.Cuts")
	)
	(gr_arc
		(start 427.10989 -31.500064)
		(mid 427.463552 -31.353586)
		(end 427.610016 -30.999938)
		(stroke
			(width 0.05)
			(type default)
		)
		(layer "Edge.Cuts")
	)
	(gr_arc
		(start 427.610016 -41.999916)
		(mid 427.463525 -41.646337)
		(end 427.10989 -41.500044)
		(stroke
			(width 0.05)
			(type default)
		)
		(layer "Edge.Cuts")
	)
	(gr_line
		(start 427.610016 -41.999916)
		(end 427.610016 -48.390048)
		(stroke
			(width 0.05)
			(type default)
		)
		(layer "Edge.Cuts")
	)
	(gr_line
		(start 427.610016 -10.999978)
		(end 427.610016 -30.999938)
		(stroke
			(width 0.05)
			(type default)
		)
		(layer "Edge.Cuts")
	)
	(gr_arc
		(start 428.109888 -10.500106)
		(mid 427.756425 -10.646515)
		(end 427.610016 -10.999978)
		(stroke
			(width 0.05)
			(type default)
		)
		(layer "Edge.Cuts")
	)
	(gr_line
		(start 428.31004 -10.500106)
		(end 428.109888 -10.500106)
		(stroke
			(width 0.05)
			(type default)
		)
		(layer "Edge.Cuts")
	)
	(gr_arc
		(start 428.31004 -10.500106)
		(mid 428.66352 -10.353536)
		(end 428.809912 -9.99998)
		(stroke
			(width 0.05)
			(type default)
		)
		(layer "Edge.Cuts")
	)
	(gr_arc
		(start 428.809912 -1.999996)
		(mid 428.224126 -0.585782)
		(end 426.809916 0)
		(stroke
			(width 0.05)
			(type default)
		)
		(layer "Edge.Cuts")
	)
	(gr_line
		(start 428.809912 -1.999996)
		(end 428.809912 -9.99998)
		(stroke
			(width 0.05)
			(type default)
		)
		(layer "Edge.Cuts")
	)
	(segment
		(start 28.69438 -31.1658)
		(end 23.04796 -31.1658)
		(width 0.28956)
		(layer "F.Cu")
		(net "NODE1_EN")
	)
	(segment
		(start 11.658092 -39.96436)
		(end 10.3251 -39.96436)
		(width 0.28956)
		(layer "F.Cu")
		(net "NODE1_EN")
	)
	(segment
		(start 23.04796 -31.1658)
		(end 16.58874 -37.62502)
		(width 0.28956)
		(layer "F.Cu")
		(net "NODE1_EN")
	)
	(segment
		(start 13.997432 -37.62502)
		(end 11.658092 -39.96436)
		(width 0.28956)
		(layer "F.Cu")
		(net "NODE1_EN")
	)
	(segment
		(start 29.3116 -30.54858)
		(end 28.69438 -31.1658)
		(width 0.28956)
		(layer "F.Cu")
		(net "NODE1_EN")
	)
	(segment
		(start 6.030214 -44.259246)
		(end 6.030214 -49.30013)
		(width 0.28956)
		(layer "F.Cu")
		(net "NODE1_EN")
	)
	(segment
		(start 16.58874 -37.62502)
		(end 13.997432 -37.62502)
		(width 0.28956)
		(layer "F.Cu")
		(net "NODE1_EN")
	)
	(segment
		(start 10.3251 -39.96436)
		(end 6.030214 -44.259246)
		(width 0.28956)
		(layer "F.Cu")
		(net "NODE1_EN")
	)
	(via
		(at 29.3116 -30.54858)
		(size 0.508)
		(drill 0.254)
		(layers "F.Cu" "B.Cu")
		(net "NODE1_EN")
	)
	(segment
		(start 14.9352 -23.7236)
		(end 21.76018 -30.54858)
		(width 0.18288)
		(layer "In2.Cu")
		(net "NODE1_EN")
	)
	(segment
		(start 5.21462 -23.7236)
		(end 14.9352 -23.7236)
		(width 0.18288)
		(layer "In2.Cu")
		(net "NODE1_EN")
	)
	(segment
		(start 4.848352 -23.357332)
		(end 5.21462 -23.7236)
		(width 0.18288)
		(layer "In2.Cu")
		(net "NODE1_EN")
	)
	(segment
		(start 21.76018 -30.54858)
		(end 29.3116 -30.54858)
		(width 0.18288)
		(layer "In2.Cu")
		(net "NODE1_EN")
	)
	(segment
		(start 125.7554 -21.2344)
		(end 125.8316 -21.1582)
		(width 0.18288)
		(layer "In5.Cu")
		(net "NODE1_EN")
	)
	(segment
		(start 112.2934 -34.1122)
		(end 113.538 -35.3568)
		(width 0.18288)
		(layer "In5.Cu")
		(net "NODE1_EN")
	)
	(segment
		(start 124.3584 -31.0642)
		(end 123.2281 -29.9339)
		(width 0.18288)
		(layer "In5.Cu")
		(net "NODE1_EN")
	)
	(segment
		(start 125.8316 -12.498578)
		(end 126.5301 -11.800078)
		(width 0.18288)
		(layer "In5.Cu")
		(net "NODE1_EN")
	)
	(segment
		(start 110.794292 -34.1122)
		(end 112.2934 -34.1122)
		(width 0.18288)
		(layer "In5.Cu")
		(net "NODE1_EN")
	)
	(segment
		(start 117.6274 -35.3568)
		(end 118.364 -34.6202)
		(width 0.18288)
		(layer "In5.Cu")
		(net "NODE1_EN")
	)
	(segment
		(start 123.2281 -27.4447)
		(end 125.7554 -24.9174)
		(width 0.18288)
		(layer "In5.Cu")
		(net "NODE1_EN")
	)
	(segment
		(start 86.995508 -35.4584)
		(end 109.448092 -35.4584)
		(width 0.18288)
		(layer "In5.Cu")
		(net "NODE1_EN")
	)
	(segment
		(start 118.364 -34.6202)
		(end 122.174 -34.6202)
		(width 0.18288)
		(layer "In5.Cu")
		(net "NODE1_EN")
	)
	(segment
		(start 29.3116 -30.54858)
		(end 82.085688 -30.54858)
		(width 0.18288)
		(layer "In5.Cu")
		(net "NODE1_EN")
	)
	(segment
		(start 82.085688 -30.54858)
		(end 86.995508 -35.4584)
		(width 0.18288)
		(layer "In5.Cu")
		(net "NODE1_EN")
	)
	(segment
		(start 123.2281 -29.9339)
		(end 123.2281 -27.4447)
		(width 0.18288)
		(layer "In5.Cu")
		(net "NODE1_EN")
	)
	(segment
		(start 125.7554 -24.9174)
		(end 125.7554 -21.2344)
		(width 0.18288)
		(layer "In5.Cu")
		(net "NODE1_EN")
	)
	(segment
		(start 109.448092 -35.4584)
		(end 110.794292 -34.1122)
		(width 0.18288)
		(layer "In5.Cu")
		(net "NODE1_EN")
	)
	(segment
		(start 113.538 -35.3568)
		(end 117.6274 -35.3568)
		(width 0.18288)
		(layer "In5.Cu")
		(net "NODE1_EN")
	)
	(segment
		(start 122.174 -34.6202)
		(end 124.3584 -32.4358)
		(width 0.18288)
		(layer "In5.Cu")
		(net "NODE1_EN")
	)
	(segment
		(start 125.8316 -21.1582)
		(end 125.8316 -12.498578)
		(width 0.18288)
		(layer "In5.Cu")
		(net "NODE1_EN")
	)
	(segment
		(start 124.3584 -32.4358)
		(end 124.3584 -31.0642)
		(width 0.18288)
		(layer "In5.Cu")
		(net "NODE1_EN")
	)
	(segment
		(start 16.41602 -36.957)
		(end 13.6144 -36.957)
		(width 0.28956)
		(layer "F.Cu")
		(net "NODE2_EN")
	)
	(segment
		(start 22.80158 -30.57144)
		(end 16.41602 -36.957)
		(width 0.28956)
		(layer "F.Cu")
		(net "NODE2_EN")
	)
	(segment
		(start 8.9408 -39.37)
		(end 4.760214 -43.550586)
		(width 0.28956)
		(layer "F.Cu")
		(net "NODE2_EN")
	)
	(segment
		(start 33.655 -29.094176)
		(end 32.827976 -29.9212)
		(width 0.28956)
		(layer "F.Cu")
		(net "NODE2_EN")
	)
	(segment
		(start 13.6144 -36.957)
		(end 11.2014 -39.37)
		(width 0.28956)
		(layer "F.Cu")
		(net "NODE2_EN")
	)
	(segment
		(start 11.2014 -39.37)
		(end 8.9408 -39.37)
		(width 0.28956)
		(layer "F.Cu")
		(net "NODE2_EN")
	)
	(segment
		(start 4.760214 -43.550586)
		(end 4.760214 -49.30013)
		(width 0.28956)
		(layer "F.Cu")
		(net "NODE2_EN")
	)
	(segment
		(start 29.0068 -29.9212)
		(end 28.35656 -30.57144)
		(width 0.28956)
		(layer "F.Cu")
		(net "NODE2_EN")
	)
	(segment
		(start 33.655 -27.9654)
		(end 33.655 -29.094176)
		(width 0.28956)
		(layer "F.Cu")
		(net "NODE2_EN")
	)
	(segment
		(start 28.35656 -30.57144)
		(end 22.80158 -30.57144)
		(width 0.28956)
		(layer "F.Cu")
		(net "NODE2_EN")
	)
	(segment
		(start 32.827976 -29.9212)
		(end 29.0068 -29.9212)
		(width 0.28956)
		(layer "F.Cu")
		(net "NODE2_EN")
	)
	(via
		(at 33.655 -27.9654)
		(size 0.508)
		(drill 0.254)
		(layers "F.Cu" "B.Cu")
		(net "NODE2_EN")
	)
	(segment
		(start 30.299152 -26.405332)
		(end 32.094932 -26.405332)
		(width 0.18288)
		(layer "In2.Cu")
		(net "NODE2_EN")
	)
	(segment
		(start 32.094932 -26.405332)
		(end 33.655 -27.9654)
		(width 0.18288)
		(layer "In2.Cu")
		(net "NODE2_EN")
	)
	(segment
		(start 119.8372 -14.097)
		(end 119.8372 -11.193018)
		(width 0.18288)
		(layer "In5.Cu")
		(net "NODE2_EN")
	)
	(segment
		(start 83.1342 -27.9654)
		(end 87.7062 -32.5374)
		(width 0.18288)
		(layer "In5.Cu")
		(net "NODE2_EN")
	)
	(segment
		(start 119.8372 -11.193018)
		(end 120.530112 -10.500106)
		(width 0.18288)
		(layer "In5.Cu")
		(net "NODE2_EN")
	)
	(segment
		(start 108.919264 -32.5374)
		(end 119.1006 -22.356064)
		(width 0.18288)
		(layer "In5.Cu")
		(net "NODE2_EN")
	)
	(segment
		(start 119.1006 -22.356064)
		(end 119.1006 -14.8336)
		(width 0.18288)
		(layer "In5.Cu")
		(net "NODE2_EN")
	)
	(segment
		(start 87.7062 -32.5374)
		(end 108.919264 -32.5374)
		(width 0.18288)
		(layer "In5.Cu")
		(net "NODE2_EN")
	)
	(segment
		(start 33.655 -27.9654)
		(end 83.1342 -27.9654)
		(width 0.18288)
		(layer "In5.Cu")
		(net "NODE2_EN")
	)
	(segment
		(start 119.1006 -14.8336)
		(end 119.8372 -14.097)
		(width 0.18288)
		(layer "In5.Cu")
		(net "NODE2_EN")
	)
	(via
		(at 28.321 -32.9946)
		(size 0.508)
		(drill 0.254)
		(layers "F.Cu" "B.Cu")
		(net "NODE4_EN")
	)
	(segment
		(start 12.976606 -37.7444)
		(end 11.516614 -39.204392)
		(width 0.28956)
		(layer "B.Cu")
		(net "NODE4_EN")
	)
	(segment
		(start 18.288 -37.7444)
		(end 12.976606 -37.7444)
		(width 0.28956)
		(layer "B.Cu")
		(net "NODE4_EN")
	)
	(segment
		(start 8.547608 -39.204392)
		(end 4.760214 -42.991786)
		(width 0.28956)
		(layer "B.Cu")
		(net "NODE4_EN")
	)
	(segment
		(start 11.516614 -39.204392)
		(end 8.547608 -39.204392)
		(width 0.28956)
		(layer "B.Cu")
		(net "NODE4_EN")
	)
	(segment
		(start 23.0378 -32.9946)
		(end 18.288 -37.7444)
		(width 0.28956)
		(layer "B.Cu")
		(net "NODE4_EN")
	)
	(segment
		(start 4.760214 -42.991786)
		(end 4.760214 -49.30013)
		(width 0.28956)
		(layer "B.Cu")
		(net "NODE4_EN")
	)
	(segment
		(start 28.321 -32.9946)
		(end 23.0378 -32.9946)
		(width 0.28956)
		(layer "B.Cu")
		(net "NODE4_EN")
	)
	(segment
		(start 29.7688 -32.9946)
		(end 28.321 -32.9946)
		(width 0.18288)
		(layer "In2.Cu")
		(net "NODE4_EN")
	)
	(segment
		(start 29.2354 -24.548084)
		(end 29.2354 -27.1018)
		(width 0.18288)
		(layer "In2.Cu")
		(net "NODE4_EN")
	)
	(segment
		(start 30.299152 -23.484332)
		(end 29.2354 -24.548084)
		(width 0.18288)
		(layer "In2.Cu")
		(net "NODE4_EN")
	)
	(segment
		(start 29.2354 -27.1018)
		(end 31.3944 -29.2608)
		(width 0.18288)
		(layer "In2.Cu")
		(net "NODE4_EN")
	)
	(segment
		(start 31.3944 -31.369)
		(end 29.7688 -32.9946)
		(width 0.18288)
		(layer "In2.Cu")
		(net "NODE4_EN")
	)
	(segment
		(start 31.3944 -29.2608)
		(end 31.3944 -31.369)
		(width 0.18288)
		(layer "In2.Cu")
		(net "NODE4_EN")
	)
	(segment
		(start 159.44596 -35.8394)
		(end 160.3248 -36.71824)
		(width 0.18288)
		(layer "In5.Cu")
		(net "NODE4_EN")
	)
	(segment
		(start 336.8548 -25.2984)
		(end 336.8548 -24.2824)
		(width 0.18288)
		(layer "In5.Cu")
		(net "NODE4_EN")
	)
	(segment
		(start 155.40736 -36.71824)
		(end 156.2862 -35.8394)
		(width 0.18288)
		(layer "In5.Cu")
		(net "NODE4_EN")
	)
	(segment
		(start 28.321 -32.9946)
		(end 30.20822 -31.10738)
		(width 0.18288)
		(layer "In5.Cu")
		(net "NODE4_EN")
	)
	(segment
		(start 110.1598 -35.9664)
		(end 110.7694 -36.576)
		(width 0.18288)
		(layer "In5.Cu")
		(net "NODE4_EN")
	)
	(segment
		(start 117.094 -36.576)
		(end 120.27154 -39.75354)
		(width 0.18288)
		(layer "In5.Cu")
		(net "NODE4_EN")
	)
	(segment
		(start 201.83856 -36.71824)
		(end 205.06436 -33.49244)
		(width 0.18288)
		(layer "In5.Cu")
		(net "NODE4_EN")
	)
	(segment
		(start 339.2424 -15.691866)
		(end 340.837266 -14.097)
		(width 0.18288)
		(layer "In5.Cu")
		(net "NODE4_EN")
	)
	(segment
		(start 133.41096 -36.71824)
		(end 155.40736 -36.71824)
		(width 0.18288)
		(layer "In5.Cu")
		(net "NODE4_EN")
	)
	(segment
		(start 86.813644 -35.9664)
		(end 110.1598 -35.9664)
		(width 0.18288)
		(layer "In5.Cu")
		(net "NODE4_EN")
	)
	(segment
		(start 110.7694 -36.576)
		(end 117.094 -36.576)
		(width 0.18288)
		(layer "In5.Cu")
		(net "NODE4_EN")
	)
	(segment
		(start 30.20822 -31.10738)
		(end 81.954624 -31.10738)
		(width 0.18288)
		(layer "In5.Cu")
		(net "NODE4_EN")
	)
	(segment
		(start 336.8548 -24.2824)
		(end 339.2424 -21.8948)
		(width 0.18288)
		(layer "In5.Cu")
		(net "NODE4_EN")
	)
	(segment
		(start 340.837266 -11.193018)
		(end 341.530178 -10.500106)
		(width 0.18288)
		(layer "In5.Cu")
		(net "NODE4_EN")
	)
	(segment
		(start 81.954624 -31.10738)
		(end 86.813644 -35.9664)
		(width 0.18288)
		(layer "In5.Cu")
		(net "NODE4_EN")
	)
	(segment
		(start 340.837266 -14.097)
		(end 340.837266 -11.193018)
		(width 0.18288)
		(layer "In5.Cu")
		(net "NODE4_EN")
	)
	(segment
		(start 320.929 -29.54528)
		(end 332.60792 -29.54528)
		(width 0.18288)
		(layer "In5.Cu")
		(net "NODE4_EN")
	)
	(segment
		(start 120.27154 -39.75354)
		(end 130.37566 -39.75354)
		(width 0.18288)
		(layer "In5.Cu")
		(net "NODE4_EN")
	)
	(segment
		(start 316.98184 -33.49244)
		(end 320.929 -29.54528)
		(width 0.18288)
		(layer "In5.Cu")
		(net "NODE4_EN")
	)
	(segment
		(start 156.2862 -35.8394)
		(end 159.44596 -35.8394)
		(width 0.18288)
		(layer "In5.Cu")
		(net "NODE4_EN")
	)
	(segment
		(start 130.37566 -39.75354)
		(end 133.41096 -36.71824)
		(width 0.18288)
		(layer "In5.Cu")
		(net "NODE4_EN")
	)
	(segment
		(start 332.60792 -29.54528)
		(end 336.8548 -25.2984)
		(width 0.18288)
		(layer "In5.Cu")
		(net "NODE4_EN")
	)
	(segment
		(start 160.3248 -36.71824)
		(end 201.83856 -36.71824)
		(width 0.18288)
		(layer "In5.Cu")
		(net "NODE4_EN")
	)
	(segment
		(start 205.06436 -33.49244)
		(end 316.98184 -33.49244)
		(width 0.18288)
		(layer "In5.Cu")
		(net "NODE4_EN")
	)
	(segment
		(start 339.2424 -21.8948)
		(end 339.2424 -15.691866)
		(width 0.18288)
		(layer "In5.Cu")
		(net "NODE4_EN")
	)
	(via
		(at 30.4038 -33.6296)
		(size 0.508)
		(drill 0.254)
		(layers "F.Cu" "B.Cu")
		(net "NODE3_EN")
	)
	(segment
		(start 30.4038 -33.6296)
		(end 23.372826 -33.6296)
		(width 0.28956)
		(layer "B.Cu")
		(net "NODE3_EN")
	)
	(segment
		(start 6.030214 -43.220386)
		(end 6.030214 -49.30013)
		(width 0.28956)
		(layer "B.Cu")
		(net "NODE3_EN")
	)
	(segment
		(start 11.763248 -39.798752)
		(end 9.451848 -39.798752)
		(width 0.28956)
		(layer "B.Cu")
		(net "NODE3_EN")
	)
	(segment
		(start 23.372826 -33.6296)
		(end 18.572226 -38.4302)
		(width 0.28956)
		(layer "B.Cu")
		(net "NODE3_EN")
	)
	(segment
		(start 9.451848 -39.798752)
		(end 6.030214 -43.220386)
		(width 0.28956)
		(layer "B.Cu")
		(net "NODE3_EN")
	)
	(segment
		(start 18.572226 -38.4302)
		(end 13.1318 -38.4302)
		(width 0.28956)
		(layer "B.Cu")
		(net "NODE3_EN")
	)
	(segment
		(start 13.1318 -38.4302)
		(end 11.763248 -39.798752)
		(width 0.28956)
		(layer "B.Cu")
		(net "NODE3_EN")
	)
	(segment
		(start 3.7084 -23.876)
		(end 4.2926 -24.4602)
		(width 0.18288)
		(layer "In2.Cu")
		(net "NODE3_EN")
	)
	(segment
		(start 4.2926 -24.4602)
		(end 5.6896 -24.4602)
		(width 0.18288)
		(layer "In2.Cu")
		(net "NODE3_EN")
	)
	(segment
		(start 27.7876 -31.5722)
		(end 27.7876 -33.1978)
		(width 0.18288)
		(layer "In2.Cu")
		(net "NODE3_EN")
	)
	(segment
		(start 14.6558 -24.2316)
		(end 21.5392 -31.115)
		(width 0.18288)
		(layer "In2.Cu")
		(net "NODE3_EN")
	)
	(segment
		(start 3.7084 -21.500084)
		(end 3.7084 -23.876)
		(width 0.18288)
		(layer "In2.Cu")
		(net "NODE3_EN")
	)
	(segment
		(start 27.7876 -33.1978)
		(end 28.2194 -33.6296)
		(width 0.18288)
		(layer "In2.Cu")
		(net "NODE3_EN")
	)
	(segment
		(start 28.2194 -33.6296)
		(end 30.4038 -33.6296)
		(width 0.18288)
		(layer "In2.Cu")
		(net "NODE3_EN")
	)
	(segment
		(start 5.6896 -24.4602)
		(end 5.9182 -24.2316)
		(width 0.18288)
		(layer "In2.Cu")
		(net "NODE3_EN")
	)
	(segment
		(start 21.5392 -31.115)
		(end 27.3304 -31.115)
		(width 0.18288)
		(layer "In2.Cu")
		(net "NODE3_EN")
	)
	(segment
		(start 4.848352 -20.360132)
		(end 3.7084 -21.500084)
		(width 0.18288)
		(layer "In2.Cu")
		(net "NODE3_EN")
	)
	(segment
		(start 5.9182 -24.2316)
		(end 14.6558 -24.2316)
		(width 0.18288)
		(layer "In2.Cu")
		(net "NODE3_EN")
	)
	(segment
		(start 27.3304 -31.115)
		(end 27.7876 -31.5722)
		(width 0.18288)
		(layer "In2.Cu")
		(net "NODE3_EN")
	)
	(segment
		(start 338.6328 -34.1884)
		(end 343.656666 -34.1884)
		(width 0.18288)
		(layer "In5.Cu")
		(net "NODE3_EN")
	)
	(segment
		(start 344.228166 -28.466034)
		(end 345.694 -27.0002)
		(width 0.18288)
		(layer "In5.Cu")
		(net "NODE3_EN")
	)
	(segment
		(start 346.831666 -12.498578)
		(end 347.530166 -11.800078)
		(width 0.18288)
		(layer "In5.Cu")
		(net "NODE3_EN")
	)
	(segment
		(start 206.42072 -35.93084)
		(end 318.09436 -35.93084)
		(width 0.18288)
		(layer "In5.Cu")
		(net "NODE3_EN")
	)
	(segment
		(start 343.656666 -34.1884)
		(end 345.510866 -32.3342)
		(width 0.18288)
		(layer "In5.Cu")
		(net "NODE3_EN")
	)
	(segment
		(start 134.903972 -39.15664)
		(end 203.19492 -39.15664)
		(width 0.18288)
		(layer "In5.Cu")
		(net "NODE3_EN")
	)
	(segment
		(start 345.694 -27.0002)
		(end 345.694 -20.8026)
		(width 0.18288)
		(layer "In5.Cu")
		(net "NODE3_EN")
	)
	(segment
		(start 318.09436 -35.93084)
		(end 322.04152 -31.98368)
		(width 0.18288)
		(layer "In5.Cu")
		(net "NODE3_EN")
	)
	(segment
		(start 346.831666 -19.664934)
		(end 346.831666 -12.498578)
		(width 0.18288)
		(layer "In5.Cu")
		(net "NODE3_EN")
	)
	(segment
		(start 81.027524 -33.6296)
		(end 86.640924 -39.243)
		(width 0.18288)
		(layer "In5.Cu")
		(net "NODE3_EN")
	)
	(segment
		(start 86.640924 -39.243)
		(end 110.418372 -39.243)
		(width 0.18288)
		(layer "In5.Cu")
		(net "NODE3_EN")
	)
	(segment
		(start 131.6482 -42.412412)
		(end 134.903972 -39.15664)
		(width 0.18288)
		(layer "In5.Cu")
		(net "NODE3_EN")
	)
	(segment
		(start 322.04152 -31.98368)
		(end 331.77988 -31.98368)
		(width 0.18288)
		(layer "In5.Cu")
		(net "NODE3_EN")
	)
	(segment
		(start 331.77988 -31.98368)
		(end 335.2546 -35.4584)
		(width 0.18288)
		(layer "In5.Cu")
		(net "NODE3_EN")
	)
	(segment
		(start 30.4038 -33.6296)
		(end 81.027524 -33.6296)
		(width 0.18288)
		(layer "In5.Cu")
		(net "NODE3_EN")
	)
	(segment
		(start 335.2546 -35.4584)
		(end 337.3628 -35.4584)
		(width 0.18288)
		(layer "In5.Cu")
		(net "NODE3_EN")
	)
	(segment
		(start 344.228166 -29.9339)
		(end 344.228166 -28.466034)
		(width 0.18288)
		(layer "In5.Cu")
		(net "NODE3_EN")
	)
	(segment
		(start 345.510866 -31.2166)
		(end 344.228166 -29.9339)
		(width 0.18288)
		(layer "In5.Cu")
		(net "NODE3_EN")
	)
	(segment
		(start 345.510866 -32.3342)
		(end 345.510866 -31.2166)
		(width 0.18288)
		(layer "In5.Cu")
		(net "NODE3_EN")
	)
	(segment
		(start 113.587784 -42.412412)
		(end 131.6482 -42.412412)
		(width 0.18288)
		(layer "In5.Cu")
		(net "NODE3_EN")
	)
	(segment
		(start 345.694 -20.8026)
		(end 346.831666 -19.664934)
		(width 0.18288)
		(layer "In5.Cu")
		(net "NODE3_EN")
	)
	(segment
		(start 110.418372 -39.243)
		(end 113.587784 -42.412412)
		(width 0.18288)
		(layer "In5.Cu")
		(net "NODE3_EN")
	)
	(segment
		(start 337.3628 -35.4584)
		(end 338.6328 -34.1884)
		(width 0.18288)
		(layer "In5.Cu")
		(net "NODE3_EN")
	)
	(segment
		(start 203.19492 -39.15664)
		(end 206.42072 -35.93084)
		(width 0.18288)
		(layer "In5.Cu")
		(net "NODE3_EN")
	)
	(segment
		(start 27.167332 -17.399)
		(end 27.167332 -16.78305)
		(width 0.28956)
		(layer "F.Cu")
		(net "N39398095")
	)
	(segment
		(start 27.167332 -19.33575)
		(end 27.167332 -17.399)
		(width 0.28956)
		(layer "F.Cu")
		(net "N39398095")
	)
	(via
		(at 27.167332 -17.399)
		(size 0.508)
		(drill 0.254)
		(layers "F.Cu" "B.Cu")
		(net "N39398095")
	)
	(segment
		(start 4.019042 -18.649442)
		(end 7.588758 -18.649442)
		(width 0.28956)
		(layer "B.Cu")
		(net "N39398095")
	)
	(segment
		(start 7.588758 -18.649442)
		(end 11.0236 -15.2146)
		(width 0.28956)
		(layer "B.Cu")
		(net "N39398095")
	)
	(segment
		(start 11.0236 -15.2146)
		(end 24.982932 -15.2146)
		(width 0.28956)
		(layer "B.Cu")
		(net "N39398095")
	)
	(segment
		(start 24.982932 -15.2146)
		(end 27.167332 -17.399)
		(width 0.28956)
		(layer "B.Cu")
		(net "N39398095")
	)
	(segment
		(start 2.308352 -20.360132)
		(end 4.019042 -18.649442)
		(width 0.28956)
		(layer "B.Cu")
		(net "N39398095")
	)
	(segment
		(start 29.707332 -19.33575)
		(end 29.707332 -17.4244)
		(width 0.28956)
		(layer "F.Cu")
		(net "N39395053")
	)
	(segment
		(start 29.707332 -17.4244)
		(end 29.707332 -16.78305)
		(width 0.28956)
		(layer "F.Cu")
		(net "N39395053")
	)
	(via
		(at 29.707332 -17.4244)
		(size 0.508)
		(drill 0.254)
		(layers "F.Cu" "B.Cu")
		(net "N39395053")
	)
	(segment
		(start 29.2608 -20.8534)
		(end 29.2608 -20.7772)
		(width 0.18288)
		(layer "In2.Cu")
		(net "N39395053")
	)
	(segment
		(start 29.2608 -20.7772)
		(end 29.707332 -20.330668)
		(width 0.18288)
		(layer "In2.Cu")
		(net "N39395053")
	)
	(segment
		(start 29.707332 -20.330668)
		(end 29.707332 -17.4244)
		(width 0.18288)
		(layer "In2.Cu")
		(net "N39395053")
	)
	(segment
		(start 27.759152 -22.355048)
		(end 29.2608 -20.8534)
		(width 0.18288)
		(layer "In2.Cu")
		(net "N39395053")
	)
	(segment
		(start 27.759152 -23.484332)
		(end 27.759152 -22.355048)
		(width 0.18288)
		(layer "In2.Cu")
		(net "N39395053")
	)
	(segment
		(start 30.977332 -18.0086)
		(end 30.977332 -16.78305)
		(width 0.28956)
		(layer "F.Cu")
		(net "N39391900")
	)
	(segment
		(start 30.977332 -19.33575)
		(end 30.977332 -18.0086)
		(width 0.28956)
		(layer "F.Cu")
		(net "N39391900")
	)
	(via
		(at 30.977332 -18.0086)
		(size 0.508)
		(drill 0.254)
		(layers "F.Cu" "B.Cu")
		(net "N39391900")
	)
	(segment
		(start 27.165046 -19.113754)
		(end 28.2448 -18.034)
		(width 0.28956)
		(layer "B.Cu")
		(net "N39391900")
	)
	(segment
		(start 28.2448 -18.034)
		(end 30.951932 -18.034)
		(width 0.28956)
		(layer "B.Cu")
		(net "N39391900")
	)
	(segment
		(start 24.980646 -19.113754)
		(end 27.165046 -19.113754)
		(width 0.28956)
		(layer "B.Cu")
		(net "N39391900")
	)
	(segment
		(start 19.5072 -20.7264)
		(end 19.7358 -20.4978)
		(width 0.28956)
		(layer "B.Cu")
		(net "N39391900")
	)
	(segment
		(start 2.308352 -23.357332)
		(end 3.643884 -22.0218)
		(width 0.28956)
		(layer "B.Cu")
		(net "N39391900")
	)
	(segment
		(start 30.951932 -18.034)
		(end 30.977332 -18.0086)
		(width 0.28956)
		(layer "B.Cu")
		(net "N39391900")
	)
	(segment
		(start 8.1534 -20.7264)
		(end 19.5072 -20.7264)
		(width 0.28956)
		(layer "B.Cu")
		(net "N39391900")
	)
	(segment
		(start 6.858 -22.0218)
		(end 8.1534 -20.7264)
		(width 0.28956)
		(layer "B.Cu")
		(net "N39391900")
	)
	(segment
		(start 3.643884 -22.0218)
		(end 6.858 -22.0218)
		(width 0.28956)
		(layer "B.Cu")
		(net "N39391900")
	)
	(segment
		(start 23.5966 -20.4978)
		(end 24.980646 -19.113754)
		(width 0.28956)
		(layer "B.Cu")
		(net "N39391900")
	)
	(segment
		(start 19.7358 -20.4978)
		(end 23.5966 -20.4978)
		(width 0.28956)
		(layer "B.Cu")
		(net "N39391900")
	)
	(segment
		(start 28.437332 -19.33575)
		(end 28.437332 -18.6944)
		(width 0.28956)
		(layer "F.Cu")
		(net "N39386877")
	)
	(segment
		(start 28.437332 -18.6944)
		(end 28.437332 -16.78305)
		(width 0.28956)
		(layer "F.Cu")
		(net "N39386877")
	)
	(via
		(at 28.437332 -18.6944)
		(size 0.508)
		(drill 0.254)
		(layers "F.Cu" "B.Cu")
		(net "N39386877")
	)
	(segment
		(start 27.686 -21.717)
		(end 26.6446 -22.7584)
		(width 0.18288)
		(layer "In2.Cu")
		(net "N39386877")
	)
	(segment
		(start 27.759152 -25.523952)
		(end 27.759152 -26.405332)
		(width 0.18288)
		(layer "In2.Cu")
		(net "N39386877")
	)
	(segment
		(start 27.686 -19.445732)
		(end 27.686 -21.717)
		(width 0.18288)
		(layer "In2.Cu")
		(net "N39386877")
	)
	(segment
		(start 26.6446 -22.7584)
		(end 26.6446 -24.4094)
		(width 0.18288)
		(layer "In2.Cu")
		(net "N39386877")
	)
	(segment
		(start 28.437332 -18.6944)
		(end 27.686 -19.445732)
		(width 0.18288)
		(layer "In2.Cu")
		(net "N39386877")
	)
	(segment
		(start 26.6446 -24.4094)
		(end 27.759152 -25.523952)
		(width 0.18288)
		(layer "In2.Cu")
		(net "N39386877")
	)
	(via
		(at 17.3736 -35.8648)
		(size 0.6604)
		(drill 0.3302)
		(layers "F.Cu" "B.Cu")
		(net "10")
	)
	(segment
		(start 17.3736 -35.8648)
		(end 12.674854 -35.8648)
		(width 0.28956)
		(layer "B.Cu")
		(net "10")
	)
	(segment
		(start 12.674854 -35.8648)
		(end 11.310112 -34.500058)
		(width 0.28956)
		(layer "B.Cu")
		(net "10")
	)
	(segment
		(start 402.8694 -15.367)
		(end 402.3741 -15.8623)
		(width 0.28956)
		(layer "F.Cu")
		(net "AIRMAX_RSVD5")
	)
	(segment
		(start 389.87476 -15.09776)
		(end 389.001 -14.224)
		(width 0.28956)
		(layer "F.Cu")
		(net "AIRMAX_RSVD5")
	)
	(segment
		(start 389.001 -4.289044)
		(end 389.89 -3.400044)
		(width 0.28956)
		(layer "F.Cu")
		(net "AIRMAX_RSVD5")
	)
	(segment
		(start 389.001 -14.224)
		(end 389.001 -4.289044)
		(width 0.28956)
		(layer "F.Cu")
		(net "AIRMAX_RSVD5")
	)
	(segment
		(start 392.681714 -15.09776)
		(end 389.87476 -15.09776)
		(width 0.28956)
		(layer "F.Cu")
		(net "AIRMAX_RSVD5")
	)
	(segment
		(start 393.446254 -15.8623)
		(end 392.681714 -15.09776)
		(width 0.28956)
		(layer "F.Cu")
		(net "AIRMAX_RSVD5")
	)
	(segment
		(start 402.3741 -15.8623)
		(end 393.446254 -15.8623)
		(width 0.28956)
		(layer "F.Cu")
		(net "AIRMAX_RSVD5")
	)
	(via
		(at 402.8694 -15.367)
		(size 0.762)
		(drill 0.381)
		(layers "F.Cu" "B.Cu")
		(net "AIRMAX_RSVD5")
	)
	(segment
		(start 393.939268 -14.67358)
		(end 398.27962 -14.67358)
		(width 0.28956)
		(layer "F.Cu")
		(net "AIRMAX_RSVD7")
	)
	(segment
		(start 398.27962 -14.67358)
		(end 399.3642 -13.589)
		(width 0.28956)
		(layer "F.Cu")
		(net "AIRMAX_RSVD7")
	)
	(segment
		(start 391.889996 -2.100072)
		(end 392.9634 -3.173476)
		(width 0.28956)
		(layer "F.Cu")
		(net "AIRMAX_RSVD7")
	)
	(segment
		(start 392.9634 -3.173476)
		(end 392.9634 -13.697712)
		(width 0.28956)
		(layer "F.Cu")
		(net "AIRMAX_RSVD7")
	)
	(segment
		(start 392.9634 -13.697712)
		(end 393.939268 -14.67358)
		(width 0.28956)
		(layer "F.Cu")
		(net "AIRMAX_RSVD7")
	)
	(via
		(at 399.3642 -13.589)
		(size 0.762)
		(drill 0.381)
		(layers "F.Cu" "B.Cu")
		(net "AIRMAX_RSVD7")
	)
	(via
		(at 398.9832 -4.8006)
		(size 0.508)
		(drill 0.254)
		(layers "F.Cu" "B.Cu")
		(net "AIRMAX_RSVD6")
	)
	(segment
		(start 398.9832 -4.8006)
		(end 398.1958 -5.588)
		(width 0.18288)
		(layer "In2.Cu")
		(net "AIRMAX_RSVD6")
	)
	(segment
		(start 395.19606 -5.48386)
		(end 393.21994 -5.48386)
		(width 0.18288)
		(layer "In2.Cu")
		(net "AIRMAX_RSVD6")
	)
	(segment
		(start 393.21994 -5.48386)
		(end 393.0904 -5.6134)
		(width 0.18288)
		(layer "In2.Cu")
		(net "AIRMAX_RSVD6")
	)
	(segment
		(start 390.448292 -4.800092)
		(end 389.89 -4.800092)
		(width 0.18288)
		(layer "In2.Cu")
		(net "AIRMAX_RSVD6")
	)
	(segment
		(start 391.2616 -5.6134)
		(end 390.448292 -4.800092)
		(width 0.18288)
		(layer "In2.Cu")
		(net "AIRMAX_RSVD6")
	)
	(segment
		(start 395.3002 -5.588)
		(end 395.19606 -5.48386)
		(width 0.18288)
		(layer "In2.Cu")
		(net "AIRMAX_RSVD6")
	)
	(segment
		(start 398.1958 -5.588)
		(end 395.3002 -5.588)
		(width 0.18288)
		(layer "In2.Cu")
		(net "AIRMAX_RSVD6")
	)
	(segment
		(start 393.0904 -5.6134)
		(end 391.2616 -5.6134)
		(width 0.18288)
		(layer "In2.Cu")
		(net "AIRMAX_RSVD6")
	)
	(segment
		(start 400.58086 -15.26794)
		(end 393.692634 -15.26794)
		(width 0.28956)
		(layer "F.Cu")
		(net "AIRMAX_RSVD8")
	)
	(segment
		(start 392.928094 -14.5034)
		(end 391.9982 -14.5034)
		(width 0.28956)
		(layer "F.Cu")
		(net "AIRMAX_RSVD8")
	)
	(segment
		(start 391.0076 -13.5128)
		(end 391.0076 -4.382516)
		(width 0.28956)
		(layer "F.Cu")
		(net "AIRMAX_RSVD8")
	)
	(segment
		(start 391.9982 -14.5034)
		(end 391.0076 -13.5128)
		(width 0.28956)
		(layer "F.Cu")
		(net "AIRMAX_RSVD8")
	)
	(segment
		(start 391.0076 -4.382516)
		(end 391.889996 -3.50012)
		(width 0.28956)
		(layer "F.Cu")
		(net "AIRMAX_RSVD8")
	)
	(segment
		(start 393.692634 -15.26794)
		(end 392.928094 -14.5034)
		(width 0.28956)
		(layer "F.Cu")
		(net "AIRMAX_RSVD8")
	)
	(segment
		(start 401.1422 -14.7066)
		(end 400.58086 -15.26794)
		(width 0.28956)
		(layer "F.Cu")
		(net "AIRMAX_RSVD8")
	)
	(via
		(at 401.1422 -14.7066)
		(size 0.762)
		(drill 0.381)
		(layers "F.Cu" "B.Cu")
		(net "AIRMAX_RSVD8")
	)
	(segment
		(start 340.661498 -21.147532)
		(end 340.661498 -19.9136)
		(width 0.28956)
		(layer "F.Cu")
		(net "SFP4_PRESENT_N")
	)
	(segment
		(start 340.661498 -19.9136)
		(end 340.661498 -12.768834)
		(width 0.28956)
		(layer "F.Cu")
		(net "SFP4_PRESENT_N")
	)
	(segment
		(start 341.353902 -21.390102)
		(end 341.771732 -21.390102)
		(width 0.28956)
		(layer "F.Cu")
		(net "SFP4_PRESENT_N")
	)
	(segment
		(start 340.661498 -22.239732)
		(end 340.661498 -21.147532)
		(width 0.28956)
		(layer "F.Cu")
		(net "SFP4_PRESENT_N")
	)
	(segment
		(start 341.111332 -21.147532)
		(end 341.353902 -21.390102)
		(width 0.28956)
		(layer "F.Cu")
		(net "SFP4_PRESENT_N")
	)
	(segment
		(start 340.661498 -12.768834)
		(end 341.530178 -11.900154)
		(width 0.28956)
		(layer "F.Cu")
		(net "SFP4_PRESENT_N")
	)
	(segment
		(start 340.661498 -21.147532)
		(end 341.111332 -21.147532)
		(width 0.28956)
		(layer "F.Cu")
		(net "SFP4_PRESENT_N")
	)
	(via
		(at 340.661498 -19.9136)
		(size 0.762)
		(drill 0.381)
		(layers "F.Cu" "B.Cu")
		(net "SFP4_PRESENT_N")
	)
	(segment
		(start 349.594932 -15.264892)
		(end 349.594932 -19.9898)
		(width 0.28956)
		(layer "F.Cu")
		(net "SFP3_PRESENT_N")
	)
	(segment
		(start 349.594932 -19.9898)
		(end 349.594932 -21.161502)
		(width 0.28956)
		(layer "F.Cu")
		(net "SFP3_PRESENT_N")
	)
	(segment
		(start 350.1898 -21.161502)
		(end 349.594932 -21.161502)
		(width 0.28956)
		(layer "F.Cu")
		(net "SFP3_PRESENT_N")
	)
	(segment
		(start 347.530166 -13.200126)
		(end 349.594932 -15.264892)
		(width 0.28956)
		(layer "F.Cu")
		(net "SFP3_PRESENT_N")
	)
	(segment
		(start 350.777302 -21.092668)
		(end 350.258634 -21.092668)
		(width 0.28956)
		(layer "F.Cu")
		(net "SFP3_PRESENT_N")
	)
	(segment
		(start 350.777302 -21.092668)
		(end 350.777302 -22.159468)
		(width 0.28956)
		(layer "F.Cu")
		(net "SFP3_PRESENT_N")
	)
	(segment
		(start 350.258634 -21.092668)
		(end 350.1898 -21.161502)
		(width 0.28956)
		(layer "F.Cu")
		(net "SFP3_PRESENT_N")
	)
	(via
		(at 349.594932 -19.9898)
		(size 0.762)
		(drill 0.381)
		(layers "F.Cu" "B.Cu")
		(net "SFP3_PRESENT_N")
	)
	(via
		(at 178.0794 -4.2926)
		(size 0.508)
		(drill 0.254)
		(layers "F.Cu" "B.Cu")
		(net "AIRMAX_RSVD2")
	)
	(segment
		(start 178.0794 -4.2926)
		(end 176.7586 -5.6134)
		(width 0.18288)
		(layer "In2.Cu")
		(net "AIRMAX_RSVD2")
	)
	(segment
		(start 174.2694 -5.6134)
		(end 174.13986 -5.48386)
		(width 0.18288)
		(layer "In2.Cu")
		(net "AIRMAX_RSVD2")
	)
	(segment
		(start 176.7586 -5.6134)
		(end 174.2694 -5.6134)
		(width 0.18288)
		(layer "In2.Cu")
		(net "AIRMAX_RSVD2")
	)
	(segment
		(start 174.13986 -5.48386)
		(end 172.51934 -5.48386)
		(width 0.18288)
		(layer "In2.Cu")
		(net "AIRMAX_RSVD2")
	)
	(segment
		(start 172.51934 -5.48386)
		(end 172.4152 -5.588)
		(width 0.18288)
		(layer "In2.Cu")
		(net "AIRMAX_RSVD2")
	)
	(segment
		(start 169.677842 -5.588)
		(end 168.889934 -4.800092)
		(width 0.18288)
		(layer "In2.Cu")
		(net "AIRMAX_RSVD2")
	)
	(segment
		(start 172.4152 -5.588)
		(end 169.677842 -5.588)
		(width 0.18288)
		(layer "In2.Cu")
		(net "AIRMAX_RSVD2")
	)
	(segment
		(start 177.330354 -14.62278)
		(end 172.908468 -14.62278)
		(width 0.28956)
		(layer "F.Cu")
		(net "AIRMAX_RSVD3")
	)
	(segment
		(start 178.46294 -13.490194)
		(end 177.330354 -14.62278)
		(width 0.28956)
		(layer "F.Cu")
		(net "AIRMAX_RSVD3")
	)
	(segment
		(start 171.963334 -13.677646)
		(end 171.963334 -3.173476)
		(width 0.28956)
		(layer "F.Cu")
		(net "AIRMAX_RSVD3")
	)
	(segment
		(start 171.963334 -3.173476)
		(end 170.88993 -2.100072)
		(width 0.28956)
		(layer "F.Cu")
		(net "AIRMAX_RSVD3")
	)
	(segment
		(start 172.908468 -14.62278)
		(end 171.963334 -13.677646)
		(width 0.28956)
		(layer "F.Cu")
		(net "AIRMAX_RSVD3")
	)
	(via
		(at 178.46294 -13.490194)
		(size 0.762)
		(drill 0.381)
		(layers "F.Cu" "B.Cu")
		(net "AIRMAX_RSVD3")
	)
	(segment
		(start 170.007534 -13.5128)
		(end 170.007534 -4.382516)
		(width 0.28956)
		(layer "F.Cu")
		(net "AIRMAX_RSVD4")
	)
	(segment
		(start 172.662088 -15.21714)
		(end 171.643548 -14.1986)
		(width 0.28956)
		(layer "F.Cu")
		(net "AIRMAX_RSVD4")
	)
	(segment
		(start 171.643548 -14.1986)
		(end 170.693334 -14.1986)
		(width 0.28956)
		(layer "F.Cu")
		(net "AIRMAX_RSVD4")
	)
	(segment
		(start 170.007534 -4.382516)
		(end 170.88993 -3.50012)
		(width 0.28956)
		(layer "F.Cu")
		(net "AIRMAX_RSVD4")
	)
	(segment
		(start 179.21986 -15.21714)
		(end 172.662088 -15.21714)
		(width 0.28956)
		(layer "F.Cu")
		(net "AIRMAX_RSVD4")
	)
	(segment
		(start 170.693334 -14.1986)
		(end 170.007534 -13.5128)
		(width 0.28956)
		(layer "F.Cu")
		(net "AIRMAX_RSVD4")
	)
	(segment
		(start 179.7304 -14.7066)
		(end 179.21986 -15.21714)
		(width 0.28956)
		(layer "F.Cu")
		(net "AIRMAX_RSVD4")
	)
	(via
		(at 179.7304 -14.7066)
		(size 0.762)
		(drill 0.381)
		(layers "F.Cu" "B.Cu")
		(net "AIRMAX_RSVD4")
	)
	(segment
		(start 172.415454 -15.8115)
		(end 180.8861 -15.8115)
		(width 0.28956)
		(layer "F.Cu")
		(net "AIRMAX_RSVD1")
	)
	(segment
		(start 168.889934 -3.400044)
		(end 168.000934 -4.289044)
		(width 0.28956)
		(layer "F.Cu")
		(net "AIRMAX_RSVD1")
	)
	(segment
		(start 168.000934 -4.289044)
		(end 168.000934 -14.178534)
		(width 0.28956)
		(layer "F.Cu")
		(net "AIRMAX_RSVD1")
	)
	(segment
		(start 171.615354 -15.0114)
		(end 172.415454 -15.8115)
		(width 0.28956)
		(layer "F.Cu")
		(net "AIRMAX_RSVD1")
	)
	(segment
		(start 180.8861 -15.8115)
		(end 181.3306 -15.367)
		(width 0.28956)
		(layer "F.Cu")
		(net "AIRMAX_RSVD1")
	)
	(segment
		(start 168.000934 -14.178534)
		(end 168.8338 -15.0114)
		(width 0.28956)
		(layer "F.Cu")
		(net "AIRMAX_RSVD1")
	)
	(segment
		(start 168.8338 -15.0114)
		(end 171.615354 -15.0114)
		(width 0.28956)
		(layer "F.Cu")
		(net "AIRMAX_RSVD1")
	)
	(via
		(at 181.3306 -15.367)
		(size 0.762)
		(drill 0.381)
		(layers "F.Cu" "B.Cu")
		(net "AIRMAX_RSVD1")
	)
	(segment
		(start 119.5578 -12.872466)
		(end 119.5578 -17.4752)
		(width 0.28956)
		(layer "F.Cu")
		(net "SFP2_PRESENT_N")
	)
	(segment
		(start 120.530112 -11.900154)
		(end 119.5578 -12.872466)
		(width 0.28956)
		(layer "F.Cu")
		(net "SFP2_PRESENT_N")
	)
	(segment
		(start 119.833898 -19.9136)
		(end 119.833898 -21.147532)
		(width 0.28956)
		(layer "F.Cu")
		(net "SFP2_PRESENT_N")
	)
	(segment
		(start 119.833898 -17.751298)
		(end 119.833898 -19.9136)
		(width 0.28956)
		(layer "F.Cu")
		(net "SFP2_PRESENT_N")
	)
	(segment
		(start 119.833898 -22.239732)
		(end 119.833898 -21.147532)
		(width 0.28956)
		(layer "F.Cu")
		(net "SFP2_PRESENT_N")
	)
	(segment
		(start 119.833898 -22.619462)
		(end 120.571768 -23.357332)
		(width 0.28956)
		(layer "F.Cu")
		(net "SFP2_PRESENT_N")
	)
	(segment
		(start 119.5578 -17.4752)
		(end 119.833898 -17.751298)
		(width 0.28956)
		(layer "F.Cu")
		(net "SFP2_PRESENT_N")
	)
	(segment
		(start 119.833898 -22.239732)
		(end 119.833898 -22.619462)
		(width 0.28956)
		(layer "F.Cu")
		(net "SFP2_PRESENT_N")
	)
	(via
		(at 119.833898 -19.9136)
		(size 0.762)
		(drill 0.381)
		(layers "F.Cu" "B.Cu")
		(net "SFP2_PRESENT_N")
	)
	(segment
		(start 128.229868 -19.985736)
		(end 128.229868 -21.350732)
		(width 0.28956)
		(layer "F.Cu")
		(net "SFP1_PRESENT_N")
	)
	(segment
		(start 128.229868 -21.350732)
		(end 128.824736 -21.350732)
		(width 0.28956)
		(layer "F.Cu")
		(net "SFP1_PRESENT_N")
	)
	(segment
		(start 129.746502 -21.143468)
		(end 129.746502 -22.210268)
		(width 0.28956)
		(layer "F.Cu")
		(net "SFP1_PRESENT_N")
	)
	(segment
		(start 129.032 -21.143468)
		(end 129.746502 -21.143468)
		(width 0.28956)
		(layer "F.Cu")
		(net "SFP1_PRESENT_N")
	)
	(segment
		(start 128.824736 -21.350732)
		(end 129.032 -21.143468)
		(width 0.28956)
		(layer "F.Cu")
		(net "SFP1_PRESENT_N")
	)
	(segment
		(start 128.229868 -14.899894)
		(end 128.229868 -19.985736)
		(width 0.28956)
		(layer "F.Cu")
		(net "SFP1_PRESENT_N")
	)
	(segment
		(start 126.5301 -13.200126)
		(end 128.229868 -14.899894)
		(width 0.28956)
		(layer "F.Cu")
		(net "SFP1_PRESENT_N")
	)
	(via
		(at 128.229868 -19.985736)
		(size 0.762)
		(drill 0.381)
		(layers "F.Cu" "B.Cu")
		(net "SFP1_PRESENT_N")
	)
	(segment
		(start 345.53017 -9.100058)
		(end 346.521532 -10.09142)
		(width 0.28956)
		(layer "F.Cu")
		(net "SKU_PIN_BLAD2_1")
	)
	(segment
		(start 346.9386 -18.6944)
		(end 346.521532 -19.111468)
		(width 0.28956)
		(layer "F.Cu")
		(net "SKU_PIN_BLAD2_1")
	)
	(segment
		(start 346.521532 -19.111468)
		(end 346.521532 -19.9898)
		(width 0.28956)
		(layer "F.Cu")
		(net "SKU_PIN_BLAD2_1")
	)
	(segment
		(start 346.521532 -19.9898)
		(end 346.521532 -21.257768)
		(width 0.28956)
		(layer "F.Cu")
		(net "SKU_PIN_BLAD2_1")
	)
	(segment
		(start 346.521532 -15.203932)
		(end 346.9386 -15.621)
		(width 0.28956)
		(layer "F.Cu")
		(net "SKU_PIN_BLAD2_1")
	)
	(segment
		(start 346.521532 -10.09142)
		(end 346.521532 -15.203932)
		(width 0.28956)
		(layer "F.Cu")
		(net "SKU_PIN_BLAD2_1")
	)
	(segment
		(start 347.639132 -21.257768)
		(end 346.521532 -21.257768)
		(width 0.28956)
		(layer "F.Cu")
		(net "SKU_PIN_BLAD2_1")
	)
	(segment
		(start 346.9386 -15.621)
		(end 346.9386 -18.6944)
		(width 0.28956)
		(layer "F.Cu")
		(net "SKU_PIN_BLAD2_1")
	)
	(via
		(at 346.521532 -19.9898)
		(size 0.762)
		(drill 0.381)
		(layers "F.Cu" "B.Cu")
		(net "SKU_PIN_BLAD2_1")
	)
	(segment
		(start 344.8558 -19.9898)
		(end 345.425268 -20.559268)
		(width 0.28956)
		(layer "F.Cu")
		(net "SKU_PIN_BLAD2_2")
	)
	(segment
		(start 345.425268 -20.559268)
		(end 345.425268 -21.274532)
		(width 0.28956)
		(layer "F.Cu")
		(net "SKU_PIN_BLAD2_2")
	)
	(segment
		(start 345.425268 -21.274532)
		(end 344.333068 -21.274532)
		(width 0.28956)
		(layer "F.Cu")
		(net "SKU_PIN_BLAD2_2")
	)
	(segment
		(start 343.530174 -13.200126)
		(end 343.530174 -18.664174)
		(width 0.28956)
		(layer "F.Cu")
		(net "SKU_PIN_BLAD2_2")
	)
	(segment
		(start 343.530174 -18.664174)
		(end 344.8558 -19.9898)
		(width 0.28956)
		(layer "F.Cu")
		(net "SKU_PIN_BLAD2_2")
	)
	(via
		(at 344.8558 -19.9898)
		(size 0.762)
		(drill 0.381)
		(layers "F.Cu" "B.Cu")
		(net "SKU_PIN_BLAD2_2")
	)
	(segment
		(start 126.045468 -19.9644)
		(end 126.045468 -21.350732)
		(width 0.28956)
		(layer "F.Cu")
		(net "SKU_PIN_BLAD1_1")
	)
	(segment
		(start 125.4506 -13.4874)
		(end 126.045468 -14.082268)
		(width 0.28956)
		(layer "F.Cu")
		(net "SKU_PIN_BLAD1_1")
	)
	(segment
		(start 124.530104 -9.100058)
		(end 125.4506 -10.020554)
		(width 0.28956)
		(layer "F.Cu")
		(net "SKU_PIN_BLAD1_1")
	)
	(segment
		(start 126.045468 -21.350732)
		(end 127.141732 -21.350732)
		(width 0.28956)
		(layer "F.Cu")
		(net "SKU_PIN_BLAD1_1")
	)
	(segment
		(start 125.4506 -10.020554)
		(end 125.4506 -13.4874)
		(width 0.28956)
		(layer "F.Cu")
		(net "SKU_PIN_BLAD1_1")
	)
	(segment
		(start 126.045468 -14.082268)
		(end 126.045468 -19.9644)
		(width 0.28956)
		(layer "F.Cu")
		(net "SKU_PIN_BLAD1_1")
	)
	(via
		(at 126.045468 -19.9644)
		(size 0.762)
		(drill 0.381)
		(layers "F.Cu" "B.Cu")
		(net "SKU_PIN_BLAD1_1")
	)
	(segment
		(start 122.530108 -13.200126)
		(end 122.530108 -18.654776)
		(width 0.28956)
		(layer "F.Cu")
		(net "SKU_PIN_BLAD1_2")
	)
	(segment
		(start 123.839732 -19.9644)
		(end 123.839732 -21.350732)
		(width 0.28956)
		(layer "F.Cu")
		(net "SKU_PIN_BLAD1_2")
	)
	(segment
		(start 122.530108 -18.654776)
		(end 123.839732 -19.9644)
		(width 0.28956)
		(layer "F.Cu")
		(net "SKU_PIN_BLAD1_2")
	)
	(segment
		(start 123.839732 -21.350732)
		(end 122.747532 -21.350732)
		(width 0.28956)
		(layer "F.Cu")
		(net "SKU_PIN_BLAD1_2")
	)
	(via
		(at 123.839732 -19.9644)
		(size 0.762)
		(drill 0.381)
		(layers "F.Cu" "B.Cu")
		(net "SKU_PIN_BLAD1_2")
	)
	(segment
		(start 342.4682 -19.939)
		(end 342.965278 -20.436078)
		(width 0.28956)
		(layer "F.Cu")
		(net "BLADE2_MATED_N")
	)
	(segment
		(start 342.965278 -20.436078)
		(end 342.965278 -21.38299)
		(width 0.28956)
		(layer "F.Cu")
		(net "BLADE2_MATED_N")
	)
	(segment
		(start 341.530178 -13.299948)
		(end 341.530178 -19.000978)
		(width 0.28956)
		(layer "F.Cu")
		(net "BLADE2_MATED_N")
	)
	(segment
		(start 341.530178 -19.000978)
		(end 342.4682 -19.939)
		(width 0.28956)
		(layer "F.Cu")
		(net "BLADE2_MATED_N")
	)
	(via
		(at 342.4682 -19.939)
		(size 0.762)
		(drill 0.381)
		(layers "F.Cu" "B.Cu")
		(net "BLADE2_MATED_N")
	)
	(segment
		(start 120.530112 -13.299948)
		(end 120.530112 -19.227292)
		(width 0.28956)
		(layer "F.Cu")
		(net "BLADE1_MATED_N")
	)
	(segment
		(start 121.31802 -20.0152)
		(end 121.31802 -21.152612)
		(width 0.28956)
		(layer "F.Cu")
		(net "BLADE1_MATED_N")
	)
	(segment
		(start 120.530112 -19.227292)
		(end 121.31802 -20.0152)
		(width 0.28956)
		(layer "F.Cu")
		(net "BLADE1_MATED_N")
	)
	(via
		(at 121.31802 -20.0152)
		(size 0.762)
		(drill 0.381)
		(layers "F.Cu" "B.Cu")
		(net "BLADE1_MATED_N")
	)
	(segment
		(start 170.850052 -23.69566)
		(end 171.335192 -24.1808)
		(width 0.1778)
		(layer "F.Cu")
		(net "SAS_BLAD1_TX7_N")
	)
	(segment
		(start 171.335192 -24.609552)
		(end 171.085002 -24.859742)
		(width 0.1778)
		(layer "F.Cu")
		(net "SAS_BLAD1_TX7_N")
	)
	(segment
		(start 171.085002 -24.859742)
		(end 171.085002 -25.899872)
		(width 0.1778)
		(layer "F.Cu")
		(net "SAS_BLAD1_TX7_N")
	)
	(segment
		(start 171.335192 -24.1808)
		(end 171.335192 -24.609552)
		(width 0.1778)
		(layer "F.Cu")
		(net "SAS_BLAD1_TX7_N")
	)
	(via
		(at 170.850052 -23.69566)
		(size 0.508)
		(drill 0.254)
		(layers "F.Cu" "B.Cu")
		(net "SAS_BLAD1_TX7_N")
	)
	(segment
		(start 166.0652 -19.287236)
		(end 166.23792 -19.114516)
		(width 0.1778)
		(layer "B.Cu")
		(net "SAS_BLAD1_TX7_N")
	)
	(segment
		(start 166.0652 -20.947888)
		(end 166.0652 -20.699476)
		(width 0.1778)
		(layer "B.Cu")
		(net "SAS_BLAD1_TX7_N")
	)
	(segment
		(start 166.23792 -19.114516)
		(end 166.23792 -18.581116)
		(width 0.1778)
		(layer "B.Cu")
		(net "SAS_BLAD1_TX7_N")
	)
	(segment
		(start 166.245032 -11.37539)
		(end 166.77259 -11.37539)
		(width 0.1778)
		(layer "B.Cu")
		(net "SAS_BLAD1_TX7_N")
	)
	(segment
		(start 166.0652 -19.820636)
		(end 166.0652 -19.287236)
		(width 0.1778)
		(layer "B.Cu")
		(net "SAS_BLAD1_TX7_N")
	)
	(segment
		(start 166.0652 -20.699476)
		(end 166.23792 -20.526756)
		(width 0.1778)
		(layer "B.Cu")
		(net "SAS_BLAD1_TX7_N")
	)
	(segment
		(start 170.731688 -25.43048)
		(end 170.141392 -25.43048)
		(width 0.1778)
		(layer "B.Cu")
		(net "SAS_BLAD1_TX7_N")
	)
	(segment
		(start 166.23792 -20.526756)
		(end 166.23792 -19.993356)
		(width 0.1778)
		(layer "B.Cu")
		(net "SAS_BLAD1_TX7_N")
	)
	(segment
		(start 166.0652 -17.874996)
		(end 166.23792 -17.702276)
		(width 0.1778)
		(layer "B.Cu")
		(net "SAS_BLAD1_TX7_N")
	)
	(segment
		(start 166.0652 -18.408396)
		(end 166.0652 -17.874996)
		(width 0.1778)
		(layer "B.Cu")
		(net "SAS_BLAD1_TX7_N")
	)
	(segment
		(start 166.0652 -16.996156)
		(end 166.0652 -11.555476)
		(width 0.1778)
		(layer "B.Cu")
		(net "SAS_BLAD1_TX7_N")
	)
	(segment
		(start 166.23792 -18.581116)
		(end 166.0652 -18.408396)
		(width 0.1778)
		(layer "B.Cu")
		(net "SAS_BLAD1_TX7_N")
	)
	(segment
		(start 169.782236 -25.281636)
		(end 169.536364 -25.035764)
		(width 0.1778)
		(layer "B.Cu")
		(net "SAS_BLAD1_TX7_N")
	)
	(segment
		(start 166.23792 -17.702276)
		(end 166.23792 -17.168876)
		(width 0.1778)
		(layer "B.Cu")
		(net "SAS_BLAD1_TX7_N")
	)
	(segment
		(start 169.248836 -24.341836)
		(end 166.214044 -21.307044)
		(width 0.1778)
		(layer "B.Cu")
		(net "SAS_BLAD1_TX7_N")
	)
	(segment
		(start 170.850052 -23.69566)
		(end 171.309792 -24.1554)
		(width 0.1778)
		(layer "B.Cu")
		(net "SAS_BLAD1_TX7_N")
	)
	(segment
		(start 166.23792 -17.168876)
		(end 166.0652 -16.996156)
		(width 0.1778)
		(layer "B.Cu")
		(net "SAS_BLAD1_TX7_N")
	)
	(segment
		(start 166.23792 -19.993356)
		(end 166.0652 -19.820636)
		(width 0.1778)
		(layer "B.Cu")
		(net "SAS_BLAD1_TX7_N")
	)
	(segment
		(start 171.309792 -24.1554)
		(end 171.309792 -24.799798)
		(width 0.1778)
		(layer "B.Cu")
		(net "SAS_BLAD1_TX7_N")
	)
	(segment
		(start 171.202096 -25.025096)
		(end 170.84294 -25.384252)
		(width 0.1778)
		(layer "B.Cu")
		(net "SAS_BLAD1_TX7_N")
	)
	(segment
		(start 171.309792 -24.799798)
		(end 171.202096 -25.025096)
		(width 0.1778)
		(layer "B.Cu")
		(net "SAS_BLAD1_TX7_N")
	)
	(segment
		(start 166.77259 -11.37539)
		(end 166.889938 -11.492738)
		(width 0.1778)
		(layer "B.Cu")
		(net "SAS_BLAD1_TX7_N")
	)
	(segment
		(start 166.889938 -11.492738)
		(end 166.889938 -11.900154)
		(width 0.1778)
		(layer "B.Cu")
		(net "SAS_BLAD1_TX7_N")
	)
	(arc
		(start 169.3926 -24.6888)
		(mid 169.355231 -24.501021)
		(end 169.248836 -24.341836)
		(width 0.1778)
		(layer "B.Cu")
		(net "SAS_BLAD1_TX7_N")
	)
	(arc
		(start 166.118032 -11.427968)
		(mid 166.1763 -11.389035)
		(end 166.245032 -11.37539)
		(width 0.1778)
		(layer "B.Cu")
		(net "SAS_BLAD1_TX7_N")
	)
	(arc
		(start 166.214044 -21.307044)
		(mid 166.103886 -21.142276)
		(end 166.0652 -20.947888)
		(width 0.1778)
		(layer "B.Cu")
		(net "SAS_BLAD1_TX7_N")
	)
	(arc
		(start 170.141392 -25.43048)
		(mid 169.947003 -25.391796)
		(end 169.782236 -25.281636)
		(width 0.1778)
		(layer "B.Cu")
		(net "SAS_BLAD1_TX7_N")
	)
	(arc
		(start 166.0652 -11.555476)
		(mid 166.078928 -11.486463)
		(end 166.118032 -11.427968)
		(width 0.1778)
		(layer "B.Cu")
		(net "SAS_BLAD1_TX7_N")
	)
	(arc
		(start 170.84294 -25.384252)
		(mid 170.791926 -25.418465)
		(end 170.731688 -25.43048)
		(width 0.1778)
		(layer "B.Cu")
		(net "SAS_BLAD1_TX7_N")
	)
	(arc
		(start 169.536364 -25.035764)
		(mid 169.429944 -24.87659)
		(end 169.3926 -24.6888)
		(width 0.1778)
		(layer "B.Cu")
		(net "SAS_BLAD1_TX7_N")
	)
	(segment
		(start 171.685712 -24.13)
		(end 171.685712 -24.609552)
		(width 0.1778)
		(layer "F.Cu")
		(net "SAS_BLAD1_TX7_P")
	)
	(segment
		(start 172.120052 -23.69566)
		(end 171.685712 -24.13)
		(width 0.1778)
		(layer "F.Cu")
		(net "SAS_BLAD1_TX7_P")
	)
	(segment
		(start 171.885102 -24.808942)
		(end 171.885102 -25.899872)
		(width 0.1778)
		(layer "F.Cu")
		(net "SAS_BLAD1_TX7_P")
	)
	(segment
		(start 171.685712 -24.609552)
		(end 171.885102 -24.808942)
		(width 0.1778)
		(layer "F.Cu")
		(net "SAS_BLAD1_TX7_P")
	)
	(via
		(at 172.120052 -23.69566)
		(size 0.508)
		(drill 0.254)
		(layers "F.Cu" "B.Cu")
		(net "SAS_BLAD1_TX7_P")
	)
	(segment
		(start 166.245032 -11.02487)
		(end 166.72433 -11.02487)
		(width 0.1778)
		(layer "B.Cu")
		(net "SAS_BLAD1_TX7_P")
	)
	(segment
		(start 166.72433 -11.02487)
		(end 166.889938 -10.859262)
		(width 0.1778)
		(layer "B.Cu")
		(net "SAS_BLAD1_TX7_P")
	)
	(segment
		(start 172.120052 -23.69566)
		(end 171.660312 -24.1554)
		(width 0.1778)
		(layer "B.Cu")
		(net "SAS_BLAD1_TX7_P")
	)
	(segment
		(start 165.71468 -20.947888)
		(end 165.71468 -11.555476)
		(width 0.1778)
		(layer "B.Cu")
		(net "SAS_BLAD1_TX7_P")
	)
	(segment
		(start 166.889938 -10.859262)
		(end 166.889938 -10.500106)
		(width 0.1778)
		(layer "B.Cu")
		(net "SAS_BLAD1_TX7_P")
	)
	(segment
		(start 171.492418 -25.230582)
		(end 171.091098 -25.631902)
		(width 0.1778)
		(layer "B.Cu")
		(net "SAS_BLAD1_TX7_P")
	)
	(segment
		(start 171.660312 -24.1554)
		(end 171.660312 -24.8793)
		(width 0.1778)
		(layer "B.Cu")
		(net "SAS_BLAD1_TX7_P")
	)
	(segment
		(start 169.000932 -24.58974)
		(end 165.96614 -21.554948)
		(width 0.1778)
		(layer "B.Cu")
		(net "SAS_BLAD1_TX7_P")
	)
	(segment
		(start 170.731688 -25.781)
		(end 170.141392 -25.781)
		(width 0.1778)
		(layer "B.Cu")
		(net "SAS_BLAD1_TX7_P")
	)
	(segment
		(start 169.534332 -25.52954)
		(end 169.28846 -25.283668)
		(width 0.1778)
		(layer "B.Cu")
		(net "SAS_BLAD1_TX7_P")
	)
	(segment
		(start 171.660312 -24.8793)
		(end 171.492418 -25.230582)
		(width 0.1778)
		(layer "B.Cu")
		(net "SAS_BLAD1_TX7_P")
	)
	(arc
		(start 169.04208 -24.6888)
		(mid 169.031377 -24.635173)
		(end 169.000932 -24.58974)
		(width 0.1778)
		(layer "B.Cu")
		(net "SAS_BLAD1_TX7_P")
	)
	(arc
		(start 169.28846 -25.283668)
		(mid 169.106096 -25.01074)
		(end 169.04208 -24.6888)
		(width 0.1778)
		(layer "B.Cu")
		(net "SAS_BLAD1_TX7_P")
	)
	(arc
		(start 171.091098 -25.631902)
		(mid 170.926242 -25.742245)
		(end 170.731688 -25.781)
		(width 0.1778)
		(layer "B.Cu")
		(net "SAS_BLAD1_TX7_P")
	)
	(arc
		(start 170.141392 -25.781)
		(mid 169.812851 -25.715649)
		(end 169.534332 -25.52954)
		(width 0.1778)
		(layer "B.Cu")
		(net "SAS_BLAD1_TX7_P")
	)
	(arc
		(start 165.870128 -11.180064)
		(mid 166.04215 -11.065186)
		(end 166.245032 -11.02487)
		(width 0.1778)
		(layer "B.Cu")
		(net "SAS_BLAD1_TX7_P")
	)
	(arc
		(start 165.96614 -21.554948)
		(mid 165.780038 -21.276427)
		(end 165.71468 -20.947888)
		(width 0.1778)
		(layer "B.Cu")
		(net "SAS_BLAD1_TX7_P")
	)
	(arc
		(start 165.71468 -11.555476)
		(mid 165.755074 -11.35231)
		(end 165.870128 -11.180064)
		(width 0.1778)
		(layer "B.Cu")
		(net "SAS_BLAD1_TX7_P")
	)
	(segment
		(start 192.094866 -29.50083)
		(end 192.094866 -28.4099)
		(width 0.1778)
		(layer "F.Cu")
		(net "SAS_BLAD1_RX2_N")
	)
	(segment
		(start 192.33388 -29.739844)
		(end 192.094866 -29.50083)
		(width 0.1778)
		(layer "F.Cu")
		(net "SAS_BLAD1_RX2_N")
	)
	(segment
		(start 191.87414 -31.68142)
		(end 192.33388 -31.22168)
		(width 0.1778)
		(layer "F.Cu")
		(net "SAS_BLAD1_RX2_N")
	)
	(segment
		(start 192.33388 -31.22168)
		(end 192.33388 -29.739844)
		(width 0.1778)
		(layer "F.Cu")
		(net "SAS_BLAD1_RX2_N")
	)
	(via
		(at 191.87414 -31.68142)
		(size 0.508)
		(drill 0.254)
		(layers "F.Cu" "B.Cu")
		(net "SAS_BLAD1_RX2_N")
	)
	(segment
		(start 183.83758 -23.335488)
		(end 183.609488 -23.335488)
		(width 0.1524)
		(layer "In5.Cu")
		(net "SAS_BLAD1_RX2_N")
	)
	(segment
		(start 182.962804 -22.460712)
		(end 182.734712 -22.460712)
		(width 0.1524)
		(layer "In5.Cu")
		(net "SAS_BLAD1_RX2_N")
	)
	(segment
		(start 192.30594 -32.11322)
		(end 192.30594 -32.349948)
		(width 0.1524)
		(layer "In5.Cu")
		(net "SAS_BLAD1_RX2_N")
	)
	(segment
		(start 185.587132 -25.08504)
		(end 185.35904 -25.08504)
		(width 0.1524)
		(layer "In5.Cu")
		(net "SAS_BLAD1_RX2_N")
	)
	(segment
		(start 181.536594 -21.262594)
		(end 181.536594 -21.034502)
		(width 0.1524)
		(layer "In5.Cu")
		(net "SAS_BLAD1_RX2_N")
	)
	(segment
		(start 188.44006 -30.76829)
		(end 187.844684 -29.875226)
		(width 0.1524)
		(layer "In5.Cu")
		(net "SAS_BLAD1_RX2_N")
	)
	(segment
		(start 192.276222 -32.421576)
		(end 192.190116 -32.507682)
		(width 0.1524)
		(layer "In5.Cu")
		(net "SAS_BLAD1_RX2_N")
	)
	(segment
		(start 172.889926 -12.895326)
		(end 172.889926 -13.200126)
		(width 0.1524)
		(layer "In5.Cu")
		(net "SAS_BLAD1_RX2_N")
	)
	(segment
		(start 187.797948 -29.78785)
		(end 187.717176 -29.592778)
		(width 0.1524)
		(layer "In5.Cu")
		(net "SAS_BLAD1_RX2_N")
	)
	(segment
		(start 181.213252 -20.71116)
		(end 180.98516 -20.71116)
		(width 0.1524)
		(layer "In5.Cu")
		(net "SAS_BLAD1_RX2_N")
	)
	(segment
		(start 172.046392 -13.804646)
		(end 172.046392 -13.06703)
		(width 0.1524)
		(layer "In5.Cu")
		(net "SAS_BLAD1_RX2_N")
	)
	(segment
		(start 191.444118 -32.498792)
		(end 189.635638 -31.749238)
		(width 0.1524)
		(layer "In5.Cu")
		(net "SAS_BLAD1_RX2_N")
	)
	(segment
		(start 172.081952 -13.890752)
		(end 172.046392 -13.804646)
		(width 0.1524)
		(layer "In5.Cu")
		(net "SAS_BLAD1_RX2_N")
	)
	(segment
		(start 184.484264 -24.210264)
		(end 184.160922 -23.886922)
		(width 0.1524)
		(layer "In5.Cu")
		(net "SAS_BLAD1_RX2_N")
	)
	(segment
		(start 184.160922 -23.886922)
		(end 184.160922 -23.65883)
		(width 0.1524)
		(layer "In5.Cu")
		(net "SAS_BLAD1_RX2_N")
	)
	(segment
		(start 173.528228 -15.337028)
		(end 172.081952 -13.890752)
		(width 0.1524)
		(layer "In5.Cu")
		(net "SAS_BLAD1_RX2_N")
	)
	(segment
		(start 178.16957 -18.338038)
		(end 176.067212 -16.495014)
		(width 0.1524)
		(layer "In5.Cu")
		(net "SAS_BLAD1_RX2_N")
	)
	(segment
		(start 183.286146 -22.784054)
		(end 182.962804 -22.460712)
		(width 0.1524)
		(layer "In5.Cu")
		(net "SAS_BLAD1_RX2_N")
	)
	(segment
		(start 182.088028 -21.585936)
		(end 181.859936 -21.585936)
		(width 0.1524)
		(layer "In5.Cu")
		(net "SAS_BLAD1_RX2_N")
	)
	(segment
		(start 184.160922 -23.65883)
		(end 183.83758 -23.335488)
		(width 0.1524)
		(layer "In5.Cu")
		(net "SAS_BLAD1_RX2_N")
	)
	(segment
		(start 185.910474 -25.408382)
		(end 185.587132 -25.08504)
		(width 0.1524)
		(layer "In5.Cu")
		(net "SAS_BLAD1_RX2_N")
	)
	(segment
		(start 189.545214 -31.70047)
		(end 189.005972 -31.335218)
		(width 0.1524)
		(layer "In5.Cu")
		(net "SAS_BLAD1_RX2_N")
	)
	(segment
		(start 187.667392 -29.248608)
		(end 186.393074 -26.173684)
		(width 0.1524)
		(layer "In5.Cu")
		(net "SAS_BLAD1_RX2_N")
	)
	(segment
		(start 191.87414 -31.68142)
		(end 192.30594 -32.11322)
		(width 0.1524)
		(layer "In5.Cu")
		(net "SAS_BLAD1_RX2_N")
	)
	(segment
		(start 181.536594 -21.034502)
		(end 181.213252 -20.71116)
		(width 0.1524)
		(layer "In5.Cu")
		(net "SAS_BLAD1_RX2_N")
	)
	(segment
		(start 186.283092 -26.009092)
		(end 185.910474 -25.636474)
		(width 0.1524)
		(layer "In5.Cu")
		(net "SAS_BLAD1_RX2_N")
	)
	(segment
		(start 176.067212 -16.495014)
		(end 173.528228 -15.337028)
		(width 0.1524)
		(layer "In5.Cu")
		(net "SAS_BLAD1_RX2_N")
	)
	(segment
		(start 180.715412 -20.441412)
		(end 178.16957 -18.338038)
		(width 0.1524)
		(layer "In5.Cu")
		(net "SAS_BLAD1_RX2_N")
	)
	(segment
		(start 185.910474 -25.636474)
		(end 185.910474 -25.408382)
		(width 0.1524)
		(layer "In5.Cu")
		(net "SAS_BLAD1_RX2_N")
	)
	(segment
		(start 182.41137 -22.13737)
		(end 182.41137 -21.909278)
		(width 0.1524)
		(layer "In5.Cu")
		(net "SAS_BLAD1_RX2_N")
	)
	(segment
		(start 185.035698 -24.533606)
		(end 184.712356 -24.210264)
		(width 0.1524)
		(layer "In5.Cu")
		(net "SAS_BLAD1_RX2_N")
	)
	(segment
		(start 183.609488 -23.335488)
		(end 183.286146 -23.012146)
		(width 0.1524)
		(layer "In5.Cu")
		(net "SAS_BLAD1_RX2_N")
	)
	(segment
		(start 182.734712 -22.460712)
		(end 182.41137 -22.13737)
		(width 0.1524)
		(layer "In5.Cu")
		(net "SAS_BLAD1_RX2_N")
	)
	(segment
		(start 180.98516 -20.71116)
		(end 180.715412 -20.441412)
		(width 0.1524)
		(layer "In5.Cu")
		(net "SAS_BLAD1_RX2_N")
	)
	(segment
		(start 172.697902 -12.703302)
		(end 172.889926 -12.895326)
		(width 0.1524)
		(layer "In5.Cu")
		(net "SAS_BLAD1_RX2_N")
	)
	(segment
		(start 188.93155 -31.27375)
		(end 188.50356 -30.84576)
		(width 0.1524)
		(layer "In5.Cu")
		(net "SAS_BLAD1_RX2_N")
	)
	(segment
		(start 181.859936 -21.585936)
		(end 181.536594 -21.262594)
		(width 0.1524)
		(layer "In5.Cu")
		(net "SAS_BLAD1_RX2_N")
	)
	(segment
		(start 182.41137 -21.909278)
		(end 182.088028 -21.585936)
		(width 0.1524)
		(layer "In5.Cu")
		(net "SAS_BLAD1_RX2_N")
	)
	(segment
		(start 185.35904 -25.08504)
		(end 185.035698 -24.761698)
		(width 0.1524)
		(layer "In5.Cu")
		(net "SAS_BLAD1_RX2_N")
	)
	(segment
		(start 183.286146 -23.012146)
		(end 183.286146 -22.784054)
		(width 0.1524)
		(layer "In5.Cu")
		(net "SAS_BLAD1_RX2_N")
	)
	(segment
		(start 187.706 -29.536136)
		(end 187.706 -29.443172)
		(width 0.1524)
		(layer "In5.Cu")
		(net "SAS_BLAD1_RX2_N")
	)
	(segment
		(start 184.712356 -24.210264)
		(end 184.484264 -24.210264)
		(width 0.1524)
		(layer "In5.Cu")
		(net "SAS_BLAD1_RX2_N")
	)
	(segment
		(start 172.41012 -12.703302)
		(end 172.697902 -12.703302)
		(width 0.1524)
		(layer "In5.Cu")
		(net "SAS_BLAD1_RX2_N")
	)
	(segment
		(start 185.035698 -24.761698)
		(end 185.035698 -24.533606)
		(width 0.1524)
		(layer "In5.Cu")
		(net "SAS_BLAD1_RX2_N")
	)
	(segment
		(start 192.118488 -32.5374)
		(end 191.638682 -32.5374)
		(width 0.1524)
		(layer "In5.Cu")
		(net "SAS_BLAD1_RX2_N")
	)
	(arc
		(start 172.153072 -12.809728)
		(mid 172.271021 -12.73098)
		(end 172.41012 -12.703302)
		(width 0.1524)
		(layer "In5.Cu")
		(net "SAS_BLAD1_RX2_N")
	)
	(arc
		(start 192.30594 -32.349948)
		(mid 192.29821 -32.388717)
		(end 192.276222 -32.421576)
		(width 0.1524)
		(layer "In5.Cu")
		(net "SAS_BLAD1_RX2_N")
	)
	(arc
		(start 172.046392 -13.06703)
		(mid 172.074114 -12.927754)
		(end 172.153072 -12.809728)
		(width 0.1524)
		(layer "In5.Cu")
		(net "SAS_BLAD1_RX2_N")
	)
	(arc
		(start 188.50356 -30.84576)
		(mid 188.469895 -30.808594)
		(end 188.44006 -30.76829)
		(width 0.1524)
		(layer "In5.Cu")
		(net "SAS_BLAD1_RX2_N")
	)
	(arc
		(start 189.635638 -31.749238)
		(mid 189.589185 -31.727153)
		(end 189.545214 -31.70047)
		(width 0.1524)
		(layer "In5.Cu")
		(net "SAS_BLAD1_RX2_N")
	)
	(arc
		(start 191.638682 -32.5374)
		(mid 191.5395 -32.527674)
		(end 191.444118 -32.498792)
		(width 0.1524)
		(layer "In5.Cu")
		(net "SAS_BLAD1_RX2_N")
	)
	(arc
		(start 187.706 -29.443172)
		(mid 187.696274 -29.34399)
		(end 187.667392 -29.248608)
		(width 0.1524)
		(layer "In5.Cu")
		(net "SAS_BLAD1_RX2_N")
	)
	(arc
		(start 189.005972 -31.335218)
		(mid 188.967294 -31.30626)
		(end 188.93155 -31.27375)
		(width 0.1524)
		(layer "In5.Cu")
		(net "SAS_BLAD1_RX2_N")
	)
	(arc
		(start 192.190116 -32.507682)
		(mid 192.157267 -32.529694)
		(end 192.118488 -32.5374)
		(width 0.1524)
		(layer "In5.Cu")
		(net "SAS_BLAD1_RX2_N")
	)
	(arc
		(start 187.717176 -29.592778)
		(mid 187.708796 -29.565008)
		(end 187.706 -29.536136)
		(width 0.1524)
		(layer "In5.Cu")
		(net "SAS_BLAD1_RX2_N")
	)
	(arc
		(start 186.393074 -26.173684)
		(mid 186.346182 -26.085975)
		(end 186.283092 -26.009092)
		(width 0.1524)
		(layer "In5.Cu")
		(net "SAS_BLAD1_RX2_N")
	)
	(arc
		(start 187.844684 -29.875226)
		(mid 187.819175 -29.832683)
		(end 187.797948 -29.78785)
		(width 0.1524)
		(layer "In5.Cu")
		(net "SAS_BLAD1_RX2_N")
	)
	(segment
		(start 173.885098 -28.4099)
		(end 173.885098 -29.50083)
		(width 0.1778)
		(layer "F.Cu")
		(net "SAS_BLAD1_RX6_P")
	)
	(segment
		(start 173.660308 -29.72562)
		(end 173.660308 -32.43326)
		(width 0.1778)
		(layer "F.Cu")
		(net "SAS_BLAD1_RX6_P")
	)
	(segment
		(start 173.660308 -32.43326)
		(end 174.145448 -32.9184)
		(width 0.1778)
		(layer "F.Cu")
		(net "SAS_BLAD1_RX6_P")
	)
	(segment
		(start 173.885098 -29.50083)
		(end 173.660308 -29.72562)
		(width 0.1778)
		(layer "F.Cu")
		(net "SAS_BLAD1_RX6_P")
	)
	(via
		(at 174.145448 -32.9184)
		(size 0.508)
		(drill 0.254)
		(layers "F.Cu" "B.Cu")
		(net "SAS_BLAD1_RX6_P")
	)
	(segment
		(start 174.06366 -22.327362)
		(end 174.027592 -22.183852)
		(width 0.1778)
		(layer "B.Cu")
		(net "SAS_BLAD1_RX6_P")
	)
	(segment
		(start 173.858428 -30.764734)
		(end 173.685708 -30.592014)
		(width 0.1778)
		(layer "B.Cu")
		(net "SAS_BLAD1_RX6_P")
	)
	(segment
		(start 167.0812 -6.824726)
		(end 166.889938 -6.633464)
		(width 0.1778)
		(layer "B.Cu")
		(net "SAS_BLAD1_RX6_P")
	)
	(segment
		(start 173.332394 -20.8153)
		(end 172.955458 -20.43811)
		(width 0.1778)
		(layer "B.Cu")
		(net "SAS_BLAD1_RX6_P")
	)
	(segment
		(start 173.685708 -27.794458)
		(end 173.685708 -27.433524)
		(width 0.1778)
		(layer "B.Cu")
		(net "SAS_BLAD1_RX6_P")
	)
	(segment
		(start 174.23892 -22.66315)
		(end 174.0662 -22.49043)
		(width 0.1778)
		(layer "B.Cu")
		(net "SAS_BLAD1_RX6_P")
	)
	(segment
		(start 173.332902 -21.059648)
		(end 173.332394 -21.059648)
		(width 0.1778)
		(layer "B.Cu")
		(net "SAS_BLAD1_RX6_P")
	)
	(segment
		(start 173.685708 -30.592014)
		(end 173.685708 -28.673298)
		(width 0.1778)
		(layer "B.Cu")
		(net "SAS_BLAD1_RX6_P")
	)
	(segment
		(start 172.955458 -20.43811)
		(end 172.711364 -20.43811)
		(width 0.1778)
		(layer "B.Cu")
		(net "SAS_BLAD1_RX6_P")
	)
	(segment
		(start 174.0662 -23.36927)
		(end 174.23892 -23.19655)
		(width 0.1778)
		(layer "B.Cu")
		(net "SAS_BLAD1_RX6_P")
	)
	(segment
		(start 166.889938 -6.633464)
		(end 166.889938 -6.299962)
		(width 0.1778)
		(layer "B.Cu")
		(net "SAS_BLAD1_RX6_P")
	)
	(segment
		(start 174.0662 -26.221436)
		(end 174.23892 -26.048716)
		(width 0.1778)
		(layer "B.Cu")
		(net "SAS_BLAD1_RX6_P")
	)
	(segment
		(start 173.65218 -21.37918)
		(end 173.535594 -21.262594)
		(width 0.1778)
		(layer "B.Cu")
		(net "SAS_BLAD1_RX6_P")
	)
	(segment
		(start 174.23892 -23.19655)
		(end 174.23892 -22.66315)
		(width 0.1778)
		(layer "B.Cu")
		(net "SAS_BLAD1_RX6_P")
	)
	(segment
		(start 174.0662 -22.49043)
		(end 174.0662 -22.378162)
		(width 0.1778)
		(layer "B.Cu")
		(net "SAS_BLAD1_RX6_P")
	)
	(segment
		(start 169.028872 -16.755872)
		(end 168.336722 -15.078964)
		(width 0.1778)
		(layer "B.Cu")
		(net "SAS_BLAD1_RX6_P")
	)
	(segment
		(start 173.53534 -21.262086)
		(end 173.332902 -21.059648)
		(width 0.1778)
		(layer "B.Cu")
		(net "SAS_BLAD1_RX6_P")
	)
	(segment
		(start 174.23892 -24.622506)
		(end 174.23892 -24.089106)
		(width 0.1778)
		(layer "B.Cu")
		(net "SAS_BLAD1_RX6_P")
	)
	(segment
		(start 174.0662 -25.342596)
		(end 174.0662 -24.795226)
		(width 0.1778)
		(layer "B.Cu")
		(net "SAS_BLAD1_RX6_P")
	)
	(segment
		(start 172.711364 -20.43811)
		(end 169.028872 -16.755872)
		(width 0.1778)
		(layer "B.Cu")
		(net "SAS_BLAD1_RX6_P")
	)
	(segment
		(start 173.332394 -21.059648)
		(end 173.332394 -20.8153)
		(width 0.1778)
		(layer "B.Cu")
		(net "SAS_BLAD1_RX6_P")
	)
	(segment
		(start 167.91178 -6.984492)
		(end 167.906954 -6.979666)
		(width 0.1778)
		(layer "B.Cu")
		(net "SAS_BLAD1_RX6_P")
	)
	(segment
		(start 173.858428 -28.500578)
		(end 173.858428 -27.967178)
		(width 0.1778)
		(layer "B.Cu")
		(net "SAS_BLAD1_RX6_P")
	)
	(segment
		(start 173.834552 -27.074368)
		(end 173.917356 -26.991564)
		(width 0.1778)
		(layer "B.Cu")
		(net "SAS_BLAD1_RX6_P")
	)
	(segment
		(start 168.336722 -15.078964)
		(end 168.0718 -13.97)
		(width 0.1778)
		(layer "B.Cu")
		(net "SAS_BLAD1_RX6_P")
	)
	(segment
		(start 173.685708 -28.673298)
		(end 173.858428 -28.500578)
		(width 0.1778)
		(layer "B.Cu")
		(net "SAS_BLAD1_RX6_P")
	)
	(segment
		(start 174.027592 -22.183852)
		(end 173.762162 -21.543772)
		(width 0.1778)
		(layer "B.Cu")
		(net "SAS_BLAD1_RX6_P")
	)
	(segment
		(start 173.685708 -31.470854)
		(end 173.858428 -31.298134)
		(width 0.1778)
		(layer "B.Cu")
		(net "SAS_BLAD1_RX6_P")
	)
	(segment
		(start 168.0718 -13.97)
		(end 168.0718 -7.370572)
		(width 0.1778)
		(layer "B.Cu")
		(net "SAS_BLAD1_RX6_P")
	)
	(segment
		(start 174.0662 -26.632408)
		(end 174.0662 -26.221436)
		(width 0.1778)
		(layer "B.Cu")
		(net "SAS_BLAD1_RX6_P")
	)
	(segment
		(start 167.532812 -6.824726)
		(end 167.0812 -6.824726)
		(width 0.1778)
		(layer "B.Cu")
		(net "SAS_BLAD1_RX6_P")
	)
	(segment
		(start 174.145448 -32.9184)
		(end 173.685708 -32.45866)
		(width 0.1778)
		(layer "B.Cu")
		(net "SAS_BLAD1_RX6_P")
	)
	(segment
		(start 174.0662 -23.916386)
		(end 174.0662 -23.36927)
		(width 0.1778)
		(layer "B.Cu")
		(net "SAS_BLAD1_RX6_P")
	)
	(segment
		(start 173.535594 -21.262594)
		(end 173.53534 -21.262594)
		(width 0.1778)
		(layer "B.Cu")
		(net "SAS_BLAD1_RX6_P")
	)
	(segment
		(start 174.23892 -26.048716)
		(end 174.23892 -25.515316)
		(width 0.1778)
		(layer "B.Cu")
		(net "SAS_BLAD1_RX6_P")
	)
	(segment
		(start 173.858428 -27.967178)
		(end 173.685708 -27.794458)
		(width 0.1778)
		(layer "B.Cu")
		(net "SAS_BLAD1_RX6_P")
	)
	(segment
		(start 173.858428 -31.298134)
		(end 173.858428 -30.764734)
		(width 0.1778)
		(layer "B.Cu")
		(net "SAS_BLAD1_RX6_P")
	)
	(segment
		(start 173.53534 -21.262594)
		(end 173.53534 -21.262086)
		(width 0.1778)
		(layer "B.Cu")
		(net "SAS_BLAD1_RX6_P")
	)
	(segment
		(start 174.0662 -24.795226)
		(end 174.23892 -24.622506)
		(width 0.1778)
		(layer "B.Cu")
		(net "SAS_BLAD1_RX6_P")
	)
	(segment
		(start 174.23892 -25.515316)
		(end 174.0662 -25.342596)
		(width 0.1778)
		(layer "B.Cu")
		(net "SAS_BLAD1_RX6_P")
	)
	(segment
		(start 174.23892 -24.089106)
		(end 174.0662 -23.916386)
		(width 0.1778)
		(layer "B.Cu")
		(net "SAS_BLAD1_RX6_P")
	)
	(segment
		(start 173.685708 -32.45866)
		(end 173.685708 -31.470854)
		(width 0.1778)
		(layer "B.Cu")
		(net "SAS_BLAD1_RX6_P")
	)
	(arc
		(start 173.762162 -21.543772)
		(mid 173.71527 -21.456063)
		(end 173.65218 -21.37918)
		(width 0.1778)
		(layer "B.Cu")
		(net "SAS_BLAD1_RX6_P")
	)
	(arc
		(start 173.685708 -27.433524)
		(mid 173.724392 -27.239135)
		(end 173.834552 -27.074368)
		(width 0.1778)
		(layer "B.Cu")
		(net "SAS_BLAD1_RX6_P")
	)
	(arc
		(start 167.906954 -6.979666)
		(mid 167.73531 -6.864943)
		(end 167.532812 -6.824726)
		(width 0.1778)
		(layer "B.Cu")
		(net "SAS_BLAD1_RX6_P")
	)
	(arc
		(start 174.0662 -22.378162)
		(mid 174.065563 -22.35273)
		(end 174.06366 -22.327362)
		(width 0.1778)
		(layer "B.Cu")
		(net "SAS_BLAD1_RX6_P")
	)
	(arc
		(start 173.917356 -26.991564)
		(mid 174.027514 -26.826796)
		(end 174.0662 -26.632408)
		(width 0.1778)
		(layer "B.Cu")
		(net "SAS_BLAD1_RX6_P")
	)
	(arc
		(start 168.0718 -7.370572)
		(mid 168.030148 -7.161642)
		(end 167.91178 -6.984492)
		(width 0.1778)
		(layer "B.Cu")
		(net "SAS_BLAD1_RX6_P")
	)
	(segment
		(start 173.084998 -28.4099)
		(end 173.084998 -29.50083)
		(width 0.1778)
		(layer "F.Cu")
		(net "SAS_BLAD1_RX6_N")
	)
	(segment
		(start 173.309788 -29.72562)
		(end 173.309788 -32.48406)
		(width 0.1778)
		(layer "F.Cu")
		(net "SAS_BLAD1_RX6_N")
	)
	(segment
		(start 173.309788 -32.48406)
		(end 172.875448 -32.9184)
		(width 0.1778)
		(layer "F.Cu")
		(net "SAS_BLAD1_RX6_N")
	)
	(segment
		(start 173.084998 -29.50083)
		(end 173.309788 -29.72562)
		(width 0.1778)
		(layer "F.Cu")
		(net "SAS_BLAD1_RX6_N")
	)
	(via
		(at 172.875448 -32.9184)
		(size 0.508)
		(drill 0.254)
		(layers "F.Cu" "B.Cu")
		(net "SAS_BLAD1_RX6_N")
	)
	(segment
		(start 167.82796 -14.458696)
		(end 167.730678 -14.05128)
		(width 0.1778)
		(layer "B.Cu")
		(net "SAS_BLAD1_RX6_N")
	)
	(segment
		(start 167.730678 -14.05128)
		(end 167.72128 -13.97)
		(width 0.1778)
		(layer "B.Cu")
		(net "SAS_BLAD1_RX6_N")
	)
	(segment
		(start 173.335188 -32.45866)
		(end 173.335188 -27.433524)
		(width 0.1778)
		(layer "B.Cu")
		(net "SAS_BLAD1_RX6_N")
	)
	(segment
		(start 173.71568 -26.632408)
		(end 173.71568 -22.378162)
		(width 0.1778)
		(layer "B.Cu")
		(net "SAS_BLAD1_RX6_N")
	)
	(segment
		(start 167.72128 -13.97)
		(end 167.72128 -7.370826)
		(width 0.1778)
		(layer "B.Cu")
		(net "SAS_BLAD1_RX6_N")
	)
	(segment
		(start 167.074088 -7.175246)
		(end 166.889938 -7.359396)
		(width 0.1778)
		(layer "B.Cu")
		(net "SAS_BLAD1_RX6_N")
	)
	(segment
		(start 173.703742 -22.317964)
		(end 173.438312 -21.678138)
		(width 0.1778)
		(layer "B.Cu")
		(net "SAS_BLAD1_RX6_N")
	)
	(segment
		(start 166.889938 -7.359396)
		(end 166.889938 -7.70001)
		(width 0.1778)
		(layer "B.Cu")
		(net "SAS_BLAD1_RX6_N")
	)
	(segment
		(start 167.998648 -15.173706)
		(end 167.82796 -14.458696)
		(width 0.1778)
		(layer "B.Cu")
		(net "SAS_BLAD1_RX6_N")
	)
	(segment
		(start 173.586648 -26.826464)
		(end 173.669452 -26.74366)
		(width 0.1778)
		(layer "B.Cu")
		(net "SAS_BLAD1_RX6_N")
	)
	(segment
		(start 167.663876 -7.232396)
		(end 167.65905 -7.22757)
		(width 0.1778)
		(layer "B.Cu")
		(net "SAS_BLAD1_RX6_N")
	)
	(segment
		(start 167.532812 -7.175246)
		(end 167.074088 -7.175246)
		(width 0.1778)
		(layer "B.Cu")
		(net "SAS_BLAD1_RX6_N")
	)
	(segment
		(start 168.717976 -16.92148)
		(end 168.007284 -15.200376)
		(width 0.1778)
		(layer "B.Cu")
		(net "SAS_BLAD1_RX6_N")
	)
	(segment
		(start 172.875448 -32.9184)
		(end 173.335188 -32.45866)
		(width 0.1778)
		(layer "B.Cu")
		(net "SAS_BLAD1_RX6_N")
	)
	(segment
		(start 173.404276 -21.627084)
		(end 168.756584 -16.979392)
		(width 0.1778)
		(layer "B.Cu")
		(net "SAS_BLAD1_RX6_N")
	)
	(arc
		(start 167.65905 -7.22757)
		(mid 167.601145 -7.188846)
		(end 167.532812 -7.175246)
		(width 0.1778)
		(layer "B.Cu")
		(net "SAS_BLAD1_RX6_N")
	)
	(arc
		(start 173.714918 -22.362414)
		(mid 173.710959 -22.339779)
		(end 173.703742 -22.317964)
		(width 0.1778)
		(layer "B.Cu")
		(net "SAS_BLAD1_RX6_N")
	)
	(arc
		(start 173.335188 -27.433524)
		(mid 173.400539 -27.104983)
		(end 173.586648 -26.826464)
		(width 0.1778)
		(layer "B.Cu")
		(net "SAS_BLAD1_RX6_N")
	)
	(arc
		(start 168.007284 -15.200376)
		(mid 168.002449 -15.187209)
		(end 167.998648 -15.173706)
		(width 0.1778)
		(layer "B.Cu")
		(net "SAS_BLAD1_RX6_N")
	)
	(arc
		(start 173.438312 -21.678138)
		(mid 173.423799 -21.650942)
		(end 173.404276 -21.627084)
		(width 0.1778)
		(layer "B.Cu")
		(net "SAS_BLAD1_RX6_N")
	)
	(arc
		(start 168.756584 -16.979392)
		(mid 168.734406 -16.95235)
		(end 168.717976 -16.92148)
		(width 0.1778)
		(layer "B.Cu")
		(net "SAS_BLAD1_RX6_N")
	)
	(arc
		(start 173.71568 -22.378162)
		(mid 173.715495 -22.370279)
		(end 173.714918 -22.362414)
		(width 0.1778)
		(layer "B.Cu")
		(net "SAS_BLAD1_RX6_N")
	)
	(arc
		(start 167.72128 -7.370826)
		(mid 167.706358 -7.295898)
		(end 167.663876 -7.232396)
		(width 0.1778)
		(layer "B.Cu")
		(net "SAS_BLAD1_RX6_N")
	)
	(arc
		(start 173.669452 -26.74366)
		(mid 173.703665 -26.692646)
		(end 173.71568 -26.632408)
		(width 0.1778)
		(layer "B.Cu")
		(net "SAS_BLAD1_RX6_N")
	)
	(segment
		(start 192.6844 -31.22168)
		(end 192.6844 -29.711396)
		(width 0.1778)
		(layer "F.Cu")
		(net "SAS_BLAD1_RX2_P")
	)
	(segment
		(start 192.6844 -29.711396)
		(end 192.894966 -29.50083)
		(width 0.1778)
		(layer "F.Cu")
		(net "SAS_BLAD1_RX2_P")
	)
	(segment
		(start 192.894966 -29.50083)
		(end 192.894966 -28.4099)
		(width 0.1778)
		(layer "F.Cu")
		(net "SAS_BLAD1_RX2_P")
	)
	(segment
		(start 193.14414 -31.68142)
		(end 192.6844 -31.22168)
		(width 0.1778)
		(layer "F.Cu")
		(net "SAS_BLAD1_RX2_P")
	)
	(via
		(at 193.14414 -31.68142)
		(size 0.508)
		(drill 0.254)
		(layers "F.Cu" "B.Cu")
		(net "SAS_BLAD1_RX2_P")
	)
	(segment
		(start 189.317122 -32.03702)
		(end 188.778134 -31.671768)
		(width 0.1524)
		(layer "In5.Cu")
		(net "SAS_BLAD1_RX2_P")
	)
	(segment
		(start 172.691298 -12.296902)
		(end 172.889926 -12.098274)
		(width 0.1524)
		(layer "In5.Cu")
		(net "SAS_BLAD1_RX2_P")
	)
	(segment
		(start 180.436012 -20.73783)
		(end 177.90795 -18.649188)
		(width 0.1524)
		(layer "In5.Cu")
		(net "SAS_BLAD1_RX2_P")
	)
	(segment
		(start 191.288416 -32.874458)
		(end 189.479936 -32.12465)
		(width 0.1524)
		(layer "In5.Cu")
		(net "SAS_BLAD1_RX2_P")
	)
	(segment
		(start 172.889926 -12.098274)
		(end 172.889926 -11.800078)
		(width 0.1524)
		(layer "In5.Cu")
		(net "SAS_BLAD1_RX2_P")
	)
	(segment
		(start 192.118488 -32.9438)
		(end 191.638936 -32.9438)
		(width 0.1524)
		(layer "In5.Cu")
		(net "SAS_BLAD1_RX2_P")
	)
	(segment
		(start 188.101732 -30.993842)
		(end 187.50661 -30.100778)
		(width 0.1524)
		(layer "In5.Cu")
		(net "SAS_BLAD1_RX2_P")
	)
	(segment
		(start 187.2996 -29.536136)
		(end 187.2996 -29.442918)
		(width 0.1524)
		(layer "In5.Cu")
		(net "SAS_BLAD1_RX2_P")
	)
	(segment
		(start 171.737274 -14.120876)
		(end 171.639992 -13.885418)
		(width 0.1524)
		(layer "In5.Cu")
		(net "SAS_BLAD1_RX2_P")
	)
	(segment
		(start 173.29277 -15.676372)
		(end 171.737274 -14.120876)
		(width 0.1524)
		(layer "In5.Cu")
		(net "SAS_BLAD1_RX2_P")
	)
	(segment
		(start 187.422536 -29.943552)
		(end 187.34151 -29.747972)
		(width 0.1524)
		(layer "In5.Cu")
		(net "SAS_BLAD1_RX2_P")
	)
	(segment
		(start 171.639992 -13.885418)
		(end 171.639992 -13.06703)
		(width 0.1524)
		(layer "In5.Cu")
		(net "SAS_BLAD1_RX2_P")
	)
	(segment
		(start 193.14414 -31.68142)
		(end 192.71234 -32.11322)
		(width 0.1524)
		(layer "In5.Cu")
		(net "SAS_BLAD1_RX2_P")
	)
	(segment
		(start 177.904648 -18.646394)
		(end 177.901346 -18.6436)
		(width 0.1524)
		(layer "In5.Cu")
		(net "SAS_BLAD1_RX2_P")
	)
	(segment
		(start 175.8442 -16.8402)
		(end 173.29277 -15.676372)
		(width 0.1524)
		(layer "In5.Cu")
		(net "SAS_BLAD1_RX2_P")
	)
	(segment
		(start 187.291726 -29.404056)
		(end 186.017662 -26.329386)
		(width 0.1524)
		(layer "In5.Cu")
		(net "SAS_BLAD1_RX2_P")
	)
	(segment
		(start 172.41012 -12.296902)
		(end 172.691298 -12.296902)
		(width 0.1524)
		(layer "In5.Cu")
		(net "SAS_BLAD1_RX2_P")
	)
	(segment
		(start 192.563496 -32.709104)
		(end 192.477644 -32.794956)
		(width 0.1524)
		(layer "In5.Cu")
		(net "SAS_BLAD1_RX2_P")
	)
	(segment
		(start 188.644022 -31.561278)
		(end 188.216032 -31.133288)
		(width 0.1524)
		(layer "In5.Cu")
		(net "SAS_BLAD1_RX2_P")
	)
	(segment
		(start 177.9016 -18.6436)
		(end 175.8442 -16.8402)
		(width 0.1524)
		(layer "In5.Cu")
		(net "SAS_BLAD1_RX2_P")
	)
	(segment
		(start 177.901346 -18.6436)
		(end 177.9016 -18.6436)
		(width 0.1524)
		(layer "In5.Cu")
		(net "SAS_BLAD1_RX2_P")
	)
	(segment
		(start 192.71234 -32.11322)
		(end 192.71234 -32.349948)
		(width 0.1524)
		(layer "In5.Cu")
		(net "SAS_BLAD1_RX2_P")
	)
	(segment
		(start 185.995564 -26.296366)
		(end 180.44668 -20.747482)
		(width 0.1524)
		(layer "In5.Cu")
		(net "SAS_BLAD1_RX2_P")
	)
	(arc
		(start 188.216032 -31.133288)
		(mid 188.155434 -31.066391)
		(end 188.101732 -30.993842)
		(width 0.1524)
		(layer "In5.Cu")
		(net "SAS_BLAD1_RX2_P")
	)
	(arc
		(start 188.778134 -31.671768)
		(mid 188.708445 -31.619718)
		(end 188.644022 -31.561278)
		(width 0.1524)
		(layer "In5.Cu")
		(net "SAS_BLAD1_RX2_P")
	)
	(arc
		(start 187.34151 -29.747972)
		(mid 187.310156 -29.644113)
		(end 187.2996 -29.536136)
		(width 0.1524)
		(layer "In5.Cu")
		(net "SAS_BLAD1_RX2_P")
	)
	(arc
		(start 192.71234 -32.349948)
		(mid 192.673656 -32.544337)
		(end 192.563496 -32.709104)
		(width 0.1524)
		(layer "In5.Cu")
		(net "SAS_BLAD1_RX2_P")
	)
	(arc
		(start 191.638936 -32.9438)
		(mid 191.460252 -32.92643)
		(end 191.288416 -32.874458)
		(width 0.1524)
		(layer "In5.Cu")
		(net "SAS_BLAD1_RX2_P")
	)
	(arc
		(start 180.44668 -20.747482)
		(mid 180.441462 -20.742528)
		(end 180.436012 -20.73783)
		(width 0.1524)
		(layer "In5.Cu")
		(net "SAS_BLAD1_RX2_P")
	)
	(arc
		(start 171.639992 -13.06703)
		(mid 171.698683 -12.772149)
		(end 171.865798 -12.5222)
		(width 0.1524)
		(layer "In5.Cu")
		(net "SAS_BLAD1_RX2_P")
	)
	(arc
		(start 189.479936 -32.12465)
		(mid 189.396311 -32.084957)
		(end 189.317122 -32.03702)
		(width 0.1524)
		(layer "In5.Cu")
		(net "SAS_BLAD1_RX2_P")
	)
	(arc
		(start 186.017662 -26.329386)
		(mid 186.008258 -26.311773)
		(end 185.995564 -26.296366)
		(width 0.1524)
		(layer "In5.Cu")
		(net "SAS_BLAD1_RX2_P")
	)
	(arc
		(start 171.865798 -12.5222)
		(mid 172.115564 -12.355438)
		(end 172.41012 -12.296902)
		(width 0.1524)
		(layer "In5.Cu")
		(net "SAS_BLAD1_RX2_P")
	)
	(arc
		(start 187.2996 -29.442918)
		(mid 187.297597 -29.423093)
		(end 187.291726 -29.404056)
		(width 0.1524)
		(layer "In5.Cu")
		(net "SAS_BLAD1_RX2_P")
	)
	(arc
		(start 177.90795 -18.649188)
		(mid 177.90629 -18.647802)
		(end 177.904648 -18.646394)
		(width 0.1524)
		(layer "In5.Cu")
		(net "SAS_BLAD1_RX2_P")
	)
	(arc
		(start 187.50661 -30.100778)
		(mid 187.460732 -30.024219)
		(end 187.422536 -29.943552)
		(width 0.1524)
		(layer "In5.Cu")
		(net "SAS_BLAD1_RX2_P")
	)
	(arc
		(start 192.477644 -32.794956)
		(mid 192.312876 -32.905114)
		(end 192.118488 -32.9438)
		(width 0.1524)
		(layer "In5.Cu")
		(net "SAS_BLAD1_RX2_P")
	)
	(segment
		(start 192.719706 -24.761952)
		(end 192.494916 -24.986742)
		(width 0.1778)
		(layer "F.Cu")
		(net "SAS_BLAD1_TX2_N")
	)
	(segment
		(start 192.494916 -24.986742)
		(end 192.494916 -25.899872)
		(width 0.1778)
		(layer "F.Cu")
		(net "SAS_BLAD1_TX2_N")
	)
	(segment
		(start 192.259966 -18.5166)
		(end 192.719706 -18.97634)
		(width 0.1778)
		(layer "F.Cu")
		(net "SAS_BLAD1_TX2_N")
	)
	(segment
		(start 192.719706 -18.97634)
		(end 192.719706 -24.761952)
		(width 0.1778)
		(layer "F.Cu")
		(net "SAS_BLAD1_TX2_N")
	)
	(via
		(at 192.259966 -18.5166)
		(size 0.508)
		(drill 0.254)
		(layers "F.Cu" "B.Cu")
		(net "SAS_BLAD1_TX2_N")
	)
	(segment
		(start 175.386746 -11.40333)
		(end 174.889922 -11.900154)
		(width 0.1524)
		(layer "In5.Cu")
		(net "SAS_BLAD1_TX2_N")
	)
	(segment
		(start 192.542922 -17.257522)
		(end 186.837574 -11.552174)
		(width 0.1524)
		(layer "In5.Cu")
		(net "SAS_BLAD1_TX2_N")
	)
	(segment
		(start 192.259966 -18.5166)
		(end 192.691766 -18.0848)
		(width 0.1524)
		(layer "In5.Cu")
		(net "SAS_BLAD1_TX2_N")
	)
	(segment
		(start 192.691766 -18.0848)
		(end 192.691766 -17.616678)
		(width 0.1524)
		(layer "In5.Cu")
		(net "SAS_BLAD1_TX2_N")
	)
	(segment
		(start 186.478418 -11.40333)
		(end 175.386746 -11.40333)
		(width 0.1524)
		(layer "In5.Cu")
		(net "SAS_BLAD1_TX2_N")
	)
	(arc
		(start 186.837574 -11.552174)
		(mid 186.672806 -11.442016)
		(end 186.478418 -11.40333)
		(width 0.1524)
		(layer "In5.Cu")
		(net "SAS_BLAD1_TX2_N")
	)
	(arc
		(start 192.691766 -17.616678)
		(mid 192.653082 -17.422289)
		(end 192.542922 -17.257522)
		(width 0.1524)
		(layer "In5.Cu")
		(net "SAS_BLAD1_TX2_N")
	)
	(segment
		(start 193.070226 -18.97634)
		(end 193.070226 -24.761952)
		(width 0.1778)
		(layer "F.Cu")
		(net "SAS_BLAD1_TX2_P")
	)
	(segment
		(start 193.070226 -24.761952)
		(end 193.295016 -24.986742)
		(width 0.1778)
		(layer "F.Cu")
		(net "SAS_BLAD1_TX2_P")
	)
	(segment
		(start 193.295016 -24.986742)
		(end 193.295016 -25.899872)
		(width 0.1778)
		(layer "F.Cu")
		(net "SAS_BLAD1_TX2_P")
	)
	(segment
		(start 193.529966 -18.5166)
		(end 193.070226 -18.97634)
		(width 0.1778)
		(layer "F.Cu")
		(net "SAS_BLAD1_TX2_P")
	)
	(via
		(at 193.529966 -18.5166)
		(size 0.508)
		(drill 0.254)
		(layers "F.Cu" "B.Cu")
		(net "SAS_BLAD1_TX2_P")
	)
	(segment
		(start 181.561994 -10.99693)
		(end 181.104794 -10.99693)
		(width 0.1524)
		(layer "In5.Cu")
		(net "SAS_BLAD1_TX2_P")
	)
	(segment
		(start 179.661566 -10.8204)
		(end 179.204366 -10.8204)
		(width 0.1524)
		(layer "In5.Cu")
		(net "SAS_BLAD1_TX2_P")
	)
	(segment
		(start 179.837842 -10.99693)
		(end 179.661566 -10.8204)
		(width 0.1524)
		(layer "In5.Cu")
		(net "SAS_BLAD1_TX2_P")
	)
	(segment
		(start 182.371746 -10.99693)
		(end 182.19547 -10.8204)
		(width 0.1524)
		(layer "In5.Cu")
		(net "SAS_BLAD1_TX2_P")
	)
	(segment
		(start 192.83045 -16.969994)
		(end 187.125102 -11.2649)
		(width 0.1524)
		(layer "In5.Cu")
		(net "SAS_BLAD1_TX2_P")
	)
	(segment
		(start 181.104794 -10.99693)
		(end 180.928518 -10.8204)
		(width 0.1524)
		(layer "In5.Cu")
		(net "SAS_BLAD1_TX2_P")
	)
	(segment
		(start 193.529966 -18.5166)
		(end 193.098166 -18.0848)
		(width 0.1524)
		(layer "In5.Cu")
		(net "SAS_BLAD1_TX2_P")
	)
	(segment
		(start 179.204366 -10.8204)
		(end 179.02809 -10.99693)
		(width 0.1524)
		(layer "In5.Cu")
		(net "SAS_BLAD1_TX2_P")
	)
	(segment
		(start 180.928518 -10.8204)
		(end 180.471318 -10.8204)
		(width 0.1524)
		(layer "In5.Cu")
		(net "SAS_BLAD1_TX2_P")
	)
	(segment
		(start 175.386746 -10.99693)
		(end 174.889922 -10.500106)
		(width 0.1524)
		(layer "In5.Cu")
		(net "SAS_BLAD1_TX2_P")
	)
	(segment
		(start 186.478418 -10.99693)
		(end 182.371746 -10.99693)
		(width 0.1524)
		(layer "In5.Cu")
		(net "SAS_BLAD1_TX2_P")
	)
	(segment
		(start 180.471318 -10.8204)
		(end 180.295042 -10.99693)
		(width 0.1524)
		(layer "In5.Cu")
		(net "SAS_BLAD1_TX2_P")
	)
	(segment
		(start 182.19547 -10.8204)
		(end 181.73827 -10.8204)
		(width 0.1524)
		(layer "In5.Cu")
		(net "SAS_BLAD1_TX2_P")
	)
	(segment
		(start 193.098166 -18.0848)
		(end 193.098166 -17.616678)
		(width 0.1524)
		(layer "In5.Cu")
		(net "SAS_BLAD1_TX2_P")
	)
	(segment
		(start 181.73827 -10.8204)
		(end 181.561994 -10.99693)
		(width 0.1524)
		(layer "In5.Cu")
		(net "SAS_BLAD1_TX2_P")
	)
	(segment
		(start 179.02809 -10.99693)
		(end 175.386746 -10.99693)
		(width 0.1524)
		(layer "In5.Cu")
		(net "SAS_BLAD1_TX2_P")
	)
	(segment
		(start 180.295042 -10.99693)
		(end 179.837842 -10.99693)
		(width 0.1524)
		(layer "In5.Cu")
		(net "SAS_BLAD1_TX2_P")
	)
	(arc
		(start 187.125102 -11.2649)
		(mid 186.828415 -11.066597)
		(end 186.478418 -10.99693)
		(width 0.1524)
		(layer "In5.Cu")
		(net "SAS_BLAD1_TX2_P")
	)
	(arc
		(start 193.098166 -17.616678)
		(mid 193.028629 -17.266713)
		(end 192.83045 -16.969994)
		(width 0.1524)
		(layer "In5.Cu")
		(net "SAS_BLAD1_TX2_P")
	)
	(segment
		(start 173.485048 -25.899872)
		(end 173.485048 -24.808942)
		(width 0.1778)
		(layer "F.Cu")
		(net "SAS_BLAD1_TX6_N")
	)
	(segment
		(start 173.485048 -24.808942)
		(end 173.760638 -24.533352)
		(width 0.1778)
		(layer "F.Cu")
		(net "SAS_BLAD1_TX6_N")
	)
	(segment
		(start 168.2242 -17.82826)
		(end 168.2242 -18.00606)
		(width 0.1778)
		(layer "F.Cu")
		(net "SAS_BLAD1_TX6_N")
	)
	(segment
		(start 168.45026 -17.6022)
		(end 168.2242 -17.82826)
		(width 0.1778)
		(layer "F.Cu")
		(net "SAS_BLAD1_TX6_N")
	)
	(segment
		(start 172.966888 -17.80032)
		(end 171.717208 -17.80032)
		(width 0.1778)
		(layer "F.Cu")
		(net "SAS_BLAD1_TX6_N")
	)
	(segment
		(start 173.760638 -24.533352)
		(end 173.760638 -18.59407)
		(width 0.1778)
		(layer "F.Cu")
		(net "SAS_BLAD1_TX6_N")
	)
	(segment
		(start 171.233592 -17.6022)
		(end 168.45026 -17.6022)
		(width 0.1778)
		(layer "F.Cu")
		(net "SAS_BLAD1_TX6_N")
	)
	(segment
		(start 168.2242 -18.00606)
		(end 168.73474 -18.5166)
		(width 0.1778)
		(layer "F.Cu")
		(net "SAS_BLAD1_TX6_N")
	)
	(segment
		(start 173.71441 -18.482818)
		(end 173.07814 -17.846548)
		(width 0.1778)
		(layer "F.Cu")
		(net "SAS_BLAD1_TX6_N")
	)
	(via
		(at 168.73474 -18.5166)
		(size 0.508)
		(drill 0.254)
		(layers "F.Cu" "B.Cu")
		(net "SAS_BLAD1_TX6_N")
	)
	(arc
		(start 171.717208 -17.80032)
		(mid 171.455894 -17.748872)
		(end 171.233592 -17.6022)
		(width 0.1778)
		(layer "F.Cu")
		(net "SAS_BLAD1_TX6_N")
	)
	(arc
		(start 173.07814 -17.846548)
		(mid 173.027126 -17.812335)
		(end 172.966888 -17.80032)
		(width 0.1778)
		(layer "F.Cu")
		(net "SAS_BLAD1_TX6_N")
	)
	(arc
		(start 173.760638 -18.59407)
		(mid 173.74862 -18.533834)
		(end 173.71441 -18.482818)
		(width 0.1778)
		(layer "F.Cu")
		(net "SAS_BLAD1_TX6_N")
	)
	(segment
		(start 166.782496 -3.003296)
		(end 166.34206 -3.003296)
		(width 0.1524)
		(layer "In5.Cu")
		(net "SAS_BLAD1_TX6_N")
	)
	(segment
		(start 168.296844 -18.083784)
		(end 168.73474 -18.5166)
		(width 0.1524)
		(layer "In5.Cu")
		(net "SAS_BLAD1_TX6_N")
	)
	(segment
		(start 166.2684 -14.971014)
		(end 166.088314 -15.150846)
		(width 0.1524)
		(layer "In5.Cu")
		(net "SAS_BLAD1_TX6_N")
	)
	(segment
		(start 166.118032 -15.55623)
		(end 168.122092 -17.560036)
		(width 0.1524)
		(layer "In5.Cu")
		(net "SAS_BLAD1_TX6_N")
	)
	(segment
		(start 166.2684 -14.513814)
		(end 166.2684 -14.971014)
		(width 0.1524)
		(layer "In5.Cu")
		(net "SAS_BLAD1_TX6_N")
	)
	(segment
		(start 166.088314 -14.333982)
		(end 166.2684 -14.513814)
		(width 0.1524)
		(layer "In5.Cu")
		(net "SAS_BLAD1_TX6_N")
	)
	(segment
		(start 166.889938 -3.110738)
		(end 166.782496 -3.003296)
		(width 0.1524)
		(layer "In5.Cu")
		(net "SAS_BLAD1_TX6_N")
	)
	(segment
		(start 166.889938 -3.50012)
		(end 166.889938 -3.110738)
		(width 0.1524)
		(layer "In5.Cu")
		(net "SAS_BLAD1_TX6_N")
	)
	(segment
		(start 166.088314 -3.257042)
		(end 166.088314 -14.333982)
		(width 0.1524)
		(layer "In5.Cu")
		(net "SAS_BLAD1_TX6_N")
	)
	(segment
		(start 168.30294 -18.0848)
		(end 168.296844 -18.083784)
		(width 0.1524)
		(layer "In5.Cu")
		(net "SAS_BLAD1_TX6_N")
	)
	(segment
		(start 166.088314 -15.150846)
		(end 166.088314 -15.484602)
		(width 0.1524)
		(layer "In5.Cu")
		(net "SAS_BLAD1_TX6_N")
	)
	(arc
		(start 168.30294 -17.99717)
		(mid 168.3045 -18.040985)
		(end 168.30294 -18.0848)
		(width 0.1524)
		(layer "In5.Cu")
		(net "SAS_BLAD1_TX6_N")
	)
	(arc
		(start 168.122092 -17.560036)
		(mid 168.256018 -17.76061)
		(end 168.30294 -17.99717)
		(width 0.1524)
		(layer "In5.Cu")
		(net "SAS_BLAD1_TX6_N")
	)
	(arc
		(start 166.162736 -3.077464)
		(mid 166.10763 -3.159841)
		(end 166.088314 -3.257042)
		(width 0.1524)
		(layer "In5.Cu")
		(net "SAS_BLAD1_TX6_N")
	)
	(arc
		(start 166.088314 -15.484602)
		(mid 166.096044 -15.523371)
		(end 166.118032 -15.55623)
		(width 0.1524)
		(layer "In5.Cu")
		(net "SAS_BLAD1_TX6_N")
	)
	(arc
		(start 166.34206 -3.003296)
		(mid 166.245039 -3.022577)
		(end 166.162736 -3.077464)
		(width 0.1524)
		(layer "In5.Cu")
		(net "SAS_BLAD1_TX6_N")
	)
	(segment
		(start 167.87368 -17.682972)
		(end 167.87368 -18.10766)
		(width 0.1778)
		(layer "F.Cu")
		(net "SAS_BLAD1_TX6_P")
	)
	(segment
		(start 174.285148 -25.899872)
		(end 174.285148 -24.808942)
		(width 0.1778)
		(layer "F.Cu")
		(net "SAS_BLAD1_TX6_P")
	)
	(segment
		(start 174.111158 -24.634952)
		(end 174.111158 -18.59407)
		(width 0.1778)
		(layer "F.Cu")
		(net "SAS_BLAD1_TX6_P")
	)
	(segment
		(start 167.87368 -18.10766)
		(end 167.46474 -18.5166)
		(width 0.1778)
		(layer "F.Cu")
		(net "SAS_BLAD1_TX6_P")
	)
	(segment
		(start 174.285148 -24.808942)
		(end 174.111158 -24.634952)
		(width 0.1778)
		(layer "F.Cu")
		(net "SAS_BLAD1_TX6_P")
	)
	(segment
		(start 168.304972 -17.25168)
		(end 167.87368 -17.682972)
		(width 0.1778)
		(layer "F.Cu")
		(net "SAS_BLAD1_TX6_P")
	)
	(segment
		(start 171.238672 -17.25168)
		(end 168.304972 -17.25168)
		(width 0.1778)
		(layer "F.Cu")
		(net "SAS_BLAD1_TX6_P")
	)
	(segment
		(start 172.966888 -17.4498)
		(end 171.717208 -17.4498)
		(width 0.1778)
		(layer "F.Cu")
		(net "SAS_BLAD1_TX6_P")
	)
	(segment
		(start 173.962314 -18.234914)
		(end 173.326044 -17.598644)
		(width 0.1778)
		(layer "F.Cu")
		(net "SAS_BLAD1_TX6_P")
	)
	(via
		(at 167.46474 -18.5166)
		(size 0.508)
		(drill 0.254)
		(layers "F.Cu" "B.Cu")
		(net "SAS_BLAD1_TX6_P")
	)
	(arc
		(start 173.326044 -17.598644)
		(mid 173.161276 -17.488486)
		(end 172.966888 -17.4498)
		(width 0.1778)
		(layer "F.Cu")
		(net "SAS_BLAD1_TX6_P")
	)
	(arc
		(start 174.111158 -18.59407)
		(mid 174.072474 -18.399681)
		(end 173.962314 -18.234914)
		(width 0.1778)
		(layer "F.Cu")
		(net "SAS_BLAD1_TX6_P")
	)
	(arc
		(start 171.47794 -17.35074)
		(mid 171.368149 -17.277443)
		(end 171.238672 -17.25168)
		(width 0.1778)
		(layer "F.Cu")
		(net "SAS_BLAD1_TX6_P")
	)
	(arc
		(start 171.717208 -17.4498)
		(mid 171.587721 -17.424061)
		(end 171.47794 -17.35074)
		(width 0.1778)
		(layer "F.Cu")
		(net "SAS_BLAD1_TX6_P")
	)
	(segment
		(start 166.889938 -2.477262)
		(end 166.770304 -2.596896)
		(width 0.1524)
		(layer "In5.Cu")
		(net "SAS_BLAD1_TX6_P")
	)
	(segment
		(start 165.681914 -3.257042)
		(end 165.681914 -15.484602)
		(width 0.1524)
		(layer "In5.Cu")
		(net "SAS_BLAD1_TX6_P")
	)
	(segment
		(start 167.834564 -18.146776)
		(end 167.46474 -18.5166)
		(width 0.1524)
		(layer "In5.Cu")
		(net "SAS_BLAD1_TX6_P")
	)
	(segment
		(start 166.889938 -2.100072)
		(end 166.889938 -2.477262)
		(width 0.1524)
		(layer "In5.Cu")
		(net "SAS_BLAD1_TX6_P")
	)
	(segment
		(start 165.830758 -15.843758)
		(end 167.834564 -17.847564)
		(width 0.1524)
		(layer "In5.Cu")
		(net "SAS_BLAD1_TX6_P")
	)
	(segment
		(start 166.770304 -2.596896)
		(end 166.34206 -2.596896)
		(width 0.1524)
		(layer "In5.Cu")
		(net "SAS_BLAD1_TX6_P")
	)
	(arc
		(start 165.875462 -2.789936)
		(mid 165.732211 -3.004232)
		(end 165.681914 -3.257042)
		(width 0.1524)
		(layer "In5.Cu")
		(net "SAS_BLAD1_TX6_P")
	)
	(arc
		(start 165.681914 -15.484602)
		(mid 165.720598 -15.678991)
		(end 165.830758 -15.843758)
		(width 0.1524)
		(layer "In5.Cu")
		(net "SAS_BLAD1_TX6_P")
	)
	(arc
		(start 166.34206 -2.596896)
		(mid 166.089585 -2.647063)
		(end 165.875462 -2.789936)
		(width 0.1524)
		(layer "In5.Cu")
		(net "SAS_BLAD1_TX6_P")
	)
	(arc
		(start 167.834564 -17.847564)
		(mid 167.896533 -17.99717)
		(end 167.834564 -18.146776)
		(width 0.1524)
		(layer "In5.Cu")
		(net "SAS_BLAD1_TX6_P")
	)
	(segment
		(start 176.285144 -29.50083)
		(end 176.285144 -28.4099)
		(width 0.1778)
		(layer "F.Cu")
		(net "SAS_BLAD1_RX5_P")
	)
	(segment
		(start 176.520094 -30.99562)
		(end 176.060354 -30.53588)
		(width 0.1778)
		(layer "F.Cu")
		(net "SAS_BLAD1_RX5_P")
	)
	(segment
		(start 176.060354 -30.53588)
		(end 176.060354 -29.72562)
		(width 0.1778)
		(layer "F.Cu")
		(net "SAS_BLAD1_RX5_P")
	)
	(segment
		(start 176.060354 -29.72562)
		(end 176.285144 -29.50083)
		(width 0.1778)
		(layer "F.Cu")
		(net "SAS_BLAD1_RX5_P")
	)
	(via
		(at 176.520094 -30.99562)
		(size 0.508)
		(drill 0.254)
		(layers "F.Cu" "B.Cu")
		(net "SAS_BLAD1_RX5_P")
	)
	(segment
		(start 173.757082 -23.354284)
		(end 170.57497 -20.172172)
		(width 0.1524)
		(layer "In5.Cu")
		(net "SAS_BLAD1_RX5_P")
	)
	(segment
		(start 173.4058 -30.752034)
		(end 173.4058 -26.143712)
		(width 0.1524)
		(layer "In5.Cu")
		(net "SAS_BLAD1_RX5_P")
	)
	(segment
		(start 170.307 -19.525488)
		(end 170.307 -17.710912)
		(width 0.1524)
		(layer "In5.Cu")
		(net "SAS_BLAD1_RX5_P")
	)
	(segment
		(start 173.7868 -25.342088)
		(end 173.7868 -23.425912)
		(width 0.1524)
		(layer "In5.Cu")
		(net "SAS_BLAD1_RX5_P")
	)
	(segment
		(start 176.520094 -30.99562)
		(end 176.088294 -31.42742)
		(width 0.1524)
		(layer "In5.Cu")
		(net "SAS_BLAD1_RX5_P")
	)
	(segment
		(start 167.64 -14.623288)
		(end 167.64 -13.088112)
		(width 0.1524)
		(layer "In5.Cu")
		(net "SAS_BLAD1_RX5_P")
	)
	(segment
		(start 170.277282 -17.639284)
		(end 167.90797 -15.269972)
		(width 0.1524)
		(layer "In5.Cu")
		(net "SAS_BLAD1_RX5_P")
	)
	(segment
		(start 174.729902 -32.286956)
		(end 174.151544 -31.708598)
		(width 0.1524)
		(layer "In5.Cu")
		(net "SAS_BLAD1_RX5_P")
	)
	(segment
		(start 175.93945 -32.11195)
		(end 175.764444 -32.286956)
		(width 0.1524)
		(layer "In5.Cu")
		(net "SAS_BLAD1_RX5_P")
	)
	(segment
		(start 175.405288 -32.4358)
		(end 175.089312 -32.4358)
		(width 0.1524)
		(layer "In5.Cu")
		(net "SAS_BLAD1_RX5_P")
	)
	(segment
		(start 167.871394 -12.52855)
		(end 167.871902 -12.528042)
		(width 0.1524)
		(layer "In5.Cu")
		(net "SAS_BLAD1_RX5_P")
	)
	(segment
		(start 168.889934 -12.110466)
		(end 168.889934 -11.800078)
		(width 0.1524)
		(layer "In5.Cu")
		(net "SAS_BLAD1_RX5_P")
	)
	(segment
		(start 168.703498 -12.296902)
		(end 168.889934 -12.110466)
		(width 0.1524)
		(layer "In5.Cu")
		(net "SAS_BLAD1_RX5_P")
	)
	(segment
		(start 168.430702 -12.296902)
		(end 168.703498 -12.296902)
		(width 0.1524)
		(layer "In5.Cu")
		(net "SAS_BLAD1_RX5_P")
	)
	(segment
		(start 176.088294 -31.42742)
		(end 176.088294 -31.752794)
		(width 0.1524)
		(layer "In5.Cu")
		(net "SAS_BLAD1_RX5_P")
	)
	(segment
		(start 174.151544 -31.708598)
		(end 173.564042 -31.120334)
		(width 0.1524)
		(layer "In5.Cu")
		(net "SAS_BLAD1_RX5_P")
	)
	(segment
		(start 173.673516 -25.497028)
		(end 173.757082 -25.413716)
		(width 0.1524)
		(layer "In5.Cu")
		(net "SAS_BLAD1_RX5_P")
	)
	(arc
		(start 173.7868 -23.425912)
		(mid 173.77907 -23.387143)
		(end 173.757082 -23.354284)
		(width 0.1524)
		(layer "In5.Cu")
		(net "SAS_BLAD1_RX5_P")
	)
	(arc
		(start 173.757082 -25.413716)
		(mid 173.779094 -25.380867)
		(end 173.7868 -25.342088)
		(width 0.1524)
		(layer "In5.Cu")
		(net "SAS_BLAD1_RX5_P")
	)
	(arc
		(start 173.564042 -31.120334)
		(mid 173.447041 -30.95246)
		(end 173.4058 -30.752034)
		(width 0.1524)
		(layer "In5.Cu")
		(net "SAS_BLAD1_RX5_P")
	)
	(arc
		(start 175.089312 -32.4358)
		(mid 174.894772 -32.397179)
		(end 174.729902 -32.286956)
		(width 0.1524)
		(layer "In5.Cu")
		(net "SAS_BLAD1_RX5_P")
	)
	(arc
		(start 170.57497 -20.172172)
		(mid 170.376667 -19.875485)
		(end 170.307 -19.525488)
		(width 0.1524)
		(layer "In5.Cu")
		(net "SAS_BLAD1_RX5_P")
	)
	(arc
		(start 175.764444 -32.286956)
		(mid 175.599676 -32.397114)
		(end 175.405288 -32.4358)
		(width 0.1524)
		(layer "In5.Cu")
		(net "SAS_BLAD1_RX5_P")
	)
	(arc
		(start 176.088294 -31.752794)
		(mid 176.04961 -31.947183)
		(end 175.93945 -32.11195)
		(width 0.1524)
		(layer "In5.Cu")
		(net "SAS_BLAD1_RX5_P")
	)
	(arc
		(start 167.871902 -12.528042)
		(mid 168.128338 -12.356949)
		(end 168.430702 -12.296902)
		(width 0.1524)
		(layer "In5.Cu")
		(net "SAS_BLAD1_RX5_P")
	)
	(arc
		(start 170.307 -17.710912)
		(mid 170.29927 -17.672143)
		(end 170.277282 -17.639284)
		(width 0.1524)
		(layer "In5.Cu")
		(net "SAS_BLAD1_RX5_P")
	)
	(arc
		(start 173.4058 -26.143712)
		(mid 173.475337 -25.793747)
		(end 173.673516 -25.497028)
		(width 0.1524)
		(layer "In5.Cu")
		(net "SAS_BLAD1_RX5_P")
	)
	(arc
		(start 167.64 -13.088112)
		(mid 167.700042 -12.785319)
		(end 167.871394 -12.52855)
		(width 0.1524)
		(layer "In5.Cu")
		(net "SAS_BLAD1_RX5_P")
	)
	(arc
		(start 167.90797 -15.269972)
		(mid 167.709667 -14.973285)
		(end 167.64 -14.623288)
		(width 0.1524)
		(layer "In5.Cu")
		(net "SAS_BLAD1_RX5_P")
	)
	(segment
		(start 195.295012 -29.494734)
		(end 195.295012 -28.4099)
		(width 0.1778)
		(layer "F.Cu")
		(net "SAS_BLAD1_RX1_P")
	)
	(segment
		(start 195.051934 -30.085792)
		(end 195.051934 -29.737812)
		(width 0.1778)
		(layer "F.Cu")
		(net "SAS_BLAD1_RX1_P")
	)
	(segment
		(start 195.529962 -30.56382)
		(end 195.051934 -30.085792)
		(width 0.1778)
		(layer "F.Cu")
		(net "SAS_BLAD1_RX1_P")
	)
	(segment
		(start 195.051934 -29.737812)
		(end 195.295012 -29.494734)
		(width 0.1778)
		(layer "F.Cu")
		(net "SAS_BLAD1_RX1_P")
	)
	(via
		(at 195.529962 -30.56382)
		(size 0.508)
		(drill 0.254)
		(layers "F.Cu" "B.Cu")
		(net "SAS_BLAD1_RX1_P")
	)
	(segment
		(start 184.365392 -13.423392)
		(end 183.751728 -12.809728)
		(width 0.1778)
		(layer "B.Cu")
		(net "SAS_BLAD1_RX1_P")
	)
	(segment
		(start 185.99531 -15.05331)
		(end 185.99531 -14.808962)
		(width 0.1778)
		(layer "B.Cu")
		(net "SAS_BLAD1_RX1_P")
	)
	(segment
		(start 184.98693 -14.04493)
		(end 184.98693 -13.800836)
		(width 0.1778)
		(layer "B.Cu")
		(net "SAS_BLAD1_RX1_P")
	)
	(segment
		(start 195.529962 -30.56382)
		(end 195.070222 -30.10408)
		(width 0.1778)
		(layer "B.Cu")
		(net "SAS_BLAD1_RX1_P")
	)
	(segment
		(start 184.98693 -13.800836)
		(end 184.60974 -13.423392)
		(width 0.1778)
		(layer "B.Cu")
		(net "SAS_BLAD1_RX1_P")
	)
	(segment
		(start 188.01207 -17.07007)
		(end 188.01207 -16.825722)
		(width 0.1778)
		(layer "B.Cu")
		(net "SAS_BLAD1_RX1_P")
	)
	(segment
		(start 189.02045 -18.07845)
		(end 189.02045 -17.834102)
		(width 0.1778)
		(layer "B.Cu")
		(net "SAS_BLAD1_RX1_P")
	)
	(segment
		(start 177.556414 -6.824726)
		(end 175.414686 -6.824726)
		(width 0.1778)
		(layer "B.Cu")
		(net "SAS_BLAD1_RX1_P")
	)
	(segment
		(start 183.751728 -12.56538)
		(end 183.374538 -12.18819)
		(width 0.1778)
		(layer "B.Cu")
		(net "SAS_BLAD1_RX1_P")
	)
	(segment
		(start 189.02045 -17.834102)
		(end 188.64326 -17.456912)
		(width 0.1778)
		(layer "B.Cu")
		(net "SAS_BLAD1_RX1_P")
	)
	(segment
		(start 183.374538 -12.18819)
		(end 183.13019 -12.18819)
		(width 0.1778)
		(layer "B.Cu")
		(net "SAS_BLAD1_RX1_P")
	)
	(segment
		(start 184.60974 -13.423392)
		(end 184.365392 -13.423392)
		(width 0.1778)
		(layer "B.Cu")
		(net "SAS_BLAD1_RX1_P")
	)
	(segment
		(start 183.751728 -12.809728)
		(end 183.751728 -12.56538)
		(width 0.1778)
		(layer "B.Cu")
		(net "SAS_BLAD1_RX1_P")
	)
	(segment
		(start 175.414686 -6.824726)
		(end 174.889922 -6.299962)
		(width 0.1778)
		(layer "B.Cu")
		(net "SAS_BLAD1_RX1_P")
	)
	(segment
		(start 192.840356 -21.898356)
		(end 189.02045 -18.07845)
		(width 0.1778)
		(layer "B.Cu")
		(net "SAS_BLAD1_RX1_P")
	)
	(segment
		(start 188.398912 -17.456912)
		(end 188.01207 -17.07007)
		(width 0.1778)
		(layer "B.Cu")
		(net "SAS_BLAD1_RX1_P")
	)
	(segment
		(start 185.99531 -14.808962)
		(end 185.61812 -14.431772)
		(width 0.1778)
		(layer "B.Cu")
		(net "SAS_BLAD1_RX1_P")
	)
	(segment
		(start 188.64326 -17.456912)
		(end 188.398912 -17.456912)
		(width 0.1778)
		(layer "B.Cu")
		(net "SAS_BLAD1_RX1_P")
	)
	(segment
		(start 185.61812 -14.431772)
		(end 185.374026 -14.431772)
		(width 0.1778)
		(layer "B.Cu")
		(net "SAS_BLAD1_RX1_P")
	)
	(segment
		(start 194.921378 -26.544778)
		(end 193.138044 -24.761444)
		(width 0.1778)
		(layer "B.Cu")
		(net "SAS_BLAD1_RX1_P")
	)
	(segment
		(start 187.63488 -16.448532)
		(end 187.390786 -16.448532)
		(width 0.1778)
		(layer "B.Cu")
		(net "SAS_BLAD1_RX1_P")
	)
	(segment
		(start 187.00369 -16.06169)
		(end 187.00369 -15.817342)
		(width 0.1778)
		(layer "B.Cu")
		(net "SAS_BLAD1_RX1_P")
	)
	(segment
		(start 186.382152 -15.440152)
		(end 185.99531 -15.05331)
		(width 0.1778)
		(layer "B.Cu")
		(net "SAS_BLAD1_RX1_P")
	)
	(segment
		(start 187.390786 -16.448532)
		(end 187.00369 -16.06169)
		(width 0.1778)
		(layer "B.Cu")
		(net "SAS_BLAD1_RX1_P")
	)
	(segment
		(start 192.9892 -24.402288)
		(end 192.9892 -22.257512)
		(width 0.1778)
		(layer "B.Cu")
		(net "SAS_BLAD1_RX1_P")
	)
	(segment
		(start 195.070222 -30.10408)
		(end 195.070222 -26.903934)
		(width 0.1778)
		(layer "B.Cu")
		(net "SAS_BLAD1_RX1_P")
	)
	(segment
		(start 183.13019 -12.18819)
		(end 177.91557 -6.97357)
		(width 0.1778)
		(layer "B.Cu")
		(net "SAS_BLAD1_RX1_P")
	)
	(segment
		(start 185.374026 -14.431772)
		(end 184.98693 -14.04493)
		(width 0.1778)
		(layer "B.Cu")
		(net "SAS_BLAD1_RX1_P")
	)
	(segment
		(start 186.6265 -15.440152)
		(end 186.382152 -15.440152)
		(width 0.1778)
		(layer "B.Cu")
		(net "SAS_BLAD1_RX1_P")
	)
	(segment
		(start 187.00369 -15.817342)
		(end 186.6265 -15.440152)
		(width 0.1778)
		(layer "B.Cu")
		(net "SAS_BLAD1_RX1_P")
	)
	(segment
		(start 188.01207 -16.825722)
		(end 187.63488 -16.448532)
		(width 0.1778)
		(layer "B.Cu")
		(net "SAS_BLAD1_RX1_P")
	)
	(arc
		(start 177.91557 -6.97357)
		(mid 177.750802 -6.863412)
		(end 177.556414 -6.824726)
		(width 0.1778)
		(layer "B.Cu")
		(net "SAS_BLAD1_RX1_P")
	)
	(arc
		(start 192.9892 -22.257512)
		(mid 192.950516 -22.063123)
		(end 192.840356 -21.898356)
		(width 0.1778)
		(layer "B.Cu")
		(net "SAS_BLAD1_RX1_P")
	)
	(arc
		(start 193.138044 -24.761444)
		(mid 193.027886 -24.596676)
		(end 192.9892 -24.402288)
		(width 0.1778)
		(layer "B.Cu")
		(net "SAS_BLAD1_RX1_P")
	)
	(arc
		(start 195.070222 -26.903934)
		(mid 195.031538 -26.709545)
		(end 194.921378 -26.544778)
		(width 0.1778)
		(layer "B.Cu")
		(net "SAS_BLAD1_RX1_P")
	)
	(segment
		(start 194.259962 -30.56382)
		(end 194.701414 -30.122368)
		(width 0.1778)
		(layer "F.Cu")
		(net "SAS_BLAD1_RX1_N")
	)
	(segment
		(start 194.701414 -29.701236)
		(end 194.494912 -29.494734)
		(width 0.1778)
		(layer "F.Cu")
		(net "SAS_BLAD1_RX1_N")
	)
	(segment
		(start 194.701414 -30.122368)
		(end 194.701414 -29.701236)
		(width 0.1778)
		(layer "F.Cu")
		(net "SAS_BLAD1_RX1_N")
	)
	(segment
		(start 194.494912 -29.494734)
		(end 194.494912 -28.4099)
		(width 0.1778)
		(layer "F.Cu")
		(net "SAS_BLAD1_RX1_N")
	)
	(via
		(at 194.259962 -30.56382)
		(size 0.508)
		(drill 0.254)
		(layers "F.Cu" "B.Cu")
		(net "SAS_BLAD1_RX1_N")
	)
	(segment
		(start 192.63868 -24.402288)
		(end 192.63868 -22.257512)
		(width 0.1778)
		(layer "B.Cu")
		(net "SAS_BLAD1_RX1_N")
	)
	(segment
		(start 194.673474 -26.792682)
		(end 192.89014 -25.009348)
		(width 0.1778)
		(layer "B.Cu")
		(net "SAS_BLAD1_RX1_N")
	)
	(segment
		(start 194.719702 -30.10408)
		(end 194.719702 -26.903934)
		(width 0.1778)
		(layer "B.Cu")
		(net "SAS_BLAD1_RX1_N")
	)
	(segment
		(start 194.259962 -30.56382)
		(end 194.719702 -30.10408)
		(width 0.1778)
		(layer "B.Cu")
		(net "SAS_BLAD1_RX1_N")
	)
	(segment
		(start 192.592452 -22.14626)
		(end 177.667666 -7.221474)
		(width 0.1778)
		(layer "B.Cu")
		(net "SAS_BLAD1_RX1_N")
	)
	(segment
		(start 175.414686 -7.175246)
		(end 174.889922 -7.70001)
		(width 0.1778)
		(layer "B.Cu")
		(net "SAS_BLAD1_RX1_N")
	)
	(segment
		(start 177.556414 -7.175246)
		(end 175.414686 -7.175246)
		(width 0.1778)
		(layer "B.Cu")
		(net "SAS_BLAD1_RX1_N")
	)
	(arc
		(start 192.89014 -25.009348)
		(mid 192.704038 -24.730827)
		(end 192.63868 -24.402288)
		(width 0.1778)
		(layer "B.Cu")
		(net "SAS_BLAD1_RX1_N")
	)
	(arc
		(start 177.667666 -7.221474)
		(mid 177.616652 -7.187261)
		(end 177.556414 -7.175246)
		(width 0.1778)
		(layer "B.Cu")
		(net "SAS_BLAD1_RX1_N")
	)
	(arc
		(start 192.63868 -22.257512)
		(mid 192.626662 -22.197276)
		(end 192.592452 -22.14626)
		(width 0.1778)
		(layer "B.Cu")
		(net "SAS_BLAD1_RX1_N")
	)
	(arc
		(start 194.719702 -26.903934)
		(mid 194.707684 -26.843698)
		(end 194.673474 -26.792682)
		(width 0.1778)
		(layer "B.Cu")
		(net "SAS_BLAD1_RX1_N")
	)
	(segment
		(start 175.250094 -30.99562)
		(end 175.709834 -30.53588)
		(width 0.1778)
		(layer "F.Cu")
		(net "SAS_BLAD1_RX5_N")
	)
	(segment
		(start 175.709834 -30.53588)
		(end 175.709834 -29.72562)
		(width 0.1778)
		(layer "F.Cu")
		(net "SAS_BLAD1_RX5_N")
	)
	(segment
		(start 175.709834 -29.72562)
		(end 175.485044 -29.50083)
		(width 0.1778)
		(layer "F.Cu")
		(net "SAS_BLAD1_RX5_N")
	)
	(segment
		(start 175.485044 -29.50083)
		(end 175.485044 -28.4099)
		(width 0.1778)
		(layer "F.Cu")
		(net "SAS_BLAD1_RX5_N")
	)
	(via
		(at 175.250094 -30.99562)
		(size 0.508)
		(drill 0.254)
		(layers "F.Cu" "B.Cu")
		(net "SAS_BLAD1_RX5_N")
	)
	(segment
		(start 175.681894 -31.42742)
		(end 175.681894 -31.752794)
		(width 0.1524)
		(layer "In5.Cu")
		(net "SAS_BLAD1_RX5_N")
	)
	(segment
		(start 173.961044 -25.784556)
		(end 174.044356 -25.701244)
		(width 0.1524)
		(layer "In5.Cu")
		(net "SAS_BLAD1_RX5_N")
	)
	(segment
		(start 168.430702 -12.703302)
		(end 168.735502 -12.703302)
		(width 0.1524)
		(layer "In5.Cu")
		(net "SAS_BLAD1_RX5_N")
	)
	(segment
		(start 171.545758 -20.568158)
		(end 170.862244 -19.884644)
		(width 0.1524)
		(layer "In5.Cu")
		(net "SAS_BLAD1_RX5_N")
	)
	(segment
		(start 173.99 -28.045156)
		(end 173.8122 -27.867356)
		(width 0.1524)
		(layer "In5.Cu")
		(net "SAS_BLAD1_RX5_N")
	)
	(segment
		(start 174.044356 -23.066756)
		(end 173.848268 -22.870668)
		(width 0.1524)
		(layer "In5.Cu")
		(net "SAS_BLAD1_RX5_N")
	)
	(segment
		(start 173.99 -28.451556)
		(end 173.99 -28.045156)
		(width 0.1524)
		(layer "In5.Cu")
		(net "SAS_BLAD1_RX5_N")
	)
	(segment
		(start 173.99 -29.670756)
		(end 173.99 -29.264356)
		(width 0.1524)
		(layer "In5.Cu")
		(net "SAS_BLAD1_RX5_N")
	)
	(segment
		(start 175.01743 -31.999682)
		(end 174.78375 -31.765748)
		(width 0.1524)
		(layer "In5.Cu")
		(net "SAS_BLAD1_RX5_N")
	)
	(segment
		(start 173.8122 -29.086556)
		(end 173.8122 -28.629356)
		(width 0.1524)
		(layer "In5.Cu")
		(net "SAS_BLAD1_RX5_N")
	)
	(segment
		(start 174.439072 -31.421324)
		(end 173.84776 -30.82925)
		(width 0.1524)
		(layer "In5.Cu")
		(net "SAS_BLAD1_RX5_N")
	)
	(segment
		(start 168.0464 -14.623288)
		(end 168.0464 -13.087858)
		(width 0.1524)
		(layer "In5.Cu")
		(net "SAS_BLAD1_RX5_N")
	)
	(segment
		(start 173.848268 -22.642068)
		(end 173.524926 -22.318726)
		(width 0.1524)
		(layer "In5.Cu")
		(net "SAS_BLAD1_RX5_N")
	)
	(segment
		(start 173.9646 -26.672032)
		(end 173.8122 -26.519632)
		(width 0.1524)
		(layer "In5.Cu")
		(net "SAS_BLAD1_RX5_N")
	)
	(segment
		(start 173.8122 -26.519632)
		(end 173.8122 -26.143712)
		(width 0.1524)
		(layer "In5.Cu")
		(net "SAS_BLAD1_RX5_N")
	)
	(segment
		(start 173.524926 -22.318726)
		(end 173.296326 -22.318726)
		(width 0.1524)
		(layer "In5.Cu")
		(net "SAS_BLAD1_RX5_N")
	)
	(segment
		(start 173.8122 -28.629356)
		(end 173.99 -28.451556)
		(width 0.1524)
		(layer "In5.Cu")
		(net "SAS_BLAD1_RX5_N")
	)
	(segment
		(start 172.972984 -21.995384)
		(end 172.972984 -21.766784)
		(width 0.1524)
		(layer "In5.Cu")
		(net "SAS_BLAD1_RX5_N")
	)
	(segment
		(start 172.972984 -21.766784)
		(end 172.649642 -21.443442)
		(width 0.1524)
		(layer "In5.Cu")
		(net "SAS_BLAD1_RX5_N")
	)
	(segment
		(start 172.421042 -21.443442)
		(end 172.0977 -21.1201)
		(width 0.1524)
		(layer "In5.Cu")
		(net "SAS_BLAD1_RX5_N")
	)
	(segment
		(start 173.8122 -29.848556)
		(end 173.99 -29.670756)
		(width 0.1524)
		(layer "In5.Cu")
		(net "SAS_BLAD1_RX5_N")
	)
	(segment
		(start 168.735502 -12.703302)
		(end 168.889934 -12.857734)
		(width 0.1524)
		(layer "In5.Cu")
		(net "SAS_BLAD1_RX5_N")
	)
	(segment
		(start 168.158922 -12.815824)
		(end 168.159176 -12.81557)
		(width 0.1524)
		(layer "In5.Cu")
		(net "SAS_BLAD1_RX5_N")
	)
	(segment
		(start 173.99 -29.264356)
		(end 173.8122 -29.086556)
		(width 0.1524)
		(layer "In5.Cu")
		(net "SAS_BLAD1_RX5_N")
	)
	(segment
		(start 174.1932 -25.342088)
		(end 174.1932 -23.425912)
		(width 0.1524)
		(layer "In5.Cu")
		(net "SAS_BLAD1_RX5_N")
	)
	(segment
		(start 173.9646 -27.129232)
		(end 173.9646 -26.672032)
		(width 0.1524)
		(layer "In5.Cu")
		(net "SAS_BLAD1_RX5_N")
	)
	(segment
		(start 172.649642 -21.443442)
		(end 172.421042 -21.443442)
		(width 0.1524)
		(layer "In5.Cu")
		(net "SAS_BLAD1_RX5_N")
	)
	(segment
		(start 171.774358 -20.568158)
		(end 171.545758 -20.568158)
		(width 0.1524)
		(layer "In5.Cu")
		(net "SAS_BLAD1_RX5_N")
	)
	(segment
		(start 173.84776 -30.82925)
		(end 173.843696 -30.82544)
		(width 0.1524)
		(layer "In5.Cu")
		(net "SAS_BLAD1_RX5_N")
	)
	(segment
		(start 172.0977 -21.1201)
		(end 172.0977 -20.8915)
		(width 0.1524)
		(layer "In5.Cu")
		(net "SAS_BLAD1_RX5_N")
	)
	(segment
		(start 173.848268 -22.870668)
		(end 173.848268 -22.642068)
		(width 0.1524)
		(layer "In5.Cu")
		(net "SAS_BLAD1_RX5_N")
	)
	(segment
		(start 168.889934 -12.857734)
		(end 168.889934 -13.200126)
		(width 0.1524)
		(layer "In5.Cu")
		(net "SAS_BLAD1_RX5_N")
	)
	(segment
		(start 175.405288 -32.0294)
		(end 175.089058 -32.0294)
		(width 0.1524)
		(layer "In5.Cu")
		(net "SAS_BLAD1_RX5_N")
	)
	(segment
		(start 172.0977 -20.8915)
		(end 171.774358 -20.568158)
		(width 0.1524)
		(layer "In5.Cu")
		(net "SAS_BLAD1_RX5_N")
	)
	(segment
		(start 173.8122 -27.281632)
		(end 173.9646 -27.129232)
		(width 0.1524)
		(layer "In5.Cu")
		(net "SAS_BLAD1_RX5_N")
	)
	(segment
		(start 170.564556 -17.351756)
		(end 168.195244 -14.982444)
		(width 0.1524)
		(layer "In5.Cu")
		(net "SAS_BLAD1_RX5_N")
	)
	(segment
		(start 175.652176 -31.824422)
		(end 175.476916 -31.999682)
		(width 0.1524)
		(layer "In5.Cu")
		(net "SAS_BLAD1_RX5_N")
	)
	(segment
		(start 173.296326 -22.318726)
		(end 172.972984 -21.995384)
		(width 0.1524)
		(layer "In5.Cu")
		(net "SAS_BLAD1_RX5_N")
	)
	(segment
		(start 175.250094 -30.99562)
		(end 175.681894 -31.42742)
		(width 0.1524)
		(layer "In5.Cu")
		(net "SAS_BLAD1_RX5_N")
	)
	(segment
		(start 170.7134 -19.525488)
		(end 170.7134 -17.710912)
		(width 0.1524)
		(layer "In5.Cu")
		(net "SAS_BLAD1_RX5_N")
	)
	(segment
		(start 173.8122 -27.867356)
		(end 173.8122 -27.281632)
		(width 0.1524)
		(layer "In5.Cu")
		(net "SAS_BLAD1_RX5_N")
	)
	(segment
		(start 174.78375 -31.765748)
		(end 174.439072 -31.421324)
		(width 0.1524)
		(layer "In5.Cu")
		(net "SAS_BLAD1_RX5_N")
	)
	(segment
		(start 173.8122 -30.752034)
		(end 173.8122 -29.848556)
		(width 0.1524)
		(layer "In5.Cu")
		(net "SAS_BLAD1_RX5_N")
	)
	(arc
		(start 168.195244 -14.982444)
		(mid 168.085086 -14.817676)
		(end 168.0464 -14.623288)
		(width 0.1524)
		(layer "In5.Cu")
		(net "SAS_BLAD1_RX5_N")
	)
	(arc
		(start 175.476916 -31.999682)
		(mid 175.444067 -32.021694)
		(end 175.405288 -32.0294)
		(width 0.1524)
		(layer "In5.Cu")
		(net "SAS_BLAD1_RX5_N")
	)
	(arc
		(start 175.089058 -32.0294)
		(mid 175.050314 -32.021618)
		(end 175.01743 -31.999682)
		(width 0.1524)
		(layer "In5.Cu")
		(net "SAS_BLAD1_RX5_N")
	)
	(arc
		(start 175.681894 -31.752794)
		(mid 175.674164 -31.791563)
		(end 175.652176 -31.824422)
		(width 0.1524)
		(layer "In5.Cu")
		(net "SAS_BLAD1_RX5_N")
	)
	(arc
		(start 173.8122 -26.143712)
		(mid 173.850884 -25.949323)
		(end 173.961044 -25.784556)
		(width 0.1524)
		(layer "In5.Cu")
		(net "SAS_BLAD1_RX5_N")
	)
	(arc
		(start 174.044356 -25.701244)
		(mid 174.154514 -25.536476)
		(end 174.1932 -25.342088)
		(width 0.1524)
		(layer "In5.Cu")
		(net "SAS_BLAD1_RX5_N")
	)
	(arc
		(start 170.862244 -19.884644)
		(mid 170.752086 -19.719876)
		(end 170.7134 -19.525488)
		(width 0.1524)
		(layer "In5.Cu")
		(net "SAS_BLAD1_RX5_N")
	)
	(arc
		(start 173.843696 -30.82544)
		(mid 173.820419 -30.791969)
		(end 173.8122 -30.752034)
		(width 0.1524)
		(layer "In5.Cu")
		(net "SAS_BLAD1_RX5_N")
	)
	(arc
		(start 168.0464 -13.087858)
		(mid 168.07559 -12.940641)
		(end 168.158922 -12.815824)
		(width 0.1524)
		(layer "In5.Cu")
		(net "SAS_BLAD1_RX5_N")
	)
	(arc
		(start 174.1932 -23.425912)
		(mid 174.154516 -23.231523)
		(end 174.044356 -23.066756)
		(width 0.1524)
		(layer "In5.Cu")
		(net "SAS_BLAD1_RX5_N")
	)
	(arc
		(start 168.159176 -12.81557)
		(mid 168.283796 -12.732491)
		(end 168.430702 -12.703302)
		(width 0.1524)
		(layer "In5.Cu")
		(net "SAS_BLAD1_RX5_N")
	)
	(arc
		(start 170.7134 -17.710912)
		(mid 170.674716 -17.516523)
		(end 170.564556 -17.351756)
		(width 0.1524)
		(layer "In5.Cu")
		(net "SAS_BLAD1_RX5_N")
	)
	(segment
		(start 195.694808 -25.899872)
		(end 195.694808 -24.808942)
		(width 0.1778)
		(layer "F.Cu")
		(net "SAS_BLAD1_TX1_P")
	)
	(segment
		(start 197.1929 -24.20112)
		(end 197.6628 -24.67102)
		(width 0.1778)
		(layer "F.Cu")
		(net "SAS_BLAD1_TX1_P")
	)
	(segment
		(start 195.470018 -24.406352)
		(end 195.67525 -24.20112)
		(width 0.1778)
		(layer "F.Cu")
		(net "SAS_BLAD1_TX1_P")
	)
	(segment
		(start 195.694808 -24.808942)
		(end 195.470018 -24.584152)
		(width 0.1778)
		(layer "F.Cu")
		(net "SAS_BLAD1_TX1_P")
	)
	(segment
		(start 195.67525 -24.20112)
		(end 197.1929 -24.20112)
		(width 0.1778)
		(layer "F.Cu")
		(net "SAS_BLAD1_TX1_P")
	)
	(segment
		(start 195.470018 -24.584152)
		(end 195.470018 -24.406352)
		(width 0.1778)
		(layer "F.Cu")
		(net "SAS_BLAD1_TX1_P")
	)
	(via
		(at 197.6628 -24.67102)
		(size 0.508)
		(drill 0.254)
		(layers "F.Cu" "B.Cu")
		(net "SAS_BLAD1_TX1_P")
	)
	(segment
		(start 191.168274 -11.295126)
		(end 191.491362 -11.618214)
		(width 0.1524)
		(layer "In5.Cu")
		(net "SAS_BLAD1_TX1_P")
	)
	(segment
		(start 187.069222 -7.196074)
		(end 187.307474 -7.196074)
		(width 0.1524)
		(layer "In5.Cu")
		(net "SAS_BLAD1_TX1_P")
	)
	(segment
		(start 187.630562 -7.519162)
		(end 187.630562 -7.757414)
		(width 0.1524)
		(layer "In5.Cu")
		(net "SAS_BLAD1_TX1_P")
	)
	(segment
		(start 190.283846 -10.410698)
		(end 190.606934 -10.733786)
		(width 0.1524)
		(layer "In5.Cu")
		(net "SAS_BLAD1_TX1_P")
	)
	(segment
		(start 175.38065 -2.5908)
		(end 177.815748 -2.5908)
		(width 0.1524)
		(layer "In5.Cu")
		(net "SAS_BLAD1_TX1_P")
	)
	(segment
		(start 193.085466 -13.212318)
		(end 193.113406 -13.253212)
		(width 0.1524)
		(layer "In5.Cu")
		(net "SAS_BLAD1_TX1_P")
	)
	(segment
		(start 198.48068 -21.284184)
		(end 198.481188 -21.284946)
		(width 0.1524)
		(layer "In5.Cu")
		(net "SAS_BLAD1_TX1_P")
	)
	(segment
		(start 188.191902 -8.080502)
		(end 188.51499 -8.40359)
		(width 0.1524)
		(layer "In5.Cu")
		(net "SAS_BLAD1_TX1_P")
	)
	(segment
		(start 198.413116 -24.23922)
		(end 198.0946 -24.23922)
		(width 0.1524)
		(layer "In5.Cu")
		(net "SAS_BLAD1_TX1_P")
	)
	(segment
		(start 174.889922 -2.100072)
		(end 175.38065 -2.5908)
		(width 0.1524)
		(layer "In5.Cu")
		(net "SAS_BLAD1_TX1_P")
	)
	(segment
		(start 198.0946 -24.23922)
		(end 197.6628 -24.67102)
		(width 0.1524)
		(layer "In5.Cu")
		(net "SAS_BLAD1_TX1_P")
	)
	(segment
		(start 190.606934 -10.733786)
		(end 190.845186 -10.733786)
		(width 0.1524)
		(layer "In5.Cu")
		(net "SAS_BLAD1_TX1_P")
	)
	(segment
		(start 189.722506 -9.849358)
		(end 189.960758 -9.849358)
		(width 0.1524)
		(layer "In5.Cu")
		(net "SAS_BLAD1_TX1_P")
	)
	(segment
		(start 188.838078 -8.96493)
		(end 189.07633 -8.96493)
		(width 0.1524)
		(layer "In5.Cu")
		(net "SAS_BLAD1_TX1_P")
	)
	(segment
		(start 193.113406 -13.253212)
		(end 198.48068 -21.28393)
		(width 0.1524)
		(layer "In5.Cu")
		(net "SAS_BLAD1_TX1_P")
	)
	(segment
		(start 189.399418 -9.288018)
		(end 189.399418 -9.52627)
		(width 0.1524)
		(layer "In5.Cu")
		(net "SAS_BLAD1_TX1_P")
	)
	(segment
		(start 189.399418 -9.52627)
		(end 189.722506 -9.849358)
		(width 0.1524)
		(layer "In5.Cu")
		(net "SAS_BLAD1_TX1_P")
	)
	(segment
		(start 185.744866 -5.871718)
		(end 187.069222 -7.196074)
		(width 0.1524)
		(layer "In5.Cu")
		(net "SAS_BLAD1_TX1_P")
	)
	(segment
		(start 188.51499 -8.641842)
		(end 188.838078 -8.96493)
		(width 0.1524)
		(layer "In5.Cu")
		(net "SAS_BLAD1_TX1_P")
	)
	(segment
		(start 191.729614 -11.618214)
		(end 192.052702 -11.941302)
		(width 0.1524)
		(layer "In5.Cu")
		(net "SAS_BLAD1_TX1_P")
	)
	(segment
		(start 187.630562 -7.757414)
		(end 187.95365 -8.080502)
		(width 0.1524)
		(layer "In5.Cu")
		(net "SAS_BLAD1_TX1_P")
	)
	(segment
		(start 191.168274 -11.056874)
		(end 191.168274 -11.295126)
		(width 0.1524)
		(layer "In5.Cu")
		(net "SAS_BLAD1_TX1_P")
	)
	(segment
		(start 178.16703 -2.66065)
		(end 185.515758 -5.718048)
		(width 0.1524)
		(layer "In5.Cu")
		(net "SAS_BLAD1_TX1_P")
	)
	(segment
		(start 187.95365 -8.080502)
		(end 188.191902 -8.080502)
		(width 0.1524)
		(layer "In5.Cu")
		(net "SAS_BLAD1_TX1_P")
	)
	(segment
		(start 189.07633 -8.96493)
		(end 189.399418 -9.288018)
		(width 0.1524)
		(layer "In5.Cu")
		(net "SAS_BLAD1_TX1_P")
	)
	(segment
		(start 188.51499 -8.40359)
		(end 188.51499 -8.641842)
		(width 0.1524)
		(layer "In5.Cu")
		(net "SAS_BLAD1_TX1_P")
	)
	(segment
		(start 190.283846 -10.172446)
		(end 190.283846 -10.410698)
		(width 0.1524)
		(layer "In5.Cu")
		(net "SAS_BLAD1_TX1_P")
	)
	(segment
		(start 198.527924 -21.37283)
		(end 199.097392 -22.746716)
		(width 0.1524)
		(layer "In5.Cu")
		(net "SAS_BLAD1_TX1_P")
	)
	(segment
		(start 191.491362 -11.618214)
		(end 191.729614 -11.618214)
		(width 0.1524)
		(layer "In5.Cu")
		(net "SAS_BLAD1_TX1_P")
	)
	(segment
		(start 199.136 -22.94128)
		(end 199.136 -23.516336)
		(width 0.1524)
		(layer "In5.Cu")
		(net "SAS_BLAD1_TX1_P")
	)
	(segment
		(start 187.307474 -7.196074)
		(end 187.630562 -7.519162)
		(width 0.1524)
		(layer "In5.Cu")
		(net "SAS_BLAD1_TX1_P")
	)
	(segment
		(start 192.052702 -12.179554)
		(end 193.085466 -13.212318)
		(width 0.1524)
		(layer "In5.Cu")
		(net "SAS_BLAD1_TX1_P")
	)
	(segment
		(start 189.960758 -9.849358)
		(end 190.283846 -10.172446)
		(width 0.1524)
		(layer "In5.Cu")
		(net "SAS_BLAD1_TX1_P")
	)
	(segment
		(start 198.48068 -21.28393)
		(end 198.48068 -21.284184)
		(width 0.1524)
		(layer "In5.Cu")
		(net "SAS_BLAD1_TX1_P")
	)
	(segment
		(start 192.052702 -11.941302)
		(end 192.052702 -12.179554)
		(width 0.1524)
		(layer "In5.Cu")
		(net "SAS_BLAD1_TX1_P")
	)
	(segment
		(start 190.845186 -10.733786)
		(end 191.168274 -11.056874)
		(width 0.1524)
		(layer "In5.Cu")
		(net "SAS_BLAD1_TX1_P")
	)
	(arc
		(start 185.578496 -5.74802)
		(mid 185.608652 -5.7652)
		(end 185.637932 -5.783834)
		(width 0.1524)
		(layer "In5.Cu")
		(net "SAS_BLAD1_TX1_P")
	)
	(arc
		(start 198.481188 -21.284946)
		(mid 198.506727 -21.327734)
		(end 198.527924 -21.37283)
		(width 0.1524)
		(layer "In5.Cu")
		(net "SAS_BLAD1_TX1_P")
	)
	(arc
		(start 198.924418 -24.027638)
		(mid 198.689816 -24.184301)
		(end 198.413116 -24.23922)
		(width 0.1524)
		(layer "In5.Cu")
		(net "SAS_BLAD1_TX1_P")
	)
	(arc
		(start 177.815748 -2.5908)
		(mid 177.994842 -2.608358)
		(end 178.16703 -2.66065)
		(width 0.1524)
		(layer "In5.Cu")
		(net "SAS_BLAD1_TX1_P")
	)
	(arc
		(start 199.097392 -22.746716)
		(mid 199.126295 -22.842094)
		(end 199.136 -22.94128)
		(width 0.1524)
		(layer "In5.Cu")
		(net "SAS_BLAD1_TX1_P")
	)
	(arc
		(start 185.637932 -5.783834)
		(mid 185.693545 -5.825165)
		(end 185.744866 -5.871718)
		(width 0.1524)
		(layer "In5.Cu")
		(net "SAS_BLAD1_TX1_P")
	)
	(arc
		(start 199.136 -23.516336)
		(mid 199.081057 -23.793025)
		(end 198.924418 -24.027638)
		(width 0.1524)
		(layer "In5.Cu")
		(net "SAS_BLAD1_TX1_P")
	)
	(arc
		(start 185.515758 -5.718048)
		(mid 185.547493 -5.732268)
		(end 185.578496 -5.74802)
		(width 0.1524)
		(layer "In5.Cu")
		(net "SAS_BLAD1_TX1_P")
	)
	(segment
		(start 197.21322 -23.8506)
		(end 197.6628 -23.40102)
		(width 0.1778)
		(layer "F.Cu")
		(net "SAS_BLAD1_TX1_N")
	)
	(segment
		(start 195.119498 -24.584152)
		(end 195.119498 -24.261064)
		(width 0.1778)
		(layer "F.Cu")
		(net "SAS_BLAD1_TX1_N")
	)
	(segment
		(start 194.894962 -25.899872)
		(end 194.894962 -24.808688)
		(width 0.1778)
		(layer "F.Cu")
		(net "SAS_BLAD1_TX1_N")
	)
	(segment
		(start 194.894962 -24.808688)
		(end 195.119498 -24.584152)
		(width 0.1778)
		(layer "F.Cu")
		(net "SAS_BLAD1_TX1_N")
	)
	(segment
		(start 195.119498 -24.261064)
		(end 195.529962 -23.8506)
		(width 0.1778)
		(layer "F.Cu")
		(net "SAS_BLAD1_TX1_N")
	)
	(segment
		(start 195.529962 -23.8506)
		(end 197.21322 -23.8506)
		(width 0.1778)
		(layer "F.Cu")
		(net "SAS_BLAD1_TX1_N")
	)
	(via
		(at 197.6628 -23.40102)
		(size 0.508)
		(drill 0.254)
		(layers "F.Cu" "B.Cu")
		(net "SAS_BLAD1_TX1_N")
	)
	(segment
		(start 192.776094 -13.480288)
		(end 192.77076 -13.472414)
		(width 0.1524)
		(layer "In5.Cu")
		(net "SAS_BLAD1_TX1_N")
	)
	(segment
		(start 198.7296 -22.941026)
		(end 198.729346 -22.941026)
		(width 0.1524)
		(layer "In5.Cu")
		(net "SAS_BLAD1_TX1_N")
	)
	(segment
		(start 192.77076 -13.472414)
		(end 185.457338 -6.158992)
		(width 0.1524)
		(layer "In5.Cu")
		(net "SAS_BLAD1_TX1_N")
	)
	(segment
		(start 175.392842 -2.9972)
		(end 174.889922 -3.50012)
		(width 0.1524)
		(layer "In5.Cu")
		(net "SAS_BLAD1_TX1_N")
	)
	(segment
		(start 198.0946 -23.83282)
		(end 198.413116 -23.83282)
		(width 0.1524)
		(layer "In5.Cu")
		(net "SAS_BLAD1_TX1_N")
	)
	(segment
		(start 198.14286 -21.510244)
		(end 192.776094 -13.480288)
		(width 0.1524)
		(layer "In5.Cu")
		(net "SAS_BLAD1_TX1_N")
	)
	(segment
		(start 177.815748 -2.9972)
		(end 175.392842 -2.9972)
		(width 0.1524)
		(layer "In5.Cu")
		(net "SAS_BLAD1_TX1_N")
	)
	(segment
		(start 185.359548 -6.09346)
		(end 178.01082 -3.036062)
		(width 0.1524)
		(layer "In5.Cu")
		(net "SAS_BLAD1_TX1_N")
	)
	(segment
		(start 198.152258 -21.528024)
		(end 198.152004 -21.52777)
		(width 0.1524)
		(layer "In5.Cu")
		(net "SAS_BLAD1_TX1_N")
	)
	(segment
		(start 198.7296 -23.51659)
		(end 198.7296 -22.941026)
		(width 0.1524)
		(layer "In5.Cu")
		(net "SAS_BLAD1_TX1_N")
	)
	(segment
		(start 197.6628 -23.40102)
		(end 198.0946 -23.83282)
		(width 0.1524)
		(layer "In5.Cu")
		(net "SAS_BLAD1_TX1_N")
	)
	(segment
		(start 198.721726 -22.902164)
		(end 198.152258 -21.528024)
		(width 0.1524)
		(layer "In5.Cu")
		(net "SAS_BLAD1_TX1_N")
	)
	(arc
		(start 198.63689 -23.74011)
		(mid 198.705442 -23.637559)
		(end 198.7296 -23.51659)
		(width 0.1524)
		(layer "In5.Cu")
		(net "SAS_BLAD1_TX1_N")
	)
	(arc
		(start 185.411364 -6.1214)
		(mid 185.398729 -6.113336)
		(end 185.38571 -6.105906)
		(width 0.1524)
		(layer "In5.Cu")
		(net "SAS_BLAD1_TX1_N")
	)
	(arc
		(start 198.413116 -23.83282)
		(mid 198.534229 -23.808729)
		(end 198.63689 -23.74011)
		(width 0.1524)
		(layer "In5.Cu")
		(net "SAS_BLAD1_TX1_N")
	)
	(arc
		(start 178.01082 -3.036062)
		(mid 177.915204 -3.007)
		(end 177.815748 -2.9972)
		(width 0.1524)
		(layer "In5.Cu")
		(net "SAS_BLAD1_TX1_N")
	)
	(arc
		(start 198.729346 -22.941026)
		(mid 198.727443 -22.921222)
		(end 198.721726 -22.902164)
		(width 0.1524)
		(layer "In5.Cu")
		(net "SAS_BLAD1_TX1_N")
	)
	(arc
		(start 185.38571 -6.105906)
		(mid 185.37278 -6.099366)
		(end 185.359548 -6.09346)
		(width 0.1524)
		(layer "In5.Cu")
		(net "SAS_BLAD1_TX1_N")
	)
	(arc
		(start 185.457338 -6.158992)
		(mid 185.435275 -6.139066)
		(end 185.411364 -6.1214)
		(width 0.1524)
		(layer "In5.Cu")
		(net "SAS_BLAD1_TX1_N")
	)
	(arc
		(start 198.152004 -21.52777)
		(mid 198.147863 -21.518782)
		(end 198.14286 -21.510244)
		(width 0.1524)
		(layer "In5.Cu")
		(net "SAS_BLAD1_TX1_N")
	)
	(segment
		(start 175.885094 -25.899872)
		(end 175.885094 -24.808688)
		(width 0.1778)
		(layer "F.Cu")
		(net "SAS_BLAD1_TX5_N")
	)
	(segment
		(start 177.7873 -23.83028)
		(end 178.22418 -23.3934)
		(width 0.1778)
		(layer "F.Cu")
		(net "SAS_BLAD1_TX5_N")
	)
	(segment
		(start 175.885094 -24.808688)
		(end 176.10963 -24.584152)
		(width 0.1778)
		(layer "F.Cu")
		(net "SAS_BLAD1_TX5_N")
	)
	(segment
		(start 176.10963 -24.584152)
		(end 176.10963 -24.261064)
		(width 0.1778)
		(layer "F.Cu")
		(net "SAS_BLAD1_TX5_N")
	)
	(segment
		(start 176.10963 -24.261064)
		(end 176.540414 -23.83028)
		(width 0.1778)
		(layer "F.Cu")
		(net "SAS_BLAD1_TX5_N")
	)
	(segment
		(start 176.540414 -23.83028)
		(end 177.7873 -23.83028)
		(width 0.1778)
		(layer "F.Cu")
		(net "SAS_BLAD1_TX5_N")
	)
	(via
		(at 178.22418 -23.3934)
		(size 0.508)
		(drill 0.254)
		(layers "F.Cu" "B.Cu")
		(net "SAS_BLAD1_TX5_N")
	)
	(segment
		(start 179.10048 -23.806912)
		(end 179.206652 -23.70074)
		(width 0.1778)
		(layer "B.Cu")
		(net "SAS_BLAD1_TX5_N")
	)
	(segment
		(start 169.797476 -14.292834)
		(end 169.720514 -13.976858)
		(width 0.1778)
		(layer "B.Cu")
		(net "SAS_BLAD1_TX5_N")
	)
	(segment
		(start 179.25288 -23.589488)
		(end 179.25288 -22.795992)
		(width 0.1778)
		(layer "B.Cu")
		(net "SAS_BLAD1_TX5_N")
	)
	(segment
		(start 169.710608 -13.8938)
		(end 169.710608 -8.662924)
		(width 0.1778)
		(layer "B.Cu")
		(net "SAS_BLAD1_TX5_N")
	)
	(segment
		(start 178.22418 -23.3934)
		(end 178.68392 -23.85314)
		(width 0.1778)
		(layer "B.Cu")
		(net "SAS_BLAD1_TX5_N")
	)
	(segment
		(start 170.31081 -15.720822)
		(end 169.916856 -14.77264)
		(width 0.1778)
		(layer "B.Cu")
		(net "SAS_BLAD1_TX5_N")
	)
	(segment
		(start 172.498766 -17.927574)
		(end 170.349164 -15.778226)
		(width 0.1778)
		(layer "B.Cu")
		(net "SAS_BLAD1_TX5_N")
	)
	(segment
		(start 169.720514 -13.976858)
		(end 169.710608 -13.8938)
		(width 0.1778)
		(layer "B.Cu")
		(net "SAS_BLAD1_TX5_N")
	)
	(segment
		(start 177.843688 -21.3868)
		(end 176.523904 -21.3868)
		(width 0.1778)
		(layer "B.Cu")
		(net "SAS_BLAD1_TX5_N")
	)
	(segment
		(start 178.68392 -23.85314)
		(end 178.989228 -23.85314)
		(width 0.1778)
		(layer "B.Cu")
		(net "SAS_BLAD1_TX5_N")
	)
	(segment
		(start 169.90822 -14.746478)
		(end 169.897298 -14.702536)
		(width 0.1778)
		(layer "B.Cu")
		(net "SAS_BLAD1_TX5_N")
	)
	(segment
		(start 176.164748 -21.237956)
		(end 173.105826 -18.179034)
		(width 0.1778)
		(layer "B.Cu")
		(net "SAS_BLAD1_TX5_N")
	)
	(segment
		(start 169.897298 -14.702536)
		(end 169.797476 -14.292834)
		(width 0.1778)
		(layer "B.Cu")
		(net "SAS_BLAD1_TX5_N")
	)
	(segment
		(start 169.522648 -8.475218)
		(end 169.075608 -8.475218)
		(width 0.1778)
		(layer "B.Cu")
		(net "SAS_BLAD1_TX5_N")
	)
	(segment
		(start 169.075608 -8.475218)
		(end 168.889934 -8.660892)
		(width 0.1778)
		(layer "B.Cu")
		(net "SAS_BLAD1_TX5_N")
	)
	(segment
		(start 168.889934 -8.660892)
		(end 168.889934 -8.999982)
		(width 0.1778)
		(layer "B.Cu")
		(net "SAS_BLAD1_TX5_N")
	)
	(segment
		(start 179.104036 -22.436836)
		(end 178.202844 -21.535644)
		(width 0.1778)
		(layer "B.Cu")
		(net "SAS_BLAD1_TX5_N")
	)
	(arc
		(start 176.523904 -21.3868)
		(mid 176.329515 -21.348116)
		(end 176.164748 -21.237956)
		(width 0.1778)
		(layer "B.Cu")
		(net "SAS_BLAD1_TX5_N")
	)
	(arc
		(start 179.206652 -23.70074)
		(mid 179.240865 -23.649726)
		(end 179.25288 -23.589488)
		(width 0.1778)
		(layer "B.Cu")
		(net "SAS_BLAD1_TX5_N")
	)
	(arc
		(start 173.105826 -18.179034)
		(mid 173.080319 -18.161927)
		(end 173.0502 -18.15592)
		(width 0.1778)
		(layer "B.Cu")
		(net "SAS_BLAD1_TX5_N")
	)
	(arc
		(start 170.349164 -15.778226)
		(mid 170.327178 -15.751402)
		(end 170.31081 -15.720822)
		(width 0.1778)
		(layer "B.Cu")
		(net "SAS_BLAD1_TX5_N")
	)
	(arc
		(start 169.655744 -8.530336)
		(mid 169.594679 -8.489534)
		(end 169.522648 -8.475218)
		(width 0.1778)
		(layer "B.Cu")
		(net "SAS_BLAD1_TX5_N")
	)
	(arc
		(start 173.0502 -18.15592)
		(mid 172.751777 -18.096578)
		(end 172.498766 -17.927574)
		(width 0.1778)
		(layer "B.Cu")
		(net "SAS_BLAD1_TX5_N")
	)
	(arc
		(start 179.25288 -22.795992)
		(mid 179.214196 -22.601603)
		(end 179.104036 -22.436836)
		(width 0.1778)
		(layer "B.Cu")
		(net "SAS_BLAD1_TX5_N")
	)
	(arc
		(start 178.202844 -21.535644)
		(mid 178.038076 -21.425486)
		(end 177.843688 -21.3868)
		(width 0.1778)
		(layer "B.Cu")
		(net "SAS_BLAD1_TX5_N")
	)
	(arc
		(start 169.916856 -14.77264)
		(mid 169.912037 -14.759725)
		(end 169.90822 -14.746478)
		(width 0.1778)
		(layer "B.Cu")
		(net "SAS_BLAD1_TX5_N")
	)
	(arc
		(start 178.989228 -23.85314)
		(mid 179.049464 -23.841122)
		(end 179.10048 -23.806912)
		(width 0.1778)
		(layer "B.Cu")
		(net "SAS_BLAD1_TX5_N")
	)
	(arc
		(start 169.710608 -8.662924)
		(mid 169.696354 -8.591175)
		(end 169.655744 -8.530336)
		(width 0.1778)
		(layer "B.Cu")
		(net "SAS_BLAD1_TX5_N")
	)
	(segment
		(start 177.74158 -24.1808)
		(end 178.22418 -24.6634)
		(width 0.1778)
		(layer "F.Cu")
		(net "SAS_BLAD1_TX5_P")
	)
	(segment
		(start 176.68494 -25.899872)
		(end 176.68494 -24.808942)
		(width 0.1778)
		(layer "F.Cu")
		(net "SAS_BLAD1_TX5_P")
	)
	(segment
		(start 176.46015 -24.406352)
		(end 176.685702 -24.1808)
		(width 0.1778)
		(layer "F.Cu")
		(net "SAS_BLAD1_TX5_P")
	)
	(segment
		(start 176.46015 -24.584152)
		(end 176.46015 -24.406352)
		(width 0.1778)
		(layer "F.Cu")
		(net "SAS_BLAD1_TX5_P")
	)
	(segment
		(start 176.68494 -24.808942)
		(end 176.46015 -24.584152)
		(width 0.1778)
		(layer "F.Cu")
		(net "SAS_BLAD1_TX5_P")
	)
	(segment
		(start 176.685702 -24.1808)
		(end 177.74158 -24.1808)
		(width 0.1778)
		(layer "F.Cu")
		(net "SAS_BLAD1_TX5_P")
	)
	(via
		(at 178.22418 -24.6634)
		(size 0.508)
		(drill 0.254)
		(layers "F.Cu" "B.Cu")
		(net "SAS_BLAD1_TX5_P")
	)
	(segment
		(start 176.523904 -21.03628)
		(end 176.759616 -21.03628)
		(width 0.1778)
		(layer "B.Cu")
		(net "SAS_BLAD1_TX5_P")
	)
	(segment
		(start 179.18557 -22.022562)
		(end 179.35194 -22.188932)
		(width 0.1778)
		(layer "B.Cu")
		(net "SAS_BLAD1_TX5_P")
	)
	(segment
		(start 178.80838 -21.40458)
		(end 179.18557 -21.78177)
		(width 0.1778)
		(layer "B.Cu")
		(net "SAS_BLAD1_TX5_P")
	)
	(segment
		(start 178.989228 -24.20366)
		(end 178.68392 -24.20366)
		(width 0.1778)
		(layer "B.Cu")
		(net "SAS_BLAD1_TX5_P")
	)
	(segment
		(start 178.450748 -21.28774)
		(end 178.567588 -21.40458)
		(width 0.1778)
		(layer "B.Cu")
		(net "SAS_BLAD1_TX5_P")
	)
	(segment
		(start 168.889934 -7.913624)
		(end 169.101008 -8.124698)
		(width 0.1778)
		(layer "B.Cu")
		(net "SAS_BLAD1_TX5_P")
	)
	(segment
		(start 173.761146 -18.094198)
		(end 174.138336 -18.471388)
		(width 0.1778)
		(layer "B.Cu")
		(net "SAS_BLAD1_TX5_P")
	)
	(segment
		(start 175.146716 -19.723862)
		(end 175.533558 -20.110704)
		(width 0.1778)
		(layer "B.Cu")
		(net "SAS_BLAD1_TX5_P")
	)
	(segment
		(start 176.759616 -21.03628)
		(end 176.932336 -20.86356)
		(width 0.1778)
		(layer "B.Cu")
		(net "SAS_BLAD1_TX5_P")
	)
	(segment
		(start 176.155096 -20.732496)
		(end 176.412652 -20.990052)
		(width 0.1778)
		(layer "B.Cu")
		(net "SAS_BLAD1_TX5_P")
	)
	(segment
		(start 175.533558 -20.111212)
		(end 175.777906 -20.111212)
		(width 0.1778)
		(layer "B.Cu")
		(net "SAS_BLAD1_TX5_P")
	)
	(segment
		(start 175.777906 -20.111212)
		(end 176.155096 -20.488148)
		(width 0.1778)
		(layer "B.Cu")
		(net "SAS_BLAD1_TX5_P")
	)
	(segment
		(start 170.245786 -14.650466)
		(end 170.621452 -15.554452)
		(width 0.1778)
		(layer "B.Cu")
		(net "SAS_BLAD1_TX5_P")
	)
	(segment
		(start 173.353984 -17.93113)
		(end 173.516798 -18.094198)
		(width 0.1778)
		(layer "B.Cu")
		(net "SAS_BLAD1_TX5_P")
	)
	(segment
		(start 174.769526 -19.102578)
		(end 175.146716 -19.479768)
		(width 0.1778)
		(layer "B.Cu")
		(net "SAS_BLAD1_TX5_P")
	)
	(segment
		(start 179.18557 -21.78177)
		(end 179.18557 -22.022562)
		(width 0.1778)
		(layer "B.Cu")
		(net "SAS_BLAD1_TX5_P")
	)
	(segment
		(start 178.567588 -21.40458)
		(end 178.80838 -21.40458)
		(width 0.1778)
		(layer "B.Cu")
		(net "SAS_BLAD1_TX5_P")
	)
	(segment
		(start 170.061128 -13.8938)
		(end 170.245786 -14.650466)
		(width 0.1778)
		(layer "B.Cu")
		(net "SAS_BLAD1_TX5_P")
	)
	(segment
		(start 175.533558 -20.110704)
		(end 175.533558 -20.111212)
		(width 0.1778)
		(layer "B.Cu")
		(net "SAS_BLAD1_TX5_P")
	)
	(segment
		(start 179.454302 -23.948898)
		(end 179.348384 -24.054816)
		(width 0.1778)
		(layer "B.Cu")
		(net "SAS_BLAD1_TX5_P")
	)
	(segment
		(start 174.525178 -19.102578)
		(end 174.769526 -19.102578)
		(width 0.1778)
		(layer "B.Cu")
		(net "SAS_BLAD1_TX5_P")
	)
	(segment
		(start 174.138336 -18.715736)
		(end 174.525178 -19.102578)
		(width 0.1778)
		(layer "B.Cu")
		(net "SAS_BLAD1_TX5_P")
	)
	(segment
		(start 168.889934 -7.600188)
		(end 168.889934 -7.913624)
		(width 0.1778)
		(layer "B.Cu")
		(net "SAS_BLAD1_TX5_P")
	)
	(segment
		(start 173.516798 -18.094198)
		(end 173.761146 -18.094198)
		(width 0.1778)
		(layer "B.Cu")
		(net "SAS_BLAD1_TX5_P")
	)
	(segment
		(start 178.68392 -24.20366)
		(end 178.22418 -24.6634)
		(width 0.1778)
		(layer "B.Cu")
		(net "SAS_BLAD1_TX5_P")
	)
	(segment
		(start 176.155096 -20.488148)
		(end 176.155096 -20.732496)
		(width 0.1778)
		(layer "B.Cu")
		(net "SAS_BLAD1_TX5_P")
	)
	(segment
		(start 179.6034 -22.795992)
		(end 179.6034 -23.589488)
		(width 0.1778)
		(layer "B.Cu")
		(net "SAS_BLAD1_TX5_P")
	)
	(segment
		(start 177.465736 -20.86356)
		(end 177.638456 -21.03628)
		(width 0.1778)
		(layer "B.Cu")
		(net "SAS_BLAD1_TX5_P")
	)
	(segment
		(start 169.101008 -8.124698)
		(end 169.522648 -8.124698)
		(width 0.1778)
		(layer "B.Cu")
		(net "SAS_BLAD1_TX5_P")
	)
	(segment
		(start 177.638456 -21.03628)
		(end 177.843688 -21.03628)
		(width 0.1778)
		(layer "B.Cu")
		(net "SAS_BLAD1_TX5_P")
	)
	(segment
		(start 170.061128 -8.662924)
		(end 170.061128 -13.8938)
		(width 0.1778)
		(layer "B.Cu")
		(net "SAS_BLAD1_TX5_P")
	)
	(segment
		(start 175.146716 -19.479768)
		(end 175.146716 -19.723862)
		(width 0.1778)
		(layer "B.Cu")
		(net "SAS_BLAD1_TX5_P")
	)
	(segment
		(start 170.621452 -15.554452)
		(end 172.74667 -17.67967)
		(width 0.1778)
		(layer "B.Cu")
		(net "SAS_BLAD1_TX5_P")
	)
	(segment
		(start 174.138336 -18.471388)
		(end 174.138336 -18.715736)
		(width 0.1778)
		(layer "B.Cu")
		(net "SAS_BLAD1_TX5_P")
	)
	(segment
		(start 176.932336 -20.86356)
		(end 177.465736 -20.86356)
		(width 0.1778)
		(layer "B.Cu")
		(net "SAS_BLAD1_TX5_P")
	)
	(arc
		(start 169.522648 -8.124698)
		(mid 169.728827 -8.165692)
		(end 169.903648 -8.282432)
		(width 0.1778)
		(layer "B.Cu")
		(net "SAS_BLAD1_TX5_P")
	)
	(arc
		(start 179.6034 -23.589488)
		(mid 179.564647 -23.784043)
		(end 179.454302 -23.948898)
		(width 0.1778)
		(layer "B.Cu")
		(net "SAS_BLAD1_TX5_P")
	)
	(arc
		(start 177.843688 -21.03628)
		(mid 178.172229 -21.101631)
		(end 178.450748 -21.28774)
		(width 0.1778)
		(layer "B.Cu")
		(net "SAS_BLAD1_TX5_P")
	)
	(arc
		(start 179.35194 -22.188932)
		(mid 179.538042 -22.467453)
		(end 179.6034 -22.795992)
		(width 0.1778)
		(layer "B.Cu")
		(net "SAS_BLAD1_TX5_P")
	)
	(arc
		(start 179.348384 -24.054816)
		(mid 179.183616 -24.164974)
		(end 178.989228 -24.20366)
		(width 0.1778)
		(layer "B.Cu")
		(net "SAS_BLAD1_TX5_P")
	)
	(arc
		(start 176.412652 -20.990052)
		(mid 176.463666 -21.024265)
		(end 176.523904 -21.03628)
		(width 0.1778)
		(layer "B.Cu")
		(net "SAS_BLAD1_TX5_P")
	)
	(arc
		(start 172.74667 -17.67967)
		(mid 172.885931 -17.772721)
		(end 173.0502 -17.8054)
		(width 0.1778)
		(layer "B.Cu")
		(net "SAS_BLAD1_TX5_P")
	)
	(arc
		(start 173.0502 -17.8054)
		(mid 173.214607 -17.838027)
		(end 173.353984 -17.93113)
		(width 0.1778)
		(layer "B.Cu")
		(net "SAS_BLAD1_TX5_P")
	)
	(arc
		(start 169.903648 -8.282432)
		(mid 170.020185 -8.457032)
		(end 170.061128 -8.662924)
		(width 0.1778)
		(layer "B.Cu")
		(net "SAS_BLAD1_TX5_P")
	)
	(segment
		(start 157.462474 -37.841428)
		(end 157.964632 -37.841428)
		(width 0.508)
		(layer "F.Cu")
		(net "P3V3_10G_1_VCCR_L")
	)
	(segment
		(start 156.959046 -37.338)
		(end 157.462474 -37.841428)
		(width 0.508)
		(layer "F.Cu")
		(net "P3V3_10G_1_VCCR_L")
	)
	(segment
		(start 156.959046 -35.26536)
		(end 156.959046 -37.338)
		(width 0.508)
		(layer "F.Cu")
		(net "P3V3_10G_1_VCCR_L")
	)
	(via
		(at 156.959046 -37.338)
		(size 0.508)
		(drill 0.254)
		(layers "F.Cu" "B.Cu")
		(net "P3V3_10G_1_VCCR_L")
	)
	(segment
		(start 159.047942 -37.6936)
		(end 159.047942 -35.26536)
		(width 0.508)
		(layer "F.Cu")
		(net "P3V3_10G_1_VCCT_L")
	)
	(segment
		(start 159.047942 -39.232332)
		(end 159.047942 -37.6936)
		(width 0.508)
		(layer "F.Cu")
		(net "P3V3_10G_1_VCCT_L")
	)
	(segment
		(start 157.991302 -40.288972)
		(end 159.047942 -39.232332)
		(width 0.508)
		(layer "F.Cu")
		(net "P3V3_10G_1_VCCT_L")
	)
	(via
		(at 159.047942 -37.6936)
		(size 0.508)
		(drill 0.254)
		(layers "F.Cu" "B.Cu")
		(net "P3V3_10G_1_VCCT_L")
	)
	(segment
		(start 86.480142 -34.68116)
		(end 87.821262 -34.68116)
		(width 0.508)
		(layer "F.Cu")
		(net "P3V3_10G_2_VCCR_L")
	)
	(segment
		(start 88.51773 -35.377628)
		(end 89.431368 -35.377628)
		(width 0.508)
		(layer "F.Cu")
		(net "P3V3_10G_2_VCCR_L")
	)
	(segment
		(start 88.114124 -34.974022)
		(end 88.51773 -35.377628)
		(width 0.508)
		(layer "F.Cu")
		(net "P3V3_10G_2_VCCR_L")
	)
	(segment
		(start 87.821262 -34.68116)
		(end 88.114124 -34.974022)
		(width 0.508)
		(layer "F.Cu")
		(net "P3V3_10G_2_VCCR_L")
	)
	(via
		(at 88.114124 -34.974022)
		(size 0.508)
		(drill 0.254)
		(layers "F.Cu" "B.Cu")
		(net "P3V3_10G_2_VCCR_L")
	)
	(segment
		(start 87.8078 -36.0934)
		(end 88.2269 -36.5125)
		(width 0.508)
		(layer "F.Cu")
		(net "P3V3_10G_2_VCCT_L")
	)
	(segment
		(start 89.405968 -37.691568)
		(end 88.2269 -36.5125)
		(width 0.508)
		(layer "F.Cu")
		(net "P3V3_10G_2_VCCT_L")
	)
	(segment
		(start 85.76564 -36.0934)
		(end 87.8078 -36.0934)
		(width 0.508)
		(layer "F.Cu")
		(net "P3V3_10G_2_VCCT_L")
	)
	(segment
		(start 89.405968 -37.875972)
		(end 89.405968 -37.691568)
		(width 0.508)
		(layer "F.Cu")
		(net "P3V3_10G_2_VCCT_L")
	)
	(segment
		(start 84.328 -34.65576)
		(end 85.76564 -36.0934)
		(width 0.508)
		(layer "F.Cu")
		(net "P3V3_10G_2_VCCT_L")
	)
	(via
		(at 88.2269 -36.5125)
		(size 0.508)
		(drill 0.254)
		(layers "F.Cu" "B.Cu")
		(net "P3V3_10G_2_VCCT_L")
	)
	(segment
		(start 84.328 -32.75584)
		(end 86.186772 -30.897068)
		(width 0.508)
		(layer "F.Cu")
		(net "P3V3_10G_2_VCCT")
	)
	(segment
		(start 90.03284 -30.897068)
		(end 89.0778 -30.897068)
		(width 0.508)
		(layer "F.Cu")
		(net "P3V3_10G_2_VCCT")
	)
	(segment
		(start 104.8512 -3.34645)
		(end 104.8512 -4.1148)
		(width 0.4572)
		(layer "F.Cu")
		(net "P3V3_10G_2_VCCT")
	)
	(segment
		(start 105.16997 -10.289794)
		(end 105.16997 -11.7348)
		(width 0.4572)
		(layer "F.Cu")
		(net "P3V3_10G_2_VCCT")
	)
	(segment
		(start 86.186772 -30.897068)
		(end 89.0778 -30.897068)
		(width 0.508)
		(layer "F.Cu")
		(net "P3V3_10G_2_VCCT")
	)
	(segment
		(start 104.8512 -3.34645)
		(end 105.9688 -3.34645)
		(width 0.4572)
		(layer "F.Cu")
		(net "P3V3_10G_2_VCCT")
	)
	(via
		(at 89.0778 -30.897068)
		(size 0.508)
		(drill 0.254)
		(layers "F.Cu" "B.Cu")
		(net "P3V3_10G_2_VCCT")
	)
	(via
		(at 104.8512 -4.1148)
		(size 0.508)
		(drill 0.254)
		(layers "F.Cu" "B.Cu")
		(net "P3V3_10G_2_VCCT")
	)
	(via
		(at 105.16997 -11.7348)
		(size 0.508)
		(drill 0.254)
		(layers "F.Cu" "B.Cu")
		(net "P3V3_10G_2_VCCT")
	)
	(segment
		(start 96.1898 -25.754584)
		(end 96.1898 -9.8806)
		(width 0.4572)
		(layer "In2.Cu")
		(net "P3V3_10G_2_VCCT")
	)
	(segment
		(start 96.1898 -9.8806)
		(end 98.7298 -7.3406)
		(width 0.4572)
		(layer "In2.Cu")
		(net "P3V3_10G_2_VCCT")
	)
	(segment
		(start 89.0778 -30.897068)
		(end 91.047316 -30.897068)
		(width 0.4572)
		(layer "In2.Cu")
		(net "P3V3_10G_2_VCCT")
	)
	(segment
		(start 91.047316 -30.897068)
		(end 96.1898 -25.754584)
		(width 0.4572)
		(layer "In2.Cu")
		(net "P3V3_10G_2_VCCT")
	)
	(segment
		(start 104.6226 -4.3434)
		(end 104.8512 -4.1148)
		(width 0.4572)
		(layer "In2.Cu")
		(net "P3V3_10G_2_VCCT")
	)
	(segment
		(start 100.7872 -4.3434)
		(end 104.6226 -4.3434)
		(width 0.4572)
		(layer "In2.Cu")
		(net "P3V3_10G_2_VCCT")
	)
	(segment
		(start 98.7298 -7.3406)
		(end 98.7298 -6.4008)
		(width 0.4572)
		(layer "In2.Cu")
		(net "P3V3_10G_2_VCCT")
	)
	(segment
		(start 98.7298 -6.4008)
		(end 100.7872 -4.3434)
		(width 0.4572)
		(layer "In2.Cu")
		(net "P3V3_10G_2_VCCT")
	)
	(segment
		(start 104.394 -13.1826)
		(end 100.584 -13.1826)
		(width 0.4572)
		(layer "In5.Cu")
		(net "P3V3_10G_2_VCCT")
	)
	(segment
		(start 100.584 -13.1826)
		(end 99.2378 -11.8364)
		(width 0.4572)
		(layer "In5.Cu")
		(net "P3V3_10G_2_VCCT")
	)
	(segment
		(start 105.16997 -12.40663)
		(end 104.394 -13.1826)
		(width 0.4572)
		(layer "In5.Cu")
		(net "P3V3_10G_2_VCCT")
	)
	(segment
		(start 99.2378 -11.8364)
		(end 99.2378 -10.3886)
		(width 0.4572)
		(layer "In5.Cu")
		(net "P3V3_10G_2_VCCT")
	)
	(segment
		(start 97.8662 -9.017)
		(end 97.8662 -5.9436)
		(width 0.4572)
		(layer "In5.Cu")
		(net "P3V3_10G_2_VCCT")
	)
	(segment
		(start 99.2378 -10.3886)
		(end 97.8662 -9.017)
		(width 0.4572)
		(layer "In5.Cu")
		(net "P3V3_10G_2_VCCT")
	)
	(segment
		(start 105.16997 -11.7348)
		(end 105.16997 -12.40663)
		(width 0.4572)
		(layer "In5.Cu")
		(net "P3V3_10G_2_VCCT")
	)
	(segment
		(start 97.8662 -5.9436)
		(end 101.0666 -2.7432)
		(width 0.4572)
		(layer "In5.Cu")
		(net "P3V3_10G_2_VCCT")
	)
	(segment
		(start 101.0666 -2.7432)
		(end 103.4796 -2.7432)
		(width 0.4572)
		(layer "In5.Cu")
		(net "P3V3_10G_2_VCCT")
	)
	(segment
		(start 103.4796 -2.7432)
		(end 104.8512 -4.1148)
		(width 0.4572)
		(layer "In5.Cu")
		(net "P3V3_10G_2_VCCT")
	)
	(segment
		(start 101.6254 -3.5306)
		(end 101.83495 -3.32105)
		(width 0.4572)
		(layer "F.Cu")
		(net "P3V3_10G_2_VCCR")
	)
	(segment
		(start 87.485982 -31.7754)
		(end 87.8586 -31.7754)
		(width 0.508)
		(layer "F.Cu")
		(net "P3V3_10G_2_VCCR")
	)
	(segment
		(start 101.83495 -3.32105)
		(end 102.5144 -3.32105)
		(width 0.4572)
		(layer "F.Cu")
		(net "P3V3_10G_2_VCCR")
	)
	(segment
		(start 86.480142 -32.78124)
		(end 87.485982 -31.7754)
		(width 0.508)
		(layer "F.Cu")
		(net "P3V3_10G_2_VCCR")
	)
	(segment
		(start 104.370124 -10.289794)
		(end 104.370124 -11.7094)
		(width 0.4572)
		(layer "F.Cu")
		(net "P3V3_10G_2_VCCR")
	)
	(segment
		(start 87.8586 -31.7754)
		(end 88.752172 -31.7754)
		(width 0.508)
		(layer "F.Cu")
		(net "P3V3_10G_2_VCCR")
	)
	(segment
		(start 88.752172 -31.7754)
		(end 90.03284 -33.056068)
		(width 0.508)
		(layer "F.Cu")
		(net "P3V3_10G_2_VCCR")
	)
	(segment
		(start 103.6828 -3.32105)
		(end 102.5144 -3.32105)
		(width 0.4572)
		(layer "F.Cu")
		(net "P3V3_10G_2_VCCR")
	)
	(via
		(at 101.6254 -3.5306)
		(size 0.508)
		(drill 0.254)
		(layers "F.Cu" "B.Cu")
		(net "P3V3_10G_2_VCCR")
	)
	(via
		(at 104.370124 -11.7094)
		(size 0.508)
		(drill 0.254)
		(layers "F.Cu" "B.Cu")
		(net "P3V3_10G_2_VCCR")
	)
	(via
		(at 87.8586 -31.7754)
		(size 0.508)
		(drill 0.254)
		(layers "F.Cu" "B.Cu")
		(net "P3V3_10G_2_VCCR")
	)
	(segment
		(start 97.9678 -7.024878)
		(end 97.9678 -6.0706)
		(width 0.4572)
		(layer "In2.Cu")
		(net "P3V3_10G_2_VCCR")
	)
	(segment
		(start 100.5078 -3.5306)
		(end 101.6254 -3.5306)
		(width 0.4572)
		(layer "In2.Cu")
		(net "P3V3_10G_2_VCCR")
	)
	(segment
		(start 97.9678 -6.0706)
		(end 100.5078 -3.5306)
		(width 0.4572)
		(layer "In2.Cu")
		(net "P3V3_10G_2_VCCR")
	)
	(segment
		(start 95.377 -25.489408)
		(end 95.377 -9.615678)
		(width 0.4572)
		(layer "In2.Cu")
		(net "P3V3_10G_2_VCCR")
	)
	(segment
		(start 88.761824 -30.135068)
		(end 90.73134 -30.135068)
		(width 0.4572)
		(layer "In2.Cu")
		(net "P3V3_10G_2_VCCR")
	)
	(segment
		(start 87.8586 -31.038292)
		(end 88.761824 -30.135068)
		(width 0.4572)
		(layer "In2.Cu")
		(net "P3V3_10G_2_VCCR")
	)
	(segment
		(start 95.377 -9.615678)
		(end 97.9678 -7.024878)
		(width 0.4572)
		(layer "In2.Cu")
		(net "P3V3_10G_2_VCCR")
	)
	(segment
		(start 87.8586 -31.7754)
		(end 87.8586 -31.038292)
		(width 0.4572)
		(layer "In2.Cu")
		(net "P3V3_10G_2_VCCR")
	)
	(segment
		(start 90.73134 -30.135068)
		(end 95.377 -25.489408)
		(width 0.4572)
		(layer "In2.Cu")
		(net "P3V3_10G_2_VCCR")
	)
	(segment
		(start 99.9998 -10.033)
		(end 98.6536 -8.6868)
		(width 0.4572)
		(layer "In5.Cu")
		(net "P3V3_10G_2_VCCR")
	)
	(segment
		(start 104.370124 -11.7094)
		(end 104.370124 -11.9888)
		(width 0.4572)
		(layer "In5.Cu")
		(net "P3V3_10G_2_VCCR")
	)
	(segment
		(start 98.6536 -6.2992)
		(end 101.4222 -3.5306)
		(width 0.4572)
		(layer "In5.Cu")
		(net "P3V3_10G_2_VCCR")
	)
	(segment
		(start 100.9142 -12.3952)
		(end 99.9998 -11.4808)
		(width 0.4572)
		(layer "In5.Cu")
		(net "P3V3_10G_2_VCCR")
	)
	(segment
		(start 101.4222 -3.5306)
		(end 101.6254 -3.5306)
		(width 0.4572)
		(layer "In5.Cu")
		(net "P3V3_10G_2_VCCR")
	)
	(segment
		(start 98.6536 -8.6868)
		(end 98.6536 -6.2992)
		(width 0.4572)
		(layer "In5.Cu")
		(net "P3V3_10G_2_VCCR")
	)
	(segment
		(start 99.9998 -11.4808)
		(end 99.9998 -10.033)
		(width 0.4572)
		(layer "In5.Cu")
		(net "P3V3_10G_2_VCCR")
	)
	(segment
		(start 104.370124 -11.9888)
		(end 103.963724 -12.3952)
		(width 0.4572)
		(layer "In5.Cu")
		(net "P3V3_10G_2_VCCR")
	)
	(segment
		(start 103.963724 -12.3952)
		(end 100.9142 -12.3952)
		(width 0.4572)
		(layer "In5.Cu")
		(net "P3V3_10G_2_VCCR")
	)
	(segment
		(start 139.490196 -18.490184)
		(end 139.490196 -22.7076)
		(width 0.28956)
		(layer "F.Cu")
		(net "ENET10G_1_RS1")
	)
	(segment
		(start 155.29941 -26.709878)
		(end 156.337 -26.709878)
		(width 0.28956)
		(layer "F.Cu")
		(net "ENET10G_1_RS1")
	)
	(segment
		(start 156.337 -26.709878)
		(end 157.381702 -26.709878)
		(width 0.28956)
		(layer "F.Cu")
		(net "ENET10G_1_RS1")
	)
	(via
		(at 139.490196 -22.7076)
		(size 0.508)
		(drill 0.254)
		(layers "F.Cu" "B.Cu")
		(net "ENET10G_1_RS1")
	)
	(via
		(at 156.337 -26.709878)
		(size 0.508)
		(drill 0.254)
		(layers "F.Cu" "B.Cu")
		(net "ENET10G_1_RS1")
	)
	(segment
		(start 140.4874 -22.7076)
		(end 139.490196 -22.7076)
		(width 0.18288)
		(layer "In5.Cu")
		(net "ENET10G_1_RS1")
	)
	(segment
		(start 146.05 -22.8854)
		(end 140.6652 -22.8854)
		(width 0.18288)
		(layer "In5.Cu")
		(net "ENET10G_1_RS1")
	)
	(segment
		(start 140.6652 -22.8854)
		(end 140.4874 -22.7076)
		(width 0.18288)
		(layer "In5.Cu")
		(net "ENET10G_1_RS1")
	)
	(segment
		(start 156.337 -26.709878)
		(end 153.176478 -26.709878)
		(width 0.18288)
		(layer "In5.Cu")
		(net "ENET10G_1_RS1")
	)
	(segment
		(start 153.176478 -26.709878)
		(end 150.5458 -24.0792)
		(width 0.18288)
		(layer "In5.Cu")
		(net "ENET10G_1_RS1")
	)
	(segment
		(start 150.5458 -24.0792)
		(end 147.2438 -24.0792)
		(width 0.18288)
		(layer "In5.Cu")
		(net "ENET10G_1_RS1")
	)
	(segment
		(start 147.2438 -24.0792)
		(end 146.05 -22.8854)
		(width 0.18288)
		(layer "In5.Cu")
		(net "ENET10G_1_RS1")
	)
	(segment
		(start 89.81821 -26.152094)
		(end 90.642694 -26.152094)
		(width 0.28956)
		(layer "F.Cu")
		(net "ENET10G_2_RS1")
	)
	(segment
		(start 101.570028 -18.48993)
		(end 101.570028 -20.146772)
		(width 0.28956)
		(layer "F.Cu")
		(net "ENET10G_2_RS1")
	)
	(segment
		(start 90.642694 -26.152094)
		(end 91.76639 -26.152094)
		(width 0.28956)
		(layer "F.Cu")
		(net "ENET10G_2_RS1")
	)
	(via
		(at 90.642694 -26.152094)
		(size 0.508)
		(drill 0.254)
		(layers "F.Cu" "B.Cu")
		(net "ENET10G_2_RS1")
	)
	(via
		(at 101.570028 -20.146772)
		(size 0.508)
		(drill 0.254)
		(layers "F.Cu" "B.Cu")
		(net "ENET10G_2_RS1")
	)
	(segment
		(start 90.642694 -26.152094)
		(end 95.564706 -26.152094)
		(width 0.18288)
		(layer "In5.Cu")
		(net "ENET10G_2_RS1")
	)
	(segment
		(start 95.564706 -26.152094)
		(end 101.570028 -20.146772)
		(width 0.18288)
		(layer "In5.Cu")
		(net "ENET10G_2_RS1")
	)
	(segment
		(start 90.8304 -27.574494)
		(end 89.81821 -27.574494)
		(width 0.28956)
		(layer "F.Cu")
		(net "ENET10G_2_RS0")
	)
	(segment
		(start 91.76639 -27.574494)
		(end 90.8304 -27.574494)
		(width 0.28956)
		(layer "F.Cu")
		(net "ENET10G_2_RS0")
	)
	(segment
		(start 103.169974 -18.48993)
		(end 103.169974 -20.9042)
		(width 0.28956)
		(layer "F.Cu")
		(net "ENET10G_2_RS0")
	)
	(via
		(at 103.169974 -20.9042)
		(size 0.508)
		(drill 0.254)
		(layers "F.Cu" "B.Cu")
		(net "ENET10G_2_RS0")
	)
	(via
		(at 90.8304 -27.574494)
		(size 0.508)
		(drill 0.254)
		(layers "F.Cu" "B.Cu")
		(net "ENET10G_2_RS0")
	)
	(segment
		(start 94.83217 -27.574494)
		(end 101.502464 -20.9042)
		(width 0.18288)
		(layer "In5.Cu")
		(net "ENET10G_2_RS0")
	)
	(segment
		(start 90.8304 -27.574494)
		(end 94.83217 -27.574494)
		(width 0.18288)
		(layer "In5.Cu")
		(net "ENET10G_2_RS0")
	)
	(segment
		(start 101.502464 -20.9042)
		(end 103.169974 -20.9042)
		(width 0.18288)
		(layer "In5.Cu")
		(net "ENET10G_2_RS0")
	)
	(segment
		(start 124.530104 -13.938504)
		(end 124.9934 -14.4018)
		(width 0.762)
		(layer "F.Cu")
		(net "P3V3_BLAD1")
	)
	(segment
		(start 124.9934 -14.4018)
		(end 124.9934 -22.987)
		(width 0.762)
		(layer "F.Cu")
		(net "P3V3_BLAD1")
	)
	(segment
		(start 124.530104 -13.299948)
		(end 124.530104 -13.938504)
		(width 0.762)
		(layer "F.Cu")
		(net "P3V3_BLAD1")
	)
	(segment
		(start 124.9934 -22.987)
		(end 124.1552 -23.8252)
		(width 0.762)
		(layer "F.Cu")
		(net "P3V3_BLAD1")
	)
	(via
		(at 153.4668 -27.2796)
		(size 0.508)
		(drill 0.254)
		(layers "F.Cu" "B.Cu")
		(net "P3V3_BLAD1")
	)
	(via
		(at 124.1552 -23.8252)
		(size 0.508)
		(drill 0.254)
		(layers "F.Cu" "B.Cu")
		(net "P3V3_BLAD1")
	)
	(via
		(at 153.5176 -24.384)
		(size 0.508)
		(drill 0.254)
		(layers "F.Cu" "B.Cu")
		(net "P3V3_BLAD1")
	)
	(via
		(at 129.9464 -27.432)
		(size 0.508)
		(drill 0.254)
		(layers "F.Cu" "B.Cu")
		(net "P3V3_BLAD1")
	)
	(via
		(at 93.2688 -31.496)
		(size 0.508)
		(drill 0.254)
		(layers "F.Cu" "B.Cu")
		(net "P3V3_BLAD1")
	)
	(via
		(at 118.4402 -25.6286)
		(size 0.508)
		(drill 0.254)
		(layers "F.Cu" "B.Cu")
		(net "P3V3_BLAD1")
	)
	(segment
		(start 141.090142 -18.490184)
		(end 141.090142 -20.160742)
		(width 0.28956)
		(layer "F.Cu")
		(net "ENET10G_1_RS0")
	)
	(segment
		(start 141.090142 -20.160742)
		(end 143.2052 -22.2758)
		(width 0.28956)
		(layer "F.Cu")
		(net "ENET10G_1_RS0")
	)
	(segment
		(start 156.337 -25.439878)
		(end 155.29941 -25.439878)
		(width 0.28956)
		(layer "F.Cu")
		(net "ENET10G_1_RS0")
	)
	(segment
		(start 157.381702 -25.439878)
		(end 156.337 -25.439878)
		(width 0.28956)
		(layer "F.Cu")
		(net "ENET10G_1_RS0")
	)
	(via
		(at 143.2052 -22.2758)
		(size 0.508)
		(drill 0.254)
		(layers "F.Cu" "B.Cu")
		(net "ENET10G_1_RS0")
	)
	(via
		(at 156.337 -25.439878)
		(size 0.508)
		(drill 0.254)
		(layers "F.Cu" "B.Cu")
		(net "ENET10G_1_RS0")
	)
	(segment
		(start 150.7744 -23.5458)
		(end 147.574 -23.5458)
		(width 0.18288)
		(layer "In5.Cu")
		(net "ENET10G_1_RS0")
	)
	(segment
		(start 147.574 -23.5458)
		(end 146.304 -22.2758)
		(width 0.18288)
		(layer "In5.Cu")
		(net "ENET10G_1_RS0")
	)
	(segment
		(start 146.304 -22.2758)
		(end 143.2052 -22.2758)
		(width 0.18288)
		(layer "In5.Cu")
		(net "ENET10G_1_RS0")
	)
	(segment
		(start 156.337 -25.439878)
		(end 152.668478 -25.439878)
		(width 0.18288)
		(layer "In5.Cu")
		(net "ENET10G_1_RS0")
	)
	(segment
		(start 152.668478 -25.439878)
		(end 150.7744 -23.5458)
		(width 0.18288)
		(layer "In5.Cu")
		(net "ENET10G_1_RS0")
	)
	(segment
		(start 347.639132 -22.057868)
		(end 347.639132 -23.636732)
		(width 0.4572)
		(layer "F.Cu")
		(net "P3V3_BLAD2")
	)
	(segment
		(start 345.53017 -16.5862)
		(end 345.53017 -13.299948)
		(width 0.762)
		(layer "F.Cu")
		(net "P3V3_BLAD2")
	)
	(segment
		(start 345.0844 -18.7198)
		(end 345.8972 -17.907)
		(width 0.762)
		(layer "F.Cu")
		(net "P3V3_BLAD2")
	)
	(segment
		(start 345.8972 -16.95323)
		(end 345.53017 -16.5862)
		(width 0.762)
		(layer "F.Cu")
		(net "P3V3_BLAD2")
	)
	(segment
		(start 347.639132 -23.636732)
		(end 348.3864 -24.384)
		(width 0.4572)
		(layer "F.Cu")
		(net "P3V3_BLAD2")
	)
	(segment
		(start 345.8972 -17.907)
		(end 345.8972 -16.95323)
		(width 0.762)
		(layer "F.Cu")
		(net "P3V3_BLAD2")
	)
	(via
		(at 373.9896 -26.0858)
		(size 0.508)
		(drill 0.254)
		(layers "F.Cu" "B.Cu")
		(net "P3V3_BLAD2")
	)
	(via
		(at 339.2424 -24.511)
		(size 0.508)
		(drill 0.254)
		(layers "F.Cu" "B.Cu")
		(net "P3V3_BLAD2")
	)
	(via
		(at 314.6806 -31.3182)
		(size 0.508)
		(drill 0.254)
		(layers "F.Cu" "B.Cu")
		(net "P3V3_BLAD2")
	)
	(via
		(at 345.0844 -18.7198)
		(size 0.508)
		(drill 0.254)
		(layers "F.Cu" "B.Cu")
		(net "P3V3_BLAD2")
	)
	(via
		(at 341.6554 -26.797)
		(size 0.508)
		(drill 0.254)
		(layers "F.Cu" "B.Cu")
		(net "P3V3_BLAD2")
	)
	(via
		(at 348.3864 -24.384)
		(size 0.508)
		(drill 0.254)
		(layers "F.Cu" "B.Cu")
		(net "P3V3_BLAD2")
	)
	(via
		(at 314.4774 -32.4866)
		(size 0.508)
		(drill 0.254)
		(layers "F.Cu" "B.Cu")
		(net "P3V3_BLAD2")
	)
	(via
		(at 374.4468 -27.0764)
		(size 0.508)
		(drill 0.254)
		(layers "F.Cu" "B.Cu")
		(net "P3V3_BLAD2")
	)
	(segment
		(start 343.4842 -20.32)
		(end 343.4842 -24.9682)
		(width 0.635)
		(layer "In5.Cu")
		(net "P3V3_BLAD2")
	)
	(segment
		(start 345.0844 -18.7198)
		(end 343.4842 -20.32)
		(width 0.635)
		(layer "In5.Cu")
		(net "P3V3_BLAD2")
	)
	(segment
		(start 343.4842 -24.9682)
		(end 341.6554 -26.797)
		(width 0.635)
		(layer "In5.Cu")
		(net "P3V3_BLAD2")
	)
	(segment
		(start 115.65001 -25.45461)
		(end 114.8334 -24.638)
		(width 0.28956)
		(layer "F.Cu")
		(net "ENET10G_2_MOD_DEF0")
	)
	(segment
		(start 103.970074 -18.48993)
		(end 103.970074 -22.5044)
		(width 0.28956)
		(layer "F.Cu")
		(net "ENET10G_2_MOD_DEF0")
	)
	(segment
		(start 119.033798 -21.147532)
		(end 118.3894 -21.147532)
		(width 0.28956)
		(layer "F.Cu")
		(net "ENET10G_2_MOD_DEF0")
	)
	(segment
		(start 116.91239 -25.45461)
		(end 115.65001 -25.45461)
		(width 0.28956)
		(layer "F.Cu")
		(net "ENET10G_2_MOD_DEF0")
	)
	(via
		(at 114.8334 -24.638)
		(size 0.508)
		(drill 0.254)
		(layers "F.Cu" "B.Cu")
		(net "ENET10G_2_MOD_DEF0")
	)
	(via
		(at 103.970074 -22.5044)
		(size 0.508)
		(drill 0.254)
		(layers "F.Cu" "B.Cu")
		(net "ENET10G_2_MOD_DEF0")
	)
	(via
		(at 118.3894 -21.147532)
		(size 0.508)
		(drill 0.254)
		(layers "F.Cu" "B.Cu")
		(net "ENET10G_2_MOD_DEF0")
	)
	(segment
		(start 105.163874 -23.6982)
		(end 112.7252 -23.6982)
		(width 0.18288)
		(layer "In5.Cu")
		(net "ENET10G_2_MOD_DEF0")
	)
	(segment
		(start 114.8334 -24.638)
		(end 115.1636 -24.638)
		(width 0.18288)
		(layer "In5.Cu")
		(net "ENET10G_2_MOD_DEF0")
	)
	(segment
		(start 113.665 -24.638)
		(end 114.8334 -24.638)
		(width 0.18288)
		(layer "In5.Cu")
		(net "ENET10G_2_MOD_DEF0")
	)
	(segment
		(start 118.3894 -21.4122)
		(end 118.3894 -21.147532)
		(width 0.18288)
		(layer "In5.Cu")
		(net "ENET10G_2_MOD_DEF0")
	)
	(segment
		(start 103.970074 -22.5044)
		(end 105.163874 -23.6982)
		(width 0.18288)
		(layer "In5.Cu")
		(net "ENET10G_2_MOD_DEF0")
	)
	(segment
		(start 112.7252 -23.6982)
		(end 113.665 -24.638)
		(width 0.18288)
		(layer "In5.Cu")
		(net "ENET10G_2_MOD_DEF0")
	)
	(segment
		(start 115.1636 -24.638)
		(end 118.3894 -21.4122)
		(width 0.18288)
		(layer "In5.Cu")
		(net "ENET10G_2_MOD_DEF0")
	)
	(segment
		(start 116.91239 -21.08581)
		(end 114.98961 -21.08581)
		(width 0.28956)
		(layer "F.Cu")
		(net "ENET10G_2_TX_FAULT")
	)
	(segment
		(start 114.98961 -21.08581)
		(end 114.5794 -20.6756)
		(width 0.28956)
		(layer "F.Cu")
		(net "ENET10G_2_TX_FAULT")
	)
	(segment
		(start 116.91239 -22.17801)
		(end 116.91239 -21.08581)
		(width 0.28956)
		(layer "F.Cu")
		(net "ENET10G_2_TX_FAULT")
	)
	(segment
		(start 107.169966 -18.48993)
		(end 107.169966 -19.9136)
		(width 0.28956)
		(layer "F.Cu")
		(net "ENET10G_2_TX_FAULT")
	)
	(via
		(at 114.5794 -20.6756)
		(size 0.508)
		(drill 0.254)
		(layers "F.Cu" "B.Cu")
		(net "ENET10G_2_TX_FAULT")
	)
	(via
		(at 107.169966 -19.9136)
		(size 0.508)
		(drill 0.254)
		(layers "F.Cu" "B.Cu")
		(net "ENET10G_2_TX_FAULT")
	)
	(segment
		(start 113.8428 -19.939)
		(end 109.4232 -19.939)
		(width 0.18288)
		(layer "In5.Cu")
		(net "ENET10G_2_TX_FAULT")
	)
	(segment
		(start 107.169966 -20.1676)
		(end 107.169966 -19.9136)
		(width 0.18288)
		(layer "In5.Cu")
		(net "ENET10G_2_TX_FAULT")
	)
	(segment
		(start 109.4232 -19.939)
		(end 109.05236 -20.30984)
		(width 0.18288)
		(layer "In5.Cu")
		(net "ENET10G_2_TX_FAULT")
	)
	(segment
		(start 114.5794 -20.6756)
		(end 113.8428 -19.939)
		(width 0.18288)
		(layer "In5.Cu")
		(net "ENET10G_2_TX_FAULT")
	)
	(segment
		(start 107.312206 -20.30984)
		(end 107.169966 -20.1676)
		(width 0.18288)
		(layer "In5.Cu")
		(net "ENET10G_2_TX_FAULT")
	)
	(segment
		(start 109.05236 -20.30984)
		(end 107.312206 -20.30984)
		(width 0.18288)
		(layer "In5.Cu")
		(net "ENET10G_2_TX_FAULT")
	)
	(segment
		(start 90.8812 -29.122878)
		(end 91.76639 -29.122878)
		(width 0.28956)
		(layer "F.Cu")
		(net "ENET10G_2_TX_DIS")
	)
	(segment
		(start 105.381552 -21.7424)
		(end 104.7242 -21.7424)
		(width 0.28956)
		(layer "F.Cu")
		(net "ENET10G_2_TX_DIS")
	)
	(segment
		(start 89.81821 -29.122878)
		(end 90.8812 -29.122878)
		(width 0.28956)
		(layer "F.Cu")
		(net "ENET10G_2_TX_DIS")
	)
	(segment
		(start 106.37012 -20.753832)
		(end 105.381552 -21.7424)
		(width 0.28956)
		(layer "F.Cu")
		(net "ENET10G_2_TX_DIS")
	)
	(segment
		(start 106.37012 -18.48993)
		(end 106.37012 -20.753832)
		(width 0.28956)
		(layer "F.Cu")
		(net "ENET10G_2_TX_DIS")
	)
	(via
		(at 104.7242 -21.7424)
		(size 0.508)
		(drill 0.254)
		(layers "F.Cu" "B.Cu")
		(net "ENET10G_2_TX_DIS")
	)
	(via
		(at 90.8812 -29.122878)
		(size 0.508)
		(drill 0.254)
		(layers "F.Cu" "B.Cu")
		(net "ENET10G_2_TX_DIS")
	)
	(segment
		(start 90.8812 -29.122878)
		(end 93.97365 -29.122878)
		(width 0.18288)
		(layer "In5.Cu")
		(net "ENET10G_2_TX_DIS")
	)
	(segment
		(start 101.354128 -21.7424)
		(end 104.7242 -21.7424)
		(width 0.18288)
		(layer "In5.Cu")
		(net "ENET10G_2_TX_DIS")
	)
	(segment
		(start 93.97365 -29.122878)
		(end 101.354128 -21.7424)
		(width 0.18288)
		(layer "In5.Cu")
		(net "ENET10G_2_TX_DIS")
	)
	(segment
		(start 127.503936 -30.966918)
		(end 127.299466 -30.8991)
		(width 0.1524)
		(layer "In2.Cu")
		(net "ENET1G_2_MDI3N")
	)
	(segment
		(start 118.993666 -4.303268)
		(end 118.6942 -4.303268)
		(width 0.1524)
		(layer "In2.Cu")
		(net "ENET1G_2_MDI3N")
	)
	(segment
		(start 127.299466 -30.8991)
		(end 127.163068 -30.967172)
		(width 0.1524)
		(layer "In2.Cu")
		(net "ENET1G_2_MDI3N")
	)
	(segment
		(start 117.6528 -31.9532)
		(end 117.6528 -28.956)
		(width 0.1524)
		(layer "In2.Cu")
		(net "ENET1G_2_MDI3N")
	)
	(segment
		(start 127.1016 -32.5882)
		(end 125.6792 -34.0106)
		(width 0.1524)
		(layer "In2.Cu")
		(net "ENET1G_2_MDI3N")
	)
	(segment
		(start 117.6528 -28.956)
		(end 119.5832 -27.0256)
		(width 0.1524)
		(layer "In2.Cu")
		(net "ENET1G_2_MDI3N")
	)
	(segment
		(start 119.33174 -17.493742)
		(end 119.33174 -4.641342)
		(width 0.1524)
		(layer "In2.Cu")
		(net "ENET1G_2_MDI3N")
	)
	(segment
		(start 127.163068 -30.967172)
		(end 127.1016 -31.02864)
		(width 0.1524)
		(layer "In2.Cu")
		(net "ENET1G_2_MDI3N")
	)
	(segment
		(start 125.6792 -34.0106)
		(end 119.7102 -34.0106)
		(width 0.1524)
		(layer "In2.Cu")
		(net "ENET1G_2_MDI3N")
	)
	(segment
		(start 127.1016 -31.02864)
		(end 127.1016 -32.5882)
		(width 0.1524)
		(layer "In2.Cu")
		(net "ENET1G_2_MDI3N")
	)
	(segment
		(start 119.33174 -4.641342)
		(end 118.993666 -4.303268)
		(width 0.1524)
		(layer "In2.Cu")
		(net "ENET1G_2_MDI3N")
	)
	(segment
		(start 127.980186 -31.919164)
		(end 127.503936 -30.966918)
		(width 0.1524)
		(layer "In2.Cu")
		(net "ENET1G_2_MDI3N")
	)
	(segment
		(start 119.5832 -27.0256)
		(end 119.5832 -17.745202)
		(width 0.1524)
		(layer "In2.Cu")
		(net "ENET1G_2_MDI3N")
	)
	(segment
		(start 118.6942 -4.303268)
		(end 118.530116 -4.467352)
		(width 0.1524)
		(layer "In2.Cu")
		(net "ENET1G_2_MDI3N")
	)
	(segment
		(start 119.7102 -34.0106)
		(end 117.6528 -31.9532)
		(width 0.1524)
		(layer "In2.Cu")
		(net "ENET1G_2_MDI3N")
	)
	(segment
		(start 118.530116 -4.467352)
		(end 118.530116 -4.800092)
		(width 0.1524)
		(layer "In2.Cu")
		(net "ENET1G_2_MDI3N")
	)
	(segment
		(start 119.5832 -17.745202)
		(end 119.33174 -17.493742)
		(width 0.1524)
		(layer "In2.Cu")
		(net "ENET1G_2_MDI3N")
	)
	(segment
		(start 126.6952 -32.419798)
		(end 125.510798 -33.6042)
		(width 0.1524)
		(layer "In2.Cu")
		(net "ENET1G_2_MDI3P")
	)
	(segment
		(start 119.9896 -27.194002)
		(end 119.9896 -17.5768)
		(width 0.1524)
		(layer "In2.Cu")
		(net "ENET1G_2_MDI3P")
	)
	(segment
		(start 118.6942 -3.896868)
		(end 118.530116 -3.732784)
		(width 0.1524)
		(layer "In2.Cu")
		(net "ENET1G_2_MDI3P")
	)
	(segment
		(start 118.0592 -29.124402)
		(end 119.9896 -27.194002)
		(width 0.1524)
		(layer "In2.Cu")
		(net "ENET1G_2_MDI3P")
	)
	(segment
		(start 127.185928 -30.330902)
		(end 127.117602 -30.535372)
		(width 0.1524)
		(layer "In2.Cu")
		(net "ENET1G_2_MDI3P")
	)
	(segment
		(start 119.878602 -33.6042)
		(end 118.0592 -31.784798)
		(width 0.1524)
		(layer "In2.Cu")
		(net "ENET1G_2_MDI3P")
	)
	(segment
		(start 125.510798 -33.6042)
		(end 119.878602 -33.6042)
		(width 0.1524)
		(layer "In2.Cu")
		(net "ENET1G_2_MDI3P")
	)
	(segment
		(start 126.710186 -29.379164)
		(end 127.185928 -30.330902)
		(width 0.1524)
		(layer "In2.Cu")
		(net "ENET1G_2_MDI3P")
	)
	(segment
		(start 119.73814 -17.32534)
		(end 119.73814 -4.47294)
		(width 0.1524)
		(layer "In2.Cu")
		(net "ENET1G_2_MDI3P")
	)
	(segment
		(start 126.922276 -30.632908)
		(end 126.6952 -30.860238)
		(width 0.1524)
		(layer "In2.Cu")
		(net "ENET1G_2_MDI3P")
	)
	(segment
		(start 118.0592 -31.784798)
		(end 118.0592 -29.124402)
		(width 0.1524)
		(layer "In2.Cu")
		(net "ENET1G_2_MDI3P")
	)
	(segment
		(start 118.530116 -3.732784)
		(end 118.530116 -3.400044)
		(width 0.1524)
		(layer "In2.Cu")
		(net "ENET1G_2_MDI3P")
	)
	(segment
		(start 119.9896 -17.5768)
		(end 119.73814 -17.32534)
		(width 0.1524)
		(layer "In2.Cu")
		(net "ENET1G_2_MDI3P")
	)
	(segment
		(start 126.6952 -30.860238)
		(end 126.6952 -32.419798)
		(width 0.1524)
		(layer "In2.Cu")
		(net "ENET1G_2_MDI3P")
	)
	(segment
		(start 119.73814 -4.47294)
		(end 119.162068 -3.896868)
		(width 0.1524)
		(layer "In2.Cu")
		(net "ENET1G_2_MDI3P")
	)
	(segment
		(start 127.117602 -30.535372)
		(end 126.922276 -30.632908)
		(width 0.1524)
		(layer "In2.Cu")
		(net "ENET1G_2_MDI3P")
	)
	(segment
		(start 119.162068 -3.896868)
		(end 118.6942 -3.896868)
		(width 0.1524)
		(layer "In2.Cu")
		(net "ENET1G_2_MDI3P")
	)
	(segment
		(start 116.91239 -23.27021)
		(end 116.36121 -23.27021)
		(width 0.28956)
		(layer "F.Cu")
		(net "ENET10G_2_SDA")
	)
	(segment
		(start 105.57002 -18.48993)
		(end 105.57002 -20.4978)
		(width 0.28956)
		(layer "F.Cu")
		(net "ENET10G_2_SDA")
	)
	(segment
		(start 116.36121 -23.27021)
		(end 115.1382 -22.0472)
		(width 0.28956)
		(layer "F.Cu")
		(net "ENET10G_2_SDA")
	)
	(via
		(at 115.1382 -22.0472)
		(size 0.508)
		(drill 0.254)
		(layers "F.Cu" "B.Cu")
		(net "ENET10G_2_SDA")
	)
	(via
		(at 105.57002 -20.4978)
		(size 0.508)
		(drill 0.254)
		(layers "F.Cu" "B.Cu")
		(net "ENET10G_2_SDA")
	)
	(segment
		(start 120.2436 -8.382)
		(end 121.748296 -8.382)
		(width 0.18288)
		(layer "In5.Cu")
		(net "ENET10G_2_SDA")
	)
	(segment
		(start 109.855 -20.5994)
		(end 113.0808 -20.5994)
		(width 0.18288)
		(layer "In5.Cu")
		(net "ENET10G_2_SDA")
	)
	(segment
		(start 114.5286 -22.0472)
		(end 115.1382 -22.0472)
		(width 0.18288)
		(layer "In5.Cu")
		(net "ENET10G_2_SDA")
	)
	(segment
		(start 116.3066 -11.4554)
		(end 118.0592 -9.7028)
		(width 0.18288)
		(layer "In5.Cu")
		(net "ENET10G_2_SDA")
	)
	(segment
		(start 109.4232 -21.0312)
		(end 109.855 -20.5994)
		(width 0.18288)
		(layer "In5.Cu")
		(net "ENET10G_2_SDA")
	)
	(segment
		(start 116.3066 -20.8788)
		(end 116.3066 -11.4554)
		(width 0.18288)
		(layer "In5.Cu")
		(net "ENET10G_2_SDA")
	)
	(segment
		(start 105.57002 -20.4978)
		(end 106.10342 -21.0312)
		(width 0.18288)
		(layer "In5.Cu")
		(net "ENET10G_2_SDA")
	)
	(segment
		(start 106.10342 -21.0312)
		(end 109.4232 -21.0312)
		(width 0.18288)
		(layer "In5.Cu")
		(net "ENET10G_2_SDA")
	)
	(segment
		(start 115.1382 -22.0472)
		(end 116.3066 -20.8788)
		(width 0.18288)
		(layer "In5.Cu")
		(net "ENET10G_2_SDA")
	)
	(segment
		(start 118.0592 -9.7028)
		(end 118.9228 -9.7028)
		(width 0.18288)
		(layer "In5.Cu")
		(net "ENET10G_2_SDA")
	)
	(segment
		(start 118.9228 -9.7028)
		(end 120.2436 -8.382)
		(width 0.18288)
		(layer "In5.Cu")
		(net "ENET10G_2_SDA")
	)
	(segment
		(start 121.748296 -8.382)
		(end 122.530108 -7.600188)
		(width 0.18288)
		(layer "In5.Cu")
		(net "ENET10G_2_SDA")
	)
	(segment
		(start 113.0808 -20.5994)
		(end 114.5286 -22.0472)
		(width 0.18288)
		(layer "In5.Cu")
		(net "ENET10G_2_SDA")
	)
	(segment
		(start 377.8504 -36.38296)
		(end 377.8504 -37.338)
		(width 0.508)
		(layer "F.Cu")
		(net "P3V3_10G_3_VCCR_L")
	)
	(segment
		(start 377.8504 -37.589206)
		(end 379.021594 -38.7604)
		(width 0.508)
		(layer "F.Cu")
		(net "P3V3_10G_3_VCCR_L")
	)
	(segment
		(start 377.8504 -37.338)
		(end 377.8504 -37.589206)
		(width 0.508)
		(layer "F.Cu")
		(net "P3V3_10G_3_VCCR_L")
	)
	(via
		(at 377.8504 -37.338)
		(size 0.508)
		(drill 0.254)
		(layers "F.Cu" "B.Cu")
		(net "P3V3_10G_3_VCCR_L")
	)
	(segment
		(start 114.808 -25.9842)
		(end 115.37061 -26.54681)
		(width 0.28956)
		(layer "F.Cu")
		(net "ENET10G_2_LOS")
	)
	(segment
		(start 115.37061 -26.54681)
		(end 116.91239 -26.54681)
		(width 0.28956)
		(layer "F.Cu")
		(net "ENET10G_2_LOS")
	)
	(segment
		(start 119.033798 -22.239732)
		(end 118.4148 -22.239732)
		(width 0.28956)
		(layer "F.Cu")
		(net "ENET10G_2_LOS")
	)
	(segment
		(start 114.808 -25.9588)
		(end 114.808 -25.9842)
		(width 0.28956)
		(layer "F.Cu")
		(net "ENET10G_2_LOS")
	)
	(segment
		(start 102.370128 -18.48993)
		(end 102.370128 -22.741128)
		(width 0.28956)
		(layer "F.Cu")
		(net "ENET10G_2_LOS")
	)
	(via
		(at 114.808 -25.9588)
		(size 0.508)
		(drill 0.254)
		(layers "F.Cu" "B.Cu")
		(net "ENET10G_2_LOS")
	)
	(via
		(at 102.370128 -22.741128)
		(size 0.508)
		(drill 0.254)
		(layers "F.Cu" "B.Cu")
		(net "ENET10G_2_LOS")
	)
	(via
		(at 118.4148 -22.239732)
		(size 0.508)
		(drill 0.254)
		(layers "F.Cu" "B.Cu")
		(net "ENET10G_2_LOS")
	)
	(segment
		(start 114.808 -25.9588)
		(end 115.57 -25.1968)
		(width 0.18288)
		(layer "In5.Cu")
		(net "ENET10G_2_LOS")
	)
	(segment
		(start 115.57 -25.084532)
		(end 118.4148 -22.239732)
		(width 0.18288)
		(layer "In5.Cu")
		(net "ENET10G_2_LOS")
	)
	(segment
		(start 103.81488 -24.18588)
		(end 112.47628 -24.18588)
		(width 0.18288)
		(layer "In5.Cu")
		(net "ENET10G_2_LOS")
	)
	(segment
		(start 115.57 -25.1968)
		(end 115.57 -25.084532)
		(width 0.18288)
		(layer "In5.Cu")
		(net "ENET10G_2_LOS")
	)
	(segment
		(start 112.47628 -24.18588)
		(end 114.2492 -25.9588)
		(width 0.18288)
		(layer "In5.Cu")
		(net "ENET10G_2_LOS")
	)
	(segment
		(start 102.370128 -22.741128)
		(end 103.81488 -24.18588)
		(width 0.18288)
		(layer "In5.Cu")
		(net "ENET10G_2_LOS")
	)
	(segment
		(start 114.2492 -25.9588)
		(end 114.808 -25.9588)
		(width 0.18288)
		(layer "In5.Cu")
		(net "ENET10G_2_LOS")
	)
	(segment
		(start 310.708802 -26.126694)
		(end 311.6834 -26.126694)
		(width 0.28956)
		(layer "F.Cu")
		(net "ENET10G_4_RS1")
	)
	(segment
		(start 311.6834 -26.126694)
		(end 312.67019 -26.126694)
		(width 0.28956)
		(layer "F.Cu")
		(net "ENET10G_4_RS1")
	)
	(segment
		(start 322.570094 -18.490184)
		(end 322.570094 -19.9136)
		(width 0.28956)
		(layer "F.Cu")
		(net "ENET10G_4_RS1")
	)
	(via
		(at 322.570094 -19.9136)
		(size 0.508)
		(drill 0.254)
		(layers "F.Cu" "B.Cu")
		(net "ENET10G_4_RS1")
	)
	(via
		(at 311.6834 -26.126694)
		(size 0.508)
		(drill 0.254)
		(layers "F.Cu" "B.Cu")
		(net "ENET10G_4_RS1")
	)
	(segment
		(start 311.6834 -26.126694)
		(end 316.357508 -26.126694)
		(width 0.18288)
		(layer "In5.Cu")
		(net "ENET10G_4_RS1")
	)
	(segment
		(start 321.914266 -20.569936)
		(end 321.914266 -20.569428)
		(width 0.18288)
		(layer "In5.Cu")
		(net "ENET10G_4_RS1")
	)
	(segment
		(start 316.357508 -26.126694)
		(end 321.914266 -20.569936)
		(width 0.18288)
		(layer "In5.Cu")
		(net "ENET10G_4_RS1")
	)
	(segment
		(start 321.914266 -20.569428)
		(end 322.570094 -19.9136)
		(width 0.18288)
		(layer "In5.Cu")
		(net "ENET10G_4_RS1")
	)
	(segment
		(start 104.76992 -18.48993)
		(end 104.76992 -20.5486)
		(width 0.28956)
		(layer "F.Cu")
		(net "ENET10G_2_SCL")
	)
	(segment
		(start 116.91239 -24.36241)
		(end 116.20881 -24.36241)
		(width 0.28956)
		(layer "F.Cu")
		(net "ENET10G_2_SCL")
	)
	(segment
		(start 116.20881 -24.36241)
		(end 115.2906 -23.4442)
		(width 0.28956)
		(layer "F.Cu")
		(net "ENET10G_2_SCL")
	)
	(via
		(at 104.76992 -20.5486)
		(size 0.508)
		(drill 0.254)
		(layers "F.Cu" "B.Cu")
		(net "ENET10G_2_SCL")
	)
	(via
		(at 115.2906 -23.4442)
		(size 0.508)
		(drill 0.254)
		(layers "F.Cu" "B.Cu")
		(net "ENET10G_2_SCL")
	)
	(segment
		(start 109.919008 -21.463)
		(end 112.8522 -21.463)
		(width 0.18288)
		(layer "In5.Cu")
		(net "ENET10G_2_SCL")
	)
	(segment
		(start 114.8334 -23.4442)
		(end 115.2906 -23.4442)
		(width 0.18288)
		(layer "In5.Cu")
		(net "ENET10G_2_SCL")
	)
	(segment
		(start 109.512608 -21.8694)
		(end 109.919008 -21.463)
		(width 0.18288)
		(layer "In5.Cu")
		(net "ENET10G_2_SCL")
	)
	(segment
		(start 118.9736 -11.0998)
		(end 119.204486 -10.868914)
		(width 0.18288)
		(layer "In5.Cu")
		(net "ENET10G_2_SCL")
	)
	(segment
		(start 119.204486 -10.868914)
		(end 119.205756 -10.868914)
		(width 0.18288)
		(layer "In5.Cu")
		(net "ENET10G_2_SCL")
	)
	(segment
		(start 120.29567 -9.779)
		(end 121.75109 -9.779)
		(width 0.18288)
		(layer "In5.Cu")
		(net "ENET10G_2_SCL")
	)
	(segment
		(start 119.205756 -10.868914)
		(end 120.29567 -9.779)
		(width 0.18288)
		(layer "In5.Cu")
		(net "ENET10G_2_SCL")
	)
	(segment
		(start 118.11 -11.0998)
		(end 118.9736 -11.0998)
		(width 0.18288)
		(layer "In5.Cu")
		(net "ENET10G_2_SCL")
	)
	(segment
		(start 115.2906 -23.4442)
		(end 117.1702 -21.5646)
		(width 0.18288)
		(layer "In5.Cu")
		(net "ENET10G_2_SCL")
	)
	(segment
		(start 117.1702 -21.5646)
		(end 117.1702 -12.0396)
		(width 0.18288)
		(layer "In5.Cu")
		(net "ENET10G_2_SCL")
	)
	(segment
		(start 104.76992 -20.5486)
		(end 104.76992 -20.79752)
		(width 0.18288)
		(layer "In5.Cu")
		(net "ENET10G_2_SCL")
	)
	(segment
		(start 117.1702 -12.0396)
		(end 118.11 -11.0998)
		(width 0.18288)
		(layer "In5.Cu")
		(net "ENET10G_2_SCL")
	)
	(segment
		(start 105.8418 -21.8694)
		(end 109.512608 -21.8694)
		(width 0.18288)
		(layer "In5.Cu")
		(net "ENET10G_2_SCL")
	)
	(segment
		(start 104.76992 -20.79752)
		(end 105.8418 -21.8694)
		(width 0.18288)
		(layer "In5.Cu")
		(net "ENET10G_2_SCL")
	)
	(segment
		(start 112.8522 -21.463)
		(end 114.8334 -23.4442)
		(width 0.18288)
		(layer "In5.Cu")
		(net "ENET10G_2_SCL")
	)
	(segment
		(start 121.75109 -9.779)
		(end 122.530108 -8.999982)
		(width 0.18288)
		(layer "In5.Cu")
		(net "ENET10G_2_SCL")
	)
	(segment
		(start 120.530112 -6.299962)
		(end 120.530112 -6.651498)
		(width 0.14732)
		(layer "B.Cu")
		(net "ENET1G_2_MDI2P")
	)
	(segment
		(start 123.59894 -30.851348)
		(end 123.401328 -30.91688)
		(width 0.14732)
		(layer "B.Cu")
		(net "ENET1G_2_MDI2P")
	)
	(segment
		(start 120.530112 -6.651498)
		(end 120.7262 -6.847586)
		(width 0.14732)
		(layer "B.Cu")
		(net "ENET1G_2_MDI2P")
	)
	(segment
		(start 121.793 -7.289038)
		(end 121.793 -14.147292)
		(width 0.14732)
		(layer "B.Cu")
		(net "ENET1G_2_MDI2P")
	)
	(segment
		(start 121.351548 -6.847586)
		(end 121.793 -7.289038)
		(width 0.14732)
		(layer "B.Cu")
		(net "ENET1G_2_MDI2P")
	)
	(segment
		(start 120.523 -15.417292)
		(end 120.523 -23.495)
		(width 0.14732)
		(layer "B.Cu")
		(net "ENET1G_2_MDI2P")
	)
	(segment
		(start 124.669804 -31.006796)
		(end 123.820428 -31.006796)
		(width 0.14732)
		(layer "B.Cu")
		(net "ENET1G_2_MDI2P")
	)
	(segment
		(start 123.820428 -31.006796)
		(end 123.730766 -30.917134)
		(width 0.14732)
		(layer "B.Cu")
		(net "ENET1G_2_MDI2P")
	)
	(segment
		(start 120.523 -23.495)
		(end 125.4506 -28.4226)
		(width 0.14732)
		(layer "B.Cu")
		(net "ENET1G_2_MDI2P")
	)
	(segment
		(start 120.7262 -6.847586)
		(end 121.351548 -6.847586)
		(width 0.14732)
		(layer "B.Cu")
		(net "ENET1G_2_MDI2P")
	)
	(segment
		(start 125.4506 -28.4226)
		(end 125.4506 -30.226)
		(width 0.14732)
		(layer "B.Cu")
		(net "ENET1G_2_MDI2P")
	)
	(segment
		(start 121.793 -14.147292)
		(end 120.523 -15.417292)
		(width 0.14732)
		(layer "B.Cu")
		(net "ENET1G_2_MDI2P")
	)
	(segment
		(start 123.401328 -30.91688)
		(end 122.900186 -31.919164)
		(width 0.14732)
		(layer "B.Cu")
		(net "ENET1G_2_MDI2P")
	)
	(segment
		(start 125.4506 -30.226)
		(end 124.669804 -31.006796)
		(width 0.14732)
		(layer "B.Cu")
		(net "ENET1G_2_MDI2P")
	)
	(segment
		(start 123.730766 -30.917134)
		(end 123.59894 -30.851348)
		(width 0.14732)
		(layer "B.Cu")
		(net "ENET1G_2_MDI2P")
	)
	(segment
		(start 308.3814 -35.70986)
		(end 308.3814 -34.63036)
		(width 0.508)
		(layer "F.Cu")
		(net "P3V3_10G_4_VCCT_L")
	)
	(segment
		(start 309.22087 -36.54933)
		(end 310.438546 -36.54933)
		(width 0.508)
		(layer "F.Cu")
		(net "P3V3_10G_4_VCCT_L")
	)
	(segment
		(start 309.22087 -36.54933)
		(end 308.3814 -35.70986)
		(width 0.508)
		(layer "F.Cu")
		(net "P3V3_10G_4_VCCT_L")
	)
	(via
		(at 309.22087 -36.54933)
		(size 0.508)
		(drill 0.254)
		(layers "F.Cu" "B.Cu")
		(net "P3V3_10G_4_VCCT_L")
	)
	(segment
		(start 120.594628 -23.99792)
		(end 120.594628 -24.227028)
		(width 0.14732)
		(layer "B.Cu")
		(net "ENET1G_2_MDI2N")
	)
	(segment
		(start 123.91136 -30.666436)
		(end 123.867164 -30.644338)
		(width 0.14732)
		(layer "B.Cu")
		(net "ENET1G_2_MDI2N")
	)
	(segment
		(start 125.1458 -30.099508)
		(end 124.543312 -30.701996)
		(width 0.14732)
		(layer "B.Cu")
		(net "ENET1G_2_MDI2N")
	)
	(segment
		(start 121.448576 -25.080976)
		(end 121.760996 -25.393396)
		(width 0.14732)
		(layer "B.Cu")
		(net "ENET1G_2_MDI2N")
	)
	(segment
		(start 121.760996 -25.393396)
		(end 121.990104 -25.393396)
		(width 0.14732)
		(layer "B.Cu")
		(net "ENET1G_2_MDI2N")
	)
	(segment
		(start 120.6754 -7.152386)
		(end 121.225056 -7.152386)
		(width 0.14732)
		(layer "B.Cu")
		(net "ENET1G_2_MDI2N")
	)
	(segment
		(start 120.907048 -24.539448)
		(end 121.136156 -24.539448)
		(width 0.14732)
		(layer "B.Cu")
		(net "ENET1G_2_MDI2N")
	)
	(segment
		(start 123.867164 -30.644338)
		(end 123.735338 -30.578552)
		(width 0.14732)
		(layer "B.Cu")
		(net "ENET1G_2_MDI2N")
	)
	(segment
		(start 122.302524 -25.705816)
		(end 122.302524 -25.934924)
		(width 0.14732)
		(layer "B.Cu")
		(net "ENET1G_2_MDI2N")
	)
	(segment
		(start 120.2182 -15.2908)
		(end 120.2182 -23.621492)
		(width 0.14732)
		(layer "B.Cu")
		(net "ENET1G_2_MDI2N")
	)
	(segment
		(start 124.543312 -30.701996)
		(end 123.94692 -30.701996)
		(width 0.14732)
		(layer "B.Cu")
		(net "ENET1G_2_MDI2N")
	)
	(segment
		(start 123.94692 -30.701996)
		(end 123.91136 -30.666436)
		(width 0.14732)
		(layer "B.Cu")
		(net "ENET1G_2_MDI2N")
	)
	(segment
		(start 123.669298 -30.38094)
		(end 124.170186 -29.379164)
		(width 0.14732)
		(layer "B.Cu")
		(net "ENET1G_2_MDI2N")
	)
	(segment
		(start 120.530112 -7.70001)
		(end 120.530112 -7.297674)
		(width 0.14732)
		(layer "B.Cu")
		(net "ENET1G_2_MDI2N")
	)
	(segment
		(start 121.990104 -25.393396)
		(end 122.302524 -25.705816)
		(width 0.14732)
		(layer "B.Cu")
		(net "ENET1G_2_MDI2N")
	)
	(segment
		(start 122.844052 -26.247344)
		(end 125.1458 -28.549092)
		(width 0.14732)
		(layer "B.Cu")
		(net "ENET1G_2_MDI2N")
	)
	(segment
		(start 120.530112 -7.297674)
		(end 120.6754 -7.152386)
		(width 0.14732)
		(layer "B.Cu")
		(net "ENET1G_2_MDI2N")
	)
	(segment
		(start 121.448576 -24.851868)
		(end 121.448576 -25.080976)
		(width 0.14732)
		(layer "B.Cu")
		(net "ENET1G_2_MDI2N")
	)
	(segment
		(start 121.4882 -14.0208)
		(end 120.2182 -15.2908)
		(width 0.14732)
		(layer "B.Cu")
		(net "ENET1G_2_MDI2N")
	)
	(segment
		(start 120.594628 -24.227028)
		(end 120.907048 -24.539448)
		(width 0.14732)
		(layer "B.Cu")
		(net "ENET1G_2_MDI2N")
	)
	(segment
		(start 123.735338 -30.578552)
		(end 123.669298 -30.38094)
		(width 0.14732)
		(layer "B.Cu")
		(net "ENET1G_2_MDI2N")
	)
	(segment
		(start 122.614944 -26.247344)
		(end 122.844052 -26.247344)
		(width 0.14732)
		(layer "B.Cu")
		(net "ENET1G_2_MDI2N")
	)
	(segment
		(start 121.225056 -7.152386)
		(end 121.4882 -7.41553)
		(width 0.14732)
		(layer "B.Cu")
		(net "ENET1G_2_MDI2N")
	)
	(segment
		(start 125.1458 -28.549092)
		(end 125.1458 -30.099508)
		(width 0.14732)
		(layer "B.Cu")
		(net "ENET1G_2_MDI2N")
	)
	(segment
		(start 122.302524 -25.934924)
		(end 122.614944 -26.247344)
		(width 0.14732)
		(layer "B.Cu")
		(net "ENET1G_2_MDI2N")
	)
	(segment
		(start 121.136156 -24.539448)
		(end 121.448576 -24.851868)
		(width 0.14732)
		(layer "B.Cu")
		(net "ENET1G_2_MDI2N")
	)
	(segment
		(start 121.4882 -7.41553)
		(end 121.4882 -14.0208)
		(width 0.14732)
		(layer "B.Cu")
		(net "ENET1G_2_MDI2N")
	)
	(segment
		(start 120.2182 -23.621492)
		(end 120.594628 -23.99792)
		(width 0.14732)
		(layer "B.Cu")
		(net "ENET1G_2_MDI2N")
	)
	(segment
		(start 306.324 -35.4838)
		(end 306.324 -34.60496)
		(width 0.508)
		(layer "F.Cu")
		(net "P3V3_10G_4_VCCR_L")
	)
	(segment
		(start 309.85587 -39.01567)
		(end 310.465216 -39.01567)
		(width 0.508)
		(layer "F.Cu")
		(net "P3V3_10G_4_VCCR_L")
	)
	(segment
		(start 307.6448 -36.8046)
		(end 309.85587 -39.01567)
		(width 0.508)
		(layer "F.Cu")
		(net "P3V3_10G_4_VCCR_L")
	)
	(segment
		(start 307.6448 -36.8046)
		(end 306.324 -35.4838)
		(width 0.508)
		(layer "F.Cu")
		(net "P3V3_10G_4_VCCR_L")
	)
	(via
		(at 307.6448 -36.8046)
		(size 0.508)
		(drill 0.254)
		(layers "F.Cu" "B.Cu")
		(net "P3V3_10G_4_VCCR_L")
	)
	(segment
		(start 378.01296 -33.16224)
		(end 377.8504 -33.3248)
		(width 0.508)
		(layer "F.Cu")
		(net "P3V3_10G_3_VCCR")
	)
	(segment
		(start 365.2266 -3.49885)
		(end 364.0836 -3.49885)
		(width 0.4572)
		(layer "F.Cu")
		(net "P3V3_10G_3_VCCR")
	)
	(segment
		(start 377.8504 -33.3248)
		(end 377.8504 -34.48304)
		(width 0.508)
		(layer "F.Cu")
		(net "P3V3_10G_3_VCCR")
	)
	(segment
		(start 363.290358 -10.289794)
		(end 363.290358 -11.7094)
		(width 0.4572)
		(layer "F.Cu")
		(net "P3V3_10G_3_VCCR")
	)
	(segment
		(start 364.0836 -3.49885)
		(end 363.09935 -3.49885)
		(width 0.4572)
		(layer "F.Cu")
		(net "P3V3_10G_3_VCCR")
	)
	(segment
		(start 378.01296 -32.094932)
		(end 378.01296 -33.16224)
		(width 0.508)
		(layer "F.Cu")
		(net "P3V3_10G_3_VCCR")
	)
	(segment
		(start 378.01296 -32.094932)
		(end 378.978668 -32.094932)
		(width 0.508)
		(layer "F.Cu")
		(net "P3V3_10G_3_VCCR")
	)
	(via
		(at 363.09935 -3.49885)
		(size 0.508)
		(drill 0.254)
		(layers "F.Cu" "B.Cu")
		(net "P3V3_10G_3_VCCR")
	)
	(via
		(at 378.978668 -32.094932)
		(size 0.508)
		(drill 0.254)
		(layers "F.Cu" "B.Cu")
		(net "P3V3_10G_3_VCCR")
	)
	(via
		(at 363.290358 -11.7094)
		(size 0.508)
		(drill 0.254)
		(layers "F.Cu" "B.Cu")
		(net "P3V3_10G_3_VCCR")
	)
	(segment
		(start 376.5042 -28.397454)
		(end 376.5042 -23.201122)
		(width 0.4572)
		(layer "In2.Cu")
		(net "P3V3_10G_3_VCCR")
	)
	(segment
		(start 371.761004 -18.457926)
		(end 371.761004 -7.980426)
		(width 0.4572)
		(layer "In2.Cu")
		(net "P3V3_10G_3_VCCR")
	)
	(segment
		(start 376.5042 -23.201122)
		(end 371.761004 -18.457926)
		(width 0.4572)
		(layer "In2.Cu")
		(net "P3V3_10G_3_VCCR")
	)
	(segment
		(start 378.978668 -32.094932)
		(end 378.978668 -30.871922)
		(width 0.4572)
		(layer "In2.Cu")
		(net "P3V3_10G_3_VCCR")
	)
	(segment
		(start 371.761004 -7.980426)
		(end 368.352578 -4.572)
		(width 0.4572)
		(layer "In2.Cu")
		(net "P3V3_10G_3_VCCR")
	)
	(segment
		(start 368.352578 -4.572)
		(end 364.1725 -4.572)
		(width 0.4572)
		(layer "In2.Cu")
		(net "P3V3_10G_3_VCCR")
	)
	(segment
		(start 378.978668 -30.871922)
		(end 376.5042 -28.397454)
		(width 0.4572)
		(layer "In2.Cu")
		(net "P3V3_10G_3_VCCR")
	)
	(segment
		(start 364.1725 -4.572)
		(end 363.09935 -3.49885)
		(width 0.4572)
		(layer "In2.Cu")
		(net "P3V3_10G_3_VCCR")
	)
	(segment
		(start 357.626666 -7.6962)
		(end 357.626666 -8.636)
		(width 0.4572)
		(layer "In5.Cu")
		(net "P3V3_10G_3_VCCR")
	)
	(segment
		(start 363.09935 -3.49885)
		(end 361.824016 -3.49885)
		(width 0.4572)
		(layer "In5.Cu")
		(net "P3V3_10G_3_VCCR")
	)
	(segment
		(start 362.859066 -12.319)
		(end 363.290358 -11.887708)
		(width 0.4572)
		(layer "In5.Cu")
		(net "P3V3_10G_3_VCCR")
	)
	(segment
		(start 363.290358 -11.887708)
		(end 363.290358 -11.7094)
		(width 0.4572)
		(layer "In5.Cu")
		(net "P3V3_10G_3_VCCR")
	)
	(segment
		(start 358.922066 -11.4808)
		(end 359.760266 -12.319)
		(width 0.4572)
		(layer "In5.Cu")
		(net "P3V3_10G_3_VCCR")
	)
	(segment
		(start 358.922066 -9.9314)
		(end 358.922066 -11.4808)
		(width 0.4572)
		(layer "In5.Cu")
		(net "P3V3_10G_3_VCCR")
	)
	(segment
		(start 357.626666 -8.636)
		(end 358.922066 -9.9314)
		(width 0.4572)
		(layer "In5.Cu")
		(net "P3V3_10G_3_VCCR")
	)
	(segment
		(start 361.824016 -3.49885)
		(end 357.626666 -7.6962)
		(width 0.4572)
		(layer "In5.Cu")
		(net "P3V3_10G_3_VCCR")
	)
	(segment
		(start 359.760266 -12.319)
		(end 362.859066 -12.319)
		(width 0.4572)
		(layer "In5.Cu")
		(net "P3V3_10G_3_VCCR")
	)
	(segment
		(start 379.9332 -37.5412)
		(end 379.9332 -40.288464)
		(width 0.508)
		(layer "F.Cu")
		(net "P3V3_10G_3_VCCT_L")
	)
	(segment
		(start 379.9332 -40.288464)
		(end 378.99975 -41.221914)
		(width 0.508)
		(layer "F.Cu")
		(net "P3V3_10G_3_VCCT_L")
	)
	(segment
		(start 379.9332 -36.38296)
		(end 379.9332 -37.5412)
		(width 0.508)
		(layer "F.Cu")
		(net "P3V3_10G_3_VCCT_L")
	)
	(via
		(at 379.9332 -37.5412)
		(size 0.508)
		(drill 0.254)
		(layers "F.Cu" "B.Cu")
		(net "P3V3_10G_3_VCCT_L")
	)
	(segment
		(start 336.559906 -22.946106)
		(end 335.915 -22.3012)
		(width 0.28956)
		(layer "F.Cu")
		(net "ENET10G_4_SCL")
	)
	(segment
		(start 325.769986 -18.490184)
		(end 325.769986 -21.7678)
		(width 0.28956)
		(layer "F.Cu")
		(net "ENET10G_4_SCL")
	)
	(segment
		(start 337.727798 -22.946106)
		(end 336.559906 -22.946106)
		(width 0.28956)
		(layer "F.Cu")
		(net "ENET10G_4_SCL")
	)
	(via
		(at 335.915 -22.3012)
		(size 0.508)
		(drill 0.254)
		(layers "F.Cu" "B.Cu")
		(net "ENET10G_4_SCL")
	)
	(via
		(at 325.769986 -21.7678)
		(size 0.508)
		(drill 0.254)
		(layers "F.Cu" "B.Cu")
		(net "ENET10G_4_SCL")
	)
	(segment
		(start 336.55 -13.589)
		(end 339.0392 -11.0998)
		(width 0.18288)
		(layer "In5.Cu")
		(net "ENET10G_4_SCL")
	)
	(segment
		(start 333.746094 -21.4884)
		(end 334.558894 -22.3012)
		(width 0.18288)
		(layer "In5.Cu")
		(net "ENET10G_4_SCL")
	)
	(segment
		(start 335.915 -22.3012)
		(end 336.55 -21.6662)
		(width 0.18288)
		(layer "In5.Cu")
		(net "ENET10G_4_SCL")
	)
	(segment
		(start 339.974936 -11.0998)
		(end 341.295736 -9.779)
		(width 0.18288)
		(layer "In5.Cu")
		(net "ENET10G_4_SCL")
	)
	(segment
		(start 339.0392 -11.0998)
		(end 339.974936 -11.0998)
		(width 0.18288)
		(layer "In5.Cu")
		(net "ENET10G_4_SCL")
	)
	(segment
		(start 331.47 -21.4884)
		(end 333.746094 -21.4884)
		(width 0.18288)
		(layer "In5.Cu")
		(net "ENET10G_4_SCL")
	)
	(segment
		(start 336.55 -21.6662)
		(end 336.55 -13.589)
		(width 0.18288)
		(layer "In5.Cu")
		(net "ENET10G_4_SCL")
	)
	(segment
		(start 325.769986 -21.7678)
		(end 326.100186 -22.098)
		(width 0.18288)
		(layer "In5.Cu")
		(net "ENET10G_4_SCL")
	)
	(segment
		(start 326.100186 -22.098)
		(end 330.8604 -22.098)
		(width 0.18288)
		(layer "In5.Cu")
		(net "ENET10G_4_SCL")
	)
	(segment
		(start 330.8604 -22.098)
		(end 331.47 -21.4884)
		(width 0.18288)
		(layer "In5.Cu")
		(net "ENET10G_4_SCL")
	)
	(segment
		(start 341.295736 -9.779)
		(end 342.751156 -9.779)
		(width 0.18288)
		(layer "In5.Cu")
		(net "ENET10G_4_SCL")
	)
	(segment
		(start 342.751156 -9.779)
		(end 343.530174 -8.999982)
		(width 0.18288)
		(layer "In5.Cu")
		(net "ENET10G_4_SCL")
	)
	(segment
		(start 334.558894 -22.3012)
		(end 335.915 -22.3012)
		(width 0.18288)
		(layer "In5.Cu")
		(net "ENET10G_4_SCL")
	)
	(segment
		(start 378.031502 -27.776678)
		(end 377.1392 -27.776678)
		(width 0.28956)
		(layer "F.Cu")
		(net "ENET10G_3_RS1")
	)
	(segment
		(start 363.015022 -22.479)
		(end 363.0676 -22.479)
		(width 0.28956)
		(layer "F.Cu")
		(net "ENET10G_3_RS1")
	)
	(segment
		(start 376.22861 -27.776678)
		(end 377.1392 -27.776678)
		(width 0.28956)
		(layer "F.Cu")
		(net "ENET10G_3_RS1")
	)
	(segment
		(start 360.490262 -19.95424)
		(end 363.015022 -22.479)
		(width 0.28956)
		(layer "F.Cu")
		(net "ENET10G_3_RS1")
	)
	(segment
		(start 360.490262 -18.48993)
		(end 360.490262 -19.95424)
		(width 0.28956)
		(layer "F.Cu")
		(net "ENET10G_3_RS1")
	)
	(via
		(at 363.0676 -22.479)
		(size 0.508)
		(drill 0.254)
		(layers "F.Cu" "B.Cu")
		(net "ENET10G_3_RS1")
	)
	(via
		(at 377.1392 -27.776678)
		(size 0.508)
		(drill 0.254)
		(layers "F.Cu" "B.Cu")
		(net "ENET10G_3_RS1")
	)
	(segment
		(start 363.5502 -22.9616)
		(end 363.0676 -22.479)
		(width 0.18288)
		(layer "In5.Cu")
		(net "ENET10G_3_RS1")
	)
	(segment
		(start 366.5474 -22.9616)
		(end 363.5502 -22.9616)
		(width 0.18288)
		(layer "In5.Cu")
		(net "ENET10G_3_RS1")
	)
	(segment
		(start 377.1392 -27.776678)
		(end 371.362478 -27.776678)
		(width 0.18288)
		(layer "In5.Cu")
		(net "ENET10G_3_RS1")
	)
	(segment
		(start 371.362478 -27.776678)
		(end 366.5474 -22.9616)
		(width 0.18288)
		(layer "In5.Cu")
		(net "ENET10G_3_RS1")
	)
	(segment
		(start 324.17004 -18.490184)
		(end 324.17004 -20.066)
		(width 0.28956)
		(layer "F.Cu")
		(net "ENET10G_4_RS0")
	)
	(segment
		(start 311.658 -27.523694)
		(end 310.708802 -27.523694)
		(width 0.28956)
		(layer "F.Cu")
		(net "ENET10G_4_RS0")
	)
	(segment
		(start 312.67019 -27.523694)
		(end 311.658 -27.523694)
		(width 0.28956)
		(layer "F.Cu")
		(net "ENET10G_4_RS0")
	)
	(via
		(at 311.658 -27.523694)
		(size 0.508)
		(drill 0.254)
		(layers "F.Cu" "B.Cu")
		(net "ENET10G_4_RS0")
	)
	(via
		(at 324.17004 -20.066)
		(size 0.508)
		(drill 0.254)
		(layers "F.Cu" "B.Cu")
		(net "ENET10G_4_RS0")
	)
	(segment
		(start 311.658 -27.523694)
		(end 315.853572 -27.523694)
		(width 0.18288)
		(layer "In5.Cu")
		(net "ENET10G_4_RS0")
	)
	(segment
		(start 315.853572 -27.523694)
		(end 323.311266 -20.066)
		(width 0.18288)
		(layer "In5.Cu")
		(net "ENET10G_4_RS0")
	)
	(segment
		(start 323.311266 -20.066)
		(end 324.17004 -20.066)
		(width 0.18288)
		(layer "In5.Cu")
		(net "ENET10G_4_RS0")
	)
	(segment
		(start 326.570086 -18.490184)
		(end 326.570086 -21.4122)
		(width 0.28956)
		(layer "F.Cu")
		(net "ENET10G_4_SDA")
	)
	(segment
		(start 335.661 -20.9804)
		(end 336.3214 -20.9804)
		(width 0.28956)
		(layer "F.Cu")
		(net "ENET10G_4_SDA")
	)
	(segment
		(start 336.3214 -20.9804)
		(end 337.144106 -21.803106)
		(width 0.28956)
		(layer "F.Cu")
		(net "ENET10G_4_SDA")
	)
	(segment
		(start 337.144106 -21.803106)
		(end 337.727798 -21.803106)
		(width 0.28956)
		(layer "F.Cu")
		(net "ENET10G_4_SDA")
	)
	(via
		(at 335.661 -20.9804)
		(size 0.508)
		(drill 0.254)
		(layers "F.Cu" "B.Cu")
		(net "ENET10G_4_SDA")
	)
	(via
		(at 326.570086 -21.4122)
		(size 0.508)
		(drill 0.254)
		(layers "F.Cu" "B.Cu")
		(net "ENET10G_4_SDA")
	)
	(segment
		(start 331.089 -20.828)
		(end 334.4672 -20.828)
		(width 0.18288)
		(layer "In5.Cu")
		(net "ENET10G_4_SDA")
	)
	(segment
		(start 340.811866 -8.382)
		(end 342.748362 -8.382)
		(width 0.18288)
		(layer "In5.Cu")
		(net "ENET10G_4_SDA")
	)
	(segment
		(start 326.570086 -21.4122)
		(end 330.5048 -21.4122)
		(width 0.18288)
		(layer "In5.Cu")
		(net "ENET10G_4_SDA")
	)
	(segment
		(start 334.6196 -20.9804)
		(end 335.661 -20.9804)
		(width 0.18288)
		(layer "In5.Cu")
		(net "ENET10G_4_SDA")
	)
	(segment
		(start 335.661 -12.745466)
		(end 338.729066 -9.6774)
		(width 0.18288)
		(layer "In5.Cu")
		(net "ENET10G_4_SDA")
	)
	(segment
		(start 339.872066 -9.6774)
		(end 340.227666 -9.3218)
		(width 0.18288)
		(layer "In5.Cu")
		(net "ENET10G_4_SDA")
	)
	(segment
		(start 335.661 -20.9804)
		(end 335.661 -12.745466)
		(width 0.18288)
		(layer "In5.Cu")
		(net "ENET10G_4_SDA")
	)
	(segment
		(start 334.4672 -20.828)
		(end 334.6196 -20.9804)
		(width 0.18288)
		(layer "In5.Cu")
		(net "ENET10G_4_SDA")
	)
	(segment
		(start 340.227666 -8.9662)
		(end 340.811866 -8.382)
		(width 0.18288)
		(layer "In5.Cu")
		(net "ENET10G_4_SDA")
	)
	(segment
		(start 338.729066 -9.6774)
		(end 339.872066 -9.6774)
		(width 0.18288)
		(layer "In5.Cu")
		(net "ENET10G_4_SDA")
	)
	(segment
		(start 342.748362 -8.382)
		(end 343.530174 -7.600188)
		(width 0.18288)
		(layer "In5.Cu")
		(net "ENET10G_4_SDA")
	)
	(segment
		(start 340.227666 -9.3218)
		(end 340.227666 -8.9662)
		(width 0.18288)
		(layer "In5.Cu")
		(net "ENET10G_4_SDA")
	)
	(segment
		(start 330.5048 -21.4122)
		(end 331.089 -20.828)
		(width 0.18288)
		(layer "In5.Cu")
		(net "ENET10G_4_SDA")
	)
	(segment
		(start 324.97014 -18.490184)
		(end 324.97014 -22.1488)
		(width 0.28956)
		(layer "F.Cu")
		(net "ENET10G_4_MOD_DEF0")
	)
	(segment
		(start 337.727798 -24.038306)
		(end 336.102706 -24.038306)
		(width 0.28956)
		(layer "F.Cu")
		(net "ENET10G_4_MOD_DEF0")
	)
	(segment
		(start 336.102706 -24.038306)
		(end 335.6356 -23.5712)
		(width 0.28956)
		(layer "F.Cu")
		(net "ENET10G_4_MOD_DEF0")
	)
	(segment
		(start 337.693 -20.6756)
		(end 337.947 -20.4216)
		(width 0.28956)
		(layer "F.Cu")
		(net "ENET10G_4_MOD_DEF0")
	)
	(segment
		(start 337.947 -20.4216)
		(end 339.135466 -20.4216)
		(width 0.28956)
		(layer "F.Cu")
		(net "ENET10G_4_MOD_DEF0")
	)
	(segment
		(start 339.135466 -20.4216)
		(end 339.861398 -21.147532)
		(width 0.28956)
		(layer "F.Cu")
		(net "ENET10G_4_MOD_DEF0")
	)
	(via
		(at 324.97014 -22.1488)
		(size 0.508)
		(drill 0.254)
		(layers "F.Cu" "B.Cu")
		(net "ENET10G_4_MOD_DEF0")
	)
	(via
		(at 335.6356 -23.5712)
		(size 0.508)
		(drill 0.254)
		(layers "F.Cu" "B.Cu")
		(net "ENET10G_4_MOD_DEF0")
	)
	(via
		(at 337.693 -20.6756)
		(size 0.508)
		(drill 0.254)
		(layers "F.Cu" "B.Cu")
		(net "ENET10G_4_MOD_DEF0")
	)
	(segment
		(start 326.39254 -23.5712)
		(end 335.6356 -23.5712)
		(width 0.18288)
		(layer "In5.Cu")
		(net "ENET10G_4_MOD_DEF0")
	)
	(segment
		(start 337.693 -21.5138)
		(end 337.693 -20.6756)
		(width 0.18288)
		(layer "In5.Cu")
		(net "ENET10G_4_MOD_DEF0")
	)
	(segment
		(start 335.6356 -23.5712)
		(end 337.693 -21.5138)
		(width 0.18288)
		(layer "In5.Cu")
		(net "ENET10G_4_MOD_DEF0")
	)
	(segment
		(start 324.97014 -22.1488)
		(end 326.39254 -23.5712)
		(width 0.18288)
		(layer "In5.Cu")
		(net "ENET10G_4_MOD_DEF0")
	)
	(segment
		(start 322.7578 -3.04165)
		(end 323.2404 -3.04165)
		(width 0.4572)
		(layer "F.Cu")
		(net "P3V3_10G_4_VCCR")
	)
	(segment
		(start 307.55844 -31.4706)
		(end 306.324 -32.70504)
		(width 0.508)
		(layer "F.Cu")
		(net "P3V3_10G_4_VCCR")
	)
	(segment
		(start 322.7578 -3.048)
		(end 322.7578 -3.04165)
		(width 0.4572)
		(layer "F.Cu")
		(net "P3V3_10G_4_VCCR")
	)
	(segment
		(start 322.2498 -3.556)
		(end 322.7578 -3.048)
		(width 0.4572)
		(layer "F.Cu")
		(net "P3V3_10G_4_VCCR")
	)
	(segment
		(start 309.7276 -31.4706)
		(end 310.322468 -32.065468)
		(width 0.508)
		(layer "F.Cu")
		(net "P3V3_10G_4_VCCR")
	)
	(segment
		(start 323.2404 -3.04165)
		(end 324.358 -3.04165)
		(width 0.4572)
		(layer "F.Cu")
		(net "P3V3_10G_4_VCCR")
	)
	(segment
		(start 310.322468 -32.065468)
		(end 311.19064 -32.065468)
		(width 0.508)
		(layer "F.Cu")
		(net "P3V3_10G_4_VCCR")
	)
	(segment
		(start 309.7276 -31.4706)
		(end 307.55844 -31.4706)
		(width 0.508)
		(layer "F.Cu")
		(net "P3V3_10G_4_VCCR")
	)
	(segment
		(start 325.37019 -10.290048)
		(end 325.37019 -11.7348)
		(width 0.4572)
		(layer "F.Cu")
		(net "P3V3_10G_4_VCCR")
	)
	(via
		(at 325.37019 -11.7348)
		(size 0.508)
		(drill 0.254)
		(layers "F.Cu" "B.Cu")
		(net "P3V3_10G_4_VCCR")
	)
	(via
		(at 309.7276 -31.4706)
		(size 0.508)
		(drill 0.254)
		(layers "F.Cu" "B.Cu")
		(net "P3V3_10G_4_VCCR")
	)
	(via
		(at 322.2498 -3.556)
		(size 0.508)
		(drill 0.254)
		(layers "F.Cu" "B.Cu")
		(net "P3V3_10G_4_VCCR")
	)
	(segment
		(start 316.552834 -22.80539)
		(end 316.552834 -8.17499)
		(width 0.4572)
		(layer "In2.Cu")
		(net "P3V3_10G_4_VCCR")
	)
	(segment
		(start 311.392824 -31.4706)
		(end 312.2676 -30.595824)
		(width 0.4572)
		(layer "In2.Cu")
		(net "P3V3_10G_4_VCCR")
	)
	(segment
		(start 312.2676 -27.090624)
		(end 316.552834 -22.80539)
		(width 0.4572)
		(layer "In2.Cu")
		(net "P3V3_10G_4_VCCR")
	)
	(segment
		(start 309.7276 -31.4706)
		(end 311.392824 -31.4706)
		(width 0.4572)
		(layer "In2.Cu")
		(net "P3V3_10G_4_VCCR")
	)
	(segment
		(start 312.2676 -30.595824)
		(end 312.2676 -27.090624)
		(width 0.4572)
		(layer "In2.Cu")
		(net "P3V3_10G_4_VCCR")
	)
	(segment
		(start 316.552834 -8.17499)
		(end 321.171824 -3.556)
		(width 0.4572)
		(layer "In2.Cu")
		(net "P3V3_10G_4_VCCR")
	)
	(segment
		(start 321.171824 -3.556)
		(end 322.2498 -3.556)
		(width 0.4572)
		(layer "In2.Cu")
		(net "P3V3_10G_4_VCCR")
	)
	(segment
		(start 321.152266 -11.6078)
		(end 321.914266 -12.3698)
		(width 0.4572)
		(layer "In5.Cu")
		(net "P3V3_10G_4_VCCR")
	)
	(segment
		(start 322.2498 -3.556)
		(end 319.552066 -6.253734)
		(width 0.4572)
		(layer "In5.Cu")
		(net "P3V3_10G_4_VCCR")
	)
	(segment
		(start 319.552066 -6.253734)
		(end 319.552066 -8.5598)
		(width 0.4572)
		(layer "In5.Cu")
		(net "P3V3_10G_4_VCCR")
	)
	(segment
		(start 321.152266 -10.16)
		(end 321.152266 -11.6078)
		(width 0.4572)
		(layer "In5.Cu")
		(net "P3V3_10G_4_VCCR")
	)
	(segment
		(start 324.96379 -12.3698)
		(end 325.37019 -11.9634)
		(width 0.4572)
		(layer "In5.Cu")
		(net "P3V3_10G_4_VCCR")
	)
	(segment
		(start 321.914266 -12.3698)
		(end 324.96379 -12.3698)
		(width 0.4572)
		(layer "In5.Cu")
		(net "P3V3_10G_4_VCCR")
	)
	(segment
		(start 325.37019 -11.9634)
		(end 325.37019 -11.7348)
		(width 0.4572)
		(layer "In5.Cu")
		(net "P3V3_10G_4_VCCR")
	)
	(segment
		(start 319.552066 -8.5598)
		(end 321.152266 -10.16)
		(width 0.4572)
		(layer "In5.Cu")
		(net "P3V3_10G_4_VCCR")
	)
	(segment
		(start 121.071894 -3.003296)
		(end 120.694704 -3.003296)
		(width 0.1524)
		(layer "In2.Cu")
		(net "ENET1G_2_MDI1N")
	)
	(segment
		(start 120.0404 -28.956)
		(end 122.428 -26.5684)
		(width 0.1524)
		(layer "In2.Cu")
		(net "ENET1G_2_MDI1N")
	)
	(segment
		(start 120.694704 -3.003296)
		(end 120.530112 -3.167888)
		(width 0.1524)
		(layer "In2.Cu")
		(net "ENET1G_2_MDI1N")
	)
	(segment
		(start 121.2596 -3.191002)
		(end 121.071894 -3.003296)
		(width 0.1524)
		(layer "In2.Cu")
		(net "ENET1G_2_MDI1N")
	)
	(segment
		(start 120.530112 -3.167888)
		(end 120.530112 -3.50012)
		(width 0.1524)
		(layer "In2.Cu")
		(net "ENET1G_2_MDI1N")
	)
	(segment
		(start 120.8024 -30.7848)
		(end 120.0404 -30.0228)
		(width 0.1524)
		(layer "In2.Cu")
		(net "ENET1G_2_MDI1N")
	)
	(segment
		(start 125.440186 -31.919164)
		(end 124.305822 -30.7848)
		(width 0.1524)
		(layer "In2.Cu")
		(net "ENET1G_2_MDI1N")
	)
	(segment
		(start 120.0404 -30.0228)
		(end 120.0404 -28.956)
		(width 0.1524)
		(layer "In2.Cu")
		(net "ENET1G_2_MDI1N")
	)
	(segment
		(start 121.2596 -18.796)
		(end 121.2596 -3.191002)
		(width 0.1524)
		(layer "In2.Cu")
		(net "ENET1G_2_MDI1N")
	)
	(segment
		(start 124.305822 -30.7848)
		(end 120.8024 -30.7848)
		(width 0.1524)
		(layer "In2.Cu")
		(net "ENET1G_2_MDI1N")
	)
	(segment
		(start 122.428 -19.9644)
		(end 121.2596 -18.796)
		(width 0.1524)
		(layer "In2.Cu")
		(net "ENET1G_2_MDI1N")
	)
	(segment
		(start 122.428 -26.5684)
		(end 122.428 -19.9644)
		(width 0.1524)
		(layer "In2.Cu")
		(net "ENET1G_2_MDI1N")
	)
	(segment
		(start 310.708802 -28.966922)
		(end 311.6326 -28.966922)
		(width 0.28956)
		(layer "F.Cu")
		(net "ENET10G_4_TX_DIS")
	)
	(segment
		(start 311.6326 -28.966922)
		(end 312.67019 -28.966922)
		(width 0.28956)
		(layer "F.Cu")
		(net "ENET10G_4_TX_DIS")
	)
	(segment
		(start 327.370186 -18.490184)
		(end 327.370186 -19.9136)
		(width 0.28956)
		(layer "F.Cu")
		(net "ENET10G_4_TX_DIS")
	)
	(via
		(at 327.370186 -19.9136)
		(size 0.508)
		(drill 0.254)
		(layers "F.Cu" "B.Cu")
		(net "ENET10G_4_TX_DIS")
	)
	(via
		(at 311.6326 -28.966922)
		(size 0.508)
		(drill 0.254)
		(layers "F.Cu" "B.Cu")
		(net "ENET10G_4_TX_DIS")
	)
	(segment
		(start 322.80733 -21.2598)
		(end 324.2564 -21.2598)
		(width 0.18288)
		(layer "In5.Cu")
		(net "ENET10G_4_TX_DIS")
	)
	(segment
		(start 324.2564 -21.2598)
		(end 325.6026 -19.9136)
		(width 0.18288)
		(layer "In5.Cu")
		(net "ENET10G_4_TX_DIS")
	)
	(segment
		(start 325.6026 -19.9136)
		(end 327.370186 -19.9136)
		(width 0.18288)
		(layer "In5.Cu")
		(net "ENET10G_4_TX_DIS")
	)
	(segment
		(start 311.6326 -28.966922)
		(end 315.100208 -28.966922)
		(width 0.18288)
		(layer "In5.Cu")
		(net "ENET10G_4_TX_DIS")
	)
	(segment
		(start 315.100208 -28.966922)
		(end 322.80733 -21.2598)
		(width 0.18288)
		(layer "In5.Cu")
		(net "ENET10G_4_TX_DIS")
	)
	(segment
		(start 120.4468 -29.124402)
		(end 122.8344 -26.736802)
		(width 0.1524)
		(layer "In2.Cu")
		(net "ENET1G_2_MDI1P")
	)
	(segment
		(start 120.7262 -2.596896)
		(end 120.530112 -2.400808)
		(width 0.1524)
		(layer "In2.Cu")
		(net "ENET1G_2_MDI1P")
	)
	(segment
		(start 120.970802 -30.3784)
		(end 120.4468 -29.854398)
		(width 0.1524)
		(layer "In2.Cu")
		(net "ENET1G_2_MDI1P")
	)
	(segment
		(start 121.630186 -29.379164)
		(end 122.825764 -29.379164)
		(width 0.1524)
		(layer "In2.Cu")
		(net "ENET1G_2_MDI1P")
	)
	(segment
		(start 121.666 -3.0226)
		(end 121.240296 -2.596896)
		(width 0.1524)
		(layer "In2.Cu")
		(net "ENET1G_2_MDI1P")
	)
	(segment
		(start 120.530112 -2.400808)
		(end 120.530112 -2.100072)
		(width 0.1524)
		(layer "In2.Cu")
		(net "ENET1G_2_MDI1P")
	)
	(segment
		(start 122.8344 -26.736802)
		(end 122.8344 -19.795998)
		(width 0.1524)
		(layer "In2.Cu")
		(net "ENET1G_2_MDI1P")
	)
	(segment
		(start 123.0884 -30.1752)
		(end 122.8852 -30.3784)
		(width 0.1524)
		(layer "In2.Cu")
		(net "ENET1G_2_MDI1P")
	)
	(segment
		(start 122.8852 -30.3784)
		(end 120.970802 -30.3784)
		(width 0.1524)
		(layer "In2.Cu")
		(net "ENET1G_2_MDI1P")
	)
	(segment
		(start 120.4468 -29.854398)
		(end 120.4468 -29.124402)
		(width 0.1524)
		(layer "In2.Cu")
		(net "ENET1G_2_MDI1P")
	)
	(segment
		(start 122.825764 -29.379164)
		(end 123.0884 -29.6418)
		(width 0.1524)
		(layer "In2.Cu")
		(net "ENET1G_2_MDI1P")
	)
	(segment
		(start 122.8344 -19.795998)
		(end 121.666 -18.627598)
		(width 0.1524)
		(layer "In2.Cu")
		(net "ENET1G_2_MDI1P")
	)
	(segment
		(start 123.0884 -29.6418)
		(end 123.0884 -30.1752)
		(width 0.1524)
		(layer "In2.Cu")
		(net "ENET1G_2_MDI1P")
	)
	(segment
		(start 121.666 -18.627598)
		(end 121.666 -3.0226)
		(width 0.1524)
		(layer "In2.Cu")
		(net "ENET1G_2_MDI1P")
	)
	(segment
		(start 121.240296 -2.596896)
		(end 120.7262 -2.596896)
		(width 0.1524)
		(layer "In2.Cu")
		(net "ENET1G_2_MDI1P")
	)
	(segment
		(start 338.6836 -21.061934)
		(end 338.6836 -21.0566)
		(width 0.28956)
		(layer "F.Cu")
		(net "ENET10G_4_LOS")
	)
	(segment
		(start 337.753198 -25.206706)
		(end 336.042 -25.206706)
		(width 0.28956)
		(layer "F.Cu")
		(net "ENET10G_4_LOS")
	)
	(segment
		(start 323.370194 -18.490184)
		(end 323.370194 -22.6314)
		(width 0.28956)
		(layer "F.Cu")
		(net "ENET10G_4_LOS")
	)
	(segment
		(start 339.861398 -22.239732)
		(end 338.6836 -21.061934)
		(width 0.28956)
		(layer "F.Cu")
		(net "ENET10G_4_LOS")
	)
	(via
		(at 336.042 -25.206706)
		(size 0.508)
		(drill 0.254)
		(layers "F.Cu" "B.Cu")
		(net "ENET10G_4_LOS")
	)
	(via
		(at 323.370194 -22.6314)
		(size 0.508)
		(drill 0.254)
		(layers "F.Cu" "B.Cu")
		(net "ENET10G_4_LOS")
	)
	(via
		(at 338.6836 -21.0566)
		(size 0.508)
		(drill 0.254)
		(layers "F.Cu" "B.Cu")
		(net "ENET10G_4_LOS")
	)
	(segment
		(start 338.709 -21.082)
		(end 338.6836 -21.0566)
		(width 0.18288)
		(layer "In5.Cu")
		(net "ENET10G_4_LOS")
	)
	(segment
		(start 336.042 -25.206706)
		(end 336.042 -24.3078)
		(width 0.18288)
		(layer "In5.Cu")
		(net "ENET10G_4_LOS")
	)
	(segment
		(start 326.236076 -24.1046)
		(end 333.9338 -24.1046)
		(width 0.18288)
		(layer "In5.Cu")
		(net "ENET10G_4_LOS")
	)
	(segment
		(start 324.762876 -22.6314)
		(end 326.236076 -24.1046)
		(width 0.18288)
		(layer "In5.Cu")
		(net "ENET10G_4_LOS")
	)
	(segment
		(start 338.709 -21.6408)
		(end 338.709 -21.082)
		(width 0.18288)
		(layer "In5.Cu")
		(net "ENET10G_4_LOS")
	)
	(segment
		(start 336.042 -24.3078)
		(end 338.709 -21.6408)
		(width 0.18288)
		(layer "In5.Cu")
		(net "ENET10G_4_LOS")
	)
	(segment
		(start 335.035906 -25.206706)
		(end 336.042 -25.206706)
		(width 0.18288)
		(layer "In5.Cu")
		(net "ENET10G_4_LOS")
	)
	(segment
		(start 323.370194 -22.6314)
		(end 324.762876 -22.6314)
		(width 0.18288)
		(layer "In5.Cu")
		(net "ENET10G_4_LOS")
	)
	(segment
		(start 333.9338 -24.1046)
		(end 335.035906 -25.206706)
		(width 0.18288)
		(layer "In5.Cu")
		(net "ENET10G_4_LOS")
	)
	(segment
		(start 308.3814 -32.73044)
		(end 309.1942 -32.73044)
		(width 0.508)
		(layer "F.Cu")
		(net "P3V3_10G_4_VCCT")
	)
	(segment
		(start 309.7784 -32.8676)
		(end 309.7784 -33.4264)
		(width 0.508)
		(layer "F.Cu")
		(net "P3V3_10G_4_VCCT")
	)
	(segment
		(start 309.33136 -32.8676)
		(end 309.7784 -32.8676)
		(width 0.508)
		(layer "F.Cu")
		(net "P3V3_10G_4_VCCT")
	)
	(segment
		(start 326.644 -3.04165)
		(end 327.60285 -3.04165)
		(width 0.4572)
		(layer "F.Cu")
		(net "P3V3_10G_4_VCCT")
	)
	(segment
		(start 310.525668 -34.173668)
		(end 311.19064 -34.173668)
		(width 0.508)
		(layer "F.Cu")
		(net "P3V3_10G_4_VCCT")
	)
	(segment
		(start 326.170036 -10.290048)
		(end 326.170036 -11.7094)
		(width 0.4572)
		(layer "F.Cu")
		(net "P3V3_10G_4_VCCT")
	)
	(segment
		(start 326.644 -3.04165)
		(end 325.5264 -3.04165)
		(width 0.4572)
		(layer "F.Cu")
		(net "P3V3_10G_4_VCCT")
	)
	(segment
		(start 309.7784 -33.4264)
		(end 310.525668 -34.173668)
		(width 0.508)
		(layer "F.Cu")
		(net "P3V3_10G_4_VCCT")
	)
	(segment
		(start 309.1942 -32.73044)
		(end 309.33136 -32.8676)
		(width 0.508)
		(layer "F.Cu")
		(net "P3V3_10G_4_VCCT")
	)
	(via
		(at 327.60285 -3.04165)
		(size 0.508)
		(drill 0.254)
		(layers "F.Cu" "B.Cu")
		(net "P3V3_10G_4_VCCT")
	)
	(via
		(at 309.7784 -32.8676)
		(size 0.508)
		(drill 0.254)
		(layers "F.Cu" "B.Cu")
		(net "P3V3_10G_4_VCCT")
	)
	(via
		(at 326.170036 -11.7094)
		(size 0.508)
		(drill 0.254)
		(layers "F.Cu" "B.Cu")
		(net "P3V3_10G_4_VCCT")
	)
	(segment
		(start 326.3265 -4.318)
		(end 327.60285 -3.04165)
		(width 0.4572)
		(layer "In2.Cu")
		(net "P3V3_10G_4_VCCT")
	)
	(segment
		(start 309.7784 -32.8676)
		(end 311.073546 -32.8676)
		(width 0.4572)
		(layer "In2.Cu")
		(net "P3V3_10G_4_VCCT")
	)
	(segment
		(start 313.0804 -27.3558)
		(end 317.314834 -23.121366)
		(width 0.4572)
		(layer "In2.Cu")
		(net "P3V3_10G_4_VCCT")
	)
	(segment
		(start 313.0804 -30.860746)
		(end 313.0804 -27.3558)
		(width 0.4572)
		(layer "In2.Cu")
		(net "P3V3_10G_4_VCCT")
	)
	(segment
		(start 311.073546 -32.8676)
		(end 313.0804 -30.860746)
		(width 0.4572)
		(layer "In2.Cu")
		(net "P3V3_10G_4_VCCT")
	)
	(segment
		(start 317.314834 -8.490966)
		(end 321.4878 -4.318)
		(width 0.4572)
		(layer "In2.Cu")
		(net "P3V3_10G_4_VCCT")
	)
	(segment
		(start 317.314834 -23.121366)
		(end 317.314834 -8.490966)
		(width 0.4572)
		(layer "In2.Cu")
		(net "P3V3_10G_4_VCCT")
	)
	(segment
		(start 321.4878 -4.318)
		(end 326.3265 -4.318)
		(width 0.4572)
		(layer "In2.Cu")
		(net "P3V3_10G_4_VCCT")
	)
	(segment
		(start 321.945 -2.7178)
		(end 318.764666 -5.898134)
		(width 0.4572)
		(layer "In5.Cu")
		(net "P3V3_10G_4_VCCT")
	)
	(segment
		(start 320.288666 -10.414)
		(end 320.288666 -11.8618)
		(width 0.4572)
		(layer "In5.Cu")
		(net "P3V3_10G_4_VCCT")
	)
	(segment
		(start 326.170036 -12.38123)
		(end 326.170036 -11.7094)
		(width 0.4572)
		(layer "In5.Cu")
		(net "P3V3_10G_4_VCCT")
	)
	(segment
		(start 321.584066 -13.1572)
		(end 325.394066 -13.1572)
		(width 0.4572)
		(layer "In5.Cu")
		(net "P3V3_10G_4_VCCT")
	)
	(segment
		(start 320.288666 -11.8618)
		(end 321.584066 -13.1572)
		(width 0.4572)
		(layer "In5.Cu")
		(net "P3V3_10G_4_VCCT")
	)
	(segment
		(start 318.764666 -5.898134)
		(end 318.764666 -8.89)
		(width 0.4572)
		(layer "In5.Cu")
		(net "P3V3_10G_4_VCCT")
	)
	(segment
		(start 327.279 -2.7178)
		(end 321.945 -2.7178)
		(width 0.4572)
		(layer "In5.Cu")
		(net "P3V3_10G_4_VCCT")
	)
	(segment
		(start 318.764666 -8.89)
		(end 320.288666 -10.414)
		(width 0.4572)
		(layer "In5.Cu")
		(net "P3V3_10G_4_VCCT")
	)
	(segment
		(start 325.394066 -13.1572)
		(end 326.170036 -12.38123)
		(width 0.4572)
		(layer "In5.Cu")
		(net "P3V3_10G_4_VCCT")
	)
	(segment
		(start 327.60285 -3.04165)
		(end 327.279 -2.7178)
		(width 0.4572)
		(layer "In5.Cu")
		(net "P3V3_10G_4_VCCT")
	)
	(segment
		(start 328.170032 -18.490184)
		(end 328.170032 -20.368768)
		(width 0.28956)
		(layer "F.Cu")
		(net "ENET10G_4_TX_FAULT")
	)
	(segment
		(start 311.6326 -30.368494)
		(end 310.708802 -30.368494)
		(width 0.28956)
		(layer "F.Cu")
		(net "ENET10G_4_TX_FAULT")
	)
	(segment
		(start 312.67019 -30.368494)
		(end 311.6326 -30.368494)
		(width 0.28956)
		(layer "F.Cu")
		(net "ENET10G_4_TX_FAULT")
	)
	(via
		(at 311.6326 -30.368494)
		(size 0.508)
		(drill 0.254)
		(layers "F.Cu" "B.Cu")
		(net "ENET10G_4_TX_FAULT")
	)
	(via
		(at 328.170032 -20.368768)
		(size 0.508)
		(drill 0.254)
		(layers "F.Cu" "B.Cu")
		(net "ENET10G_4_TX_FAULT")
	)
	(segment
		(start 327.712832 -20.368768)
		(end 328.170032 -20.368768)
		(width 0.18288)
		(layer "In5.Cu")
		(net "ENET10G_4_TX_FAULT")
	)
	(segment
		(start 325.6026 -20.7264)
		(end 327.3552 -20.7264)
		(width 0.18288)
		(layer "In5.Cu")
		(net "ENET10G_4_TX_FAULT")
	)
	(segment
		(start 324.3834 -21.9456)
		(end 325.6026 -20.7264)
		(width 0.18288)
		(layer "In5.Cu")
		(net "ENET10G_4_TX_FAULT")
	)
	(segment
		(start 311.6326 -30.368494)
		(end 314.3885 -30.368494)
		(width 0.18288)
		(layer "In5.Cu")
		(net "ENET10G_4_TX_FAULT")
	)
	(segment
		(start 314.3885 -30.368494)
		(end 322.811394 -21.9456)
		(width 0.18288)
		(layer "In5.Cu")
		(net "ENET10G_4_TX_FAULT")
	)
	(segment
		(start 322.811394 -21.9456)
		(end 324.3834 -21.9456)
		(width 0.18288)
		(layer "In5.Cu")
		(net "ENET10G_4_TX_FAULT")
	)
	(segment
		(start 327.3552 -20.7264)
		(end 327.712832 -20.368768)
		(width 0.18288)
		(layer "In5.Cu")
		(net "ENET10G_4_TX_FAULT")
	)
	(segment
		(start 364.090204 -10.289794)
		(end 364.090204 -11.7094)
		(width 0.4572)
		(layer "F.Cu")
		(net "P3V3_10G_3_VCCT")
	)
	(segment
		(start 367.538 -3.52425)
		(end 368.52225 -3.52425)
		(width 0.4572)
		(layer "F.Cu")
		(net "P3V3_10G_3_VCCT")
	)
	(segment
		(start 378.01296 -29.859732)
		(end 379.0442 -29.859732)
		(width 0.508)
		(layer "F.Cu")
		(net "P3V3_10G_3_VCCT")
	)
	(segment
		(start 379.9332 -34.48304)
		(end 379.9332 -30.748732)
		(width 0.508)
		(layer "F.Cu")
		(net "P3V3_10G_3_VCCT")
	)
	(segment
		(start 379.9332 -30.748732)
		(end 379.0442 -29.859732)
		(width 0.508)
		(layer "F.Cu")
		(net "P3V3_10G_3_VCCT")
	)
	(segment
		(start 368.52225 -3.52425)
		(end 369.4684 -4.4704)
		(width 0.4572)
		(layer "F.Cu")
		(net "P3V3_10G_3_VCCT")
	)
	(segment
		(start 366.4204 -3.52425)
		(end 367.538 -3.52425)
		(width 0.4572)
		(layer "F.Cu")
		(net "P3V3_10G_3_VCCT")
	)
	(via
		(at 379.0442 -29.859732)
		(size 0.508)
		(drill 0.254)
		(layers "F.Cu" "B.Cu")
		(net "P3V3_10G_3_VCCT")
	)
	(via
		(at 369.4684 -4.4704)
		(size 0.508)
		(drill 0.254)
		(layers "F.Cu" "B.Cu")
		(net "P3V3_10G_3_VCCT")
	)
	(via
		(at 364.090204 -11.7094)
		(size 0.508)
		(drill 0.254)
		(layers "F.Cu" "B.Cu")
		(net "P3V3_10G_3_VCCT")
	)
	(segment
		(start 372.523004 -18.142204)
		(end 372.523004 -7.525004)
		(width 0.4572)
		(layer "In2.Cu")
		(net "P3V3_10G_3_VCCT")
	)
	(segment
		(start 377.7996 -23.4188)
		(end 372.523004 -18.142204)
		(width 0.4572)
		(layer "In2.Cu")
		(net "P3V3_10G_3_VCCT")
	)
	(segment
		(start 377.7996 -28.615132)
		(end 377.7996 -23.4188)
		(width 0.4572)
		(layer "In2.Cu")
		(net "P3V3_10G_3_VCCT")
	)
	(segment
		(start 372.523004 -7.525004)
		(end 369.4684 -4.4704)
		(width 0.4572)
		(layer "In2.Cu")
		(net "P3V3_10G_3_VCCT")
	)
	(segment
		(start 379.0442 -29.859732)
		(end 377.7996 -28.615132)
		(width 0.4572)
		(layer "In2.Cu")
		(net "P3V3_10G_3_VCCT")
	)
	(segment
		(start 359.531666 -13.1826)
		(end 363.138466 -13.1826)
		(width 0.4572)
		(layer "In5.Cu")
		(net "P3V3_10G_3_VCCT")
	)
	(segment
		(start 356.864666 -9.017)
		(end 358.134666 -10.287)
		(width 0.4572)
		(layer "In5.Cu")
		(net "P3V3_10G_3_VCCT")
	)
	(segment
		(start 358.134666 -11.7856)
		(end 359.531666 -13.1826)
		(width 0.4572)
		(layer "In5.Cu")
		(net "P3V3_10G_3_VCCT")
	)
	(segment
		(start 367.7158 -2.7178)
		(end 361.512866 -2.7178)
		(width 0.4572)
		(layer "In5.Cu")
		(net "P3V3_10G_3_VCCT")
	)
	(segment
		(start 361.512866 -2.7178)
		(end 356.864666 -7.366)
		(width 0.4572)
		(layer "In5.Cu")
		(net "P3V3_10G_3_VCCT")
	)
	(segment
		(start 356.864666 -7.366)
		(end 356.864666 -9.017)
		(width 0.4572)
		(layer "In5.Cu")
		(net "P3V3_10G_3_VCCT")
	)
	(segment
		(start 364.090204 -12.230862)
		(end 364.090204 -11.7094)
		(width 0.4572)
		(layer "In5.Cu")
		(net "P3V3_10G_3_VCCT")
	)
	(segment
		(start 369.4684 -4.4704)
		(end 367.7158 -2.7178)
		(width 0.4572)
		(layer "In5.Cu")
		(net "P3V3_10G_3_VCCT")
	)
	(segment
		(start 363.138466 -13.1826)
		(end 364.090204 -12.230862)
		(width 0.4572)
		(layer "In5.Cu")
		(net "P3V3_10G_3_VCCT")
	)
	(segment
		(start 358.134666 -10.287)
		(end 358.134666 -11.7856)
		(width 0.4572)
		(layer "In5.Cu")
		(net "P3V3_10G_3_VCCT")
	)
	(segment
		(start 362.890308 -18.48993)
		(end 362.890308 -20.066508)
		(width 0.28956)
		(layer "F.Cu")
		(net "ENET10G_3_MOD_DEF0")
	)
	(segment
		(start 351.577402 -21.092668)
		(end 352.207068 -21.092668)
		(width 0.28956)
		(layer "F.Cu")
		(net "ENET10G_3_MOD_DEF0")
	)
	(segment
		(start 351.812098 -24.145494)
		(end 351.608898 -24.348694)
		(width 0.28956)
		(layer "F.Cu")
		(net "ENET10G_3_MOD_DEF0")
	)
	(segment
		(start 352.207068 -21.092668)
		(end 353.314 -22.1996)
		(width 0.28956)
		(layer "F.Cu")
		(net "ENET10G_3_MOD_DEF0")
	)
	(segment
		(start 353.314 -22.1996)
		(end 353.314 -23.4696)
		(width 0.28956)
		(layer "F.Cu")
		(net "ENET10G_3_MOD_DEF0")
	)
	(segment
		(start 352.638106 -24.145494)
		(end 351.812098 -24.145494)
		(width 0.28956)
		(layer "F.Cu")
		(net "ENET10G_3_MOD_DEF0")
	)
	(segment
		(start 353.314 -23.4696)
		(end 352.638106 -24.145494)
		(width 0.28956)
		(layer "F.Cu")
		(net "ENET10G_3_MOD_DEF0")
	)
	(via
		(at 353.314 -23.4696)
		(size 0.508)
		(drill 0.254)
		(layers "F.Cu" "B.Cu")
		(net "ENET10G_3_MOD_DEF0")
	)
	(via
		(at 362.890308 -20.066508)
		(size 0.508)
		(drill 0.254)
		(layers "F.Cu" "B.Cu")
		(net "ENET10G_3_MOD_DEF0")
	)
	(segment
		(start 362.228892 -20.066508)
		(end 361.2388 -21.0566)
		(width 0.18288)
		(layer "In5.Cu")
		(net "ENET10G_3_MOD_DEF0")
	)
	(segment
		(start 361.2388 -21.0566)
		(end 359.773982 -21.0566)
		(width 0.18288)
		(layer "In5.Cu")
		(net "ENET10G_3_MOD_DEF0")
	)
	(segment
		(start 362.890308 -20.066508)
		(end 362.228892 -20.066508)
		(width 0.18288)
		(layer "In5.Cu")
		(net "ENET10G_3_MOD_DEF0")
	)
	(segment
		(start 357.360982 -23.4696)
		(end 353.314 -23.4696)
		(width 0.18288)
		(layer "In5.Cu")
		(net "ENET10G_3_MOD_DEF0")
	)
	(segment
		(start 359.773982 -21.0566)
		(end 357.360982 -23.4696)
		(width 0.18288)
		(layer "In5.Cu")
		(net "ENET10G_3_MOD_DEF0")
	)
	(segment
		(start 376.22861 -24.906478)
		(end 377.19 -24.906478)
		(width 0.28956)
		(layer "F.Cu")
		(net "ENET10G_3_TX_DIS")
	)
	(segment
		(start 365.290354 -18.48993)
		(end 365.290354 -20.5994)
		(width 0.28956)
		(layer "F.Cu")
		(net "ENET10G_3_TX_DIS")
	)
	(segment
		(start 378.031502 -24.906478)
		(end 377.19 -24.906478)
		(width 0.28956)
		(layer "F.Cu")
		(net "ENET10G_3_TX_DIS")
	)
	(via
		(at 365.290354 -20.5994)
		(size 0.508)
		(drill 0.254)
		(layers "F.Cu" "B.Cu")
		(net "ENET10G_3_TX_DIS")
	)
	(via
		(at 377.19 -24.906478)
		(size 0.508)
		(drill 0.254)
		(layers "F.Cu" "B.Cu")
		(net "ENET10G_3_TX_DIS")
	)
	(segment
		(start 374.918478 -24.906478)
		(end 371.5004 -21.4884)
		(width 0.18288)
		(layer "In5.Cu")
		(net "ENET10G_3_TX_DIS")
	)
	(segment
		(start 371.5004 -21.4884)
		(end 366.179354 -21.4884)
		(width 0.18288)
		(layer "In5.Cu")
		(net "ENET10G_3_TX_DIS")
	)
	(segment
		(start 366.179354 -21.4884)
		(end 365.290354 -20.5994)
		(width 0.18288)
		(layer "In5.Cu")
		(net "ENET10G_3_TX_DIS")
	)
	(segment
		(start 377.19 -24.906478)
		(end 374.918478 -24.906478)
		(width 0.18288)
		(layer "In5.Cu")
		(net "ENET10G_3_TX_DIS")
	)
	(segment
		(start 352.384106 -25.440894)
		(end 351.608898 -25.440894)
		(width 0.28956)
		(layer "F.Cu")
		(net "ENET10G_3_SCL")
	)
	(segment
		(start 363.690154 -18.48993)
		(end 363.690154 -20.3708)
		(width 0.28956)
		(layer "F.Cu")
		(net "ENET10G_3_SCL")
	)
	(segment
		(start 353.0346 -24.7904)
		(end 352.384106 -25.440894)
		(width 0.28956)
		(layer "F.Cu")
		(net "ENET10G_3_SCL")
	)
	(via
		(at 363.690154 -20.3708)
		(size 0.508)
		(drill 0.254)
		(layers "F.Cu" "B.Cu")
		(net "ENET10G_3_SCL")
	)
	(via
		(at 353.0346 -24.7904)
		(size 0.508)
		(drill 0.254)
		(layers "F.Cu" "B.Cu")
		(net "ENET10G_3_SCL")
	)
	(segment
		(start 346.2274 -13.9192)
		(end 346.2274 -8.39724)
		(width 0.18288)
		(layer "In2.Cu")
		(net "ENET10G_3_SCL")
	)
	(segment
		(start 353.0346 -24.7904)
		(end 352.8568 -24.7904)
		(width 0.18288)
		(layer "In2.Cu")
		(net "ENET10G_3_SCL")
	)
	(segment
		(start 348.0816 -20.0152)
		(end 348.0816 -15.7734)
		(width 0.18288)
		(layer "In2.Cu")
		(net "ENET10G_3_SCL")
	)
	(segment
		(start 348.0816 -15.7734)
		(end 346.2274 -13.9192)
		(width 0.18288)
		(layer "In2.Cu")
		(net "ENET10G_3_SCL")
	)
	(segment
		(start 346.2274 -8.39724)
		(end 345.53017 -7.70001)
		(width 0.18288)
		(layer "In2.Cu")
		(net "ENET10G_3_SCL")
	)
	(segment
		(start 352.8568 -24.7904)
		(end 348.0816 -20.0152)
		(width 0.18288)
		(layer "In2.Cu")
		(net "ENET10G_3_SCL")
	)
	(segment
		(start 362.4834 -21.1074)
		(end 362.953554 -21.1074)
		(width 0.18288)
		(layer "In5.Cu")
		(net "ENET10G_3_SCL")
	)
	(segment
		(start 353.6188 -24.2062)
		(end 357.5304 -24.2062)
		(width 0.18288)
		(layer "In5.Cu")
		(net "ENET10G_3_SCL")
	)
	(segment
		(start 362.953554 -21.1074)
		(end 363.690154 -20.3708)
		(width 0.18288)
		(layer "In5.Cu")
		(net "ENET10G_3_SCL")
	)
	(segment
		(start 359.9942 -21.7424)
		(end 361.8484 -21.7424)
		(width 0.18288)
		(layer "In5.Cu")
		(net "ENET10G_3_SCL")
	)
	(segment
		(start 361.8484 -21.7424)
		(end 362.4834 -21.1074)
		(width 0.18288)
		(layer "In5.Cu")
		(net "ENET10G_3_SCL")
	)
	(segment
		(start 357.5304 -24.2062)
		(end 359.9942 -21.7424)
		(width 0.18288)
		(layer "In5.Cu")
		(net "ENET10G_3_SCL")
	)
	(segment
		(start 353.0346 -24.7904)
		(end 353.6188 -24.2062)
		(width 0.18288)
		(layer "In5.Cu")
		(net "ENET10G_3_SCL")
	)
	(segment
		(start 377.1138 -23.636478)
		(end 378.031502 -23.636478)
		(width 0.28956)
		(layer "F.Cu")
		(net "ENET10G_3_TX_FAULT")
	)
	(segment
		(start 366.0902 -18.48993)
		(end 366.0902 -20.0914)
		(width 0.28956)
		(layer "F.Cu")
		(net "ENET10G_3_TX_FAULT")
	)
	(segment
		(start 376.22861 -23.636478)
		(end 377.1138 -23.636478)
		(width 0.28956)
		(layer "F.Cu")
		(net "ENET10G_3_TX_FAULT")
	)
	(via
		(at 366.0902 -20.0914)
		(size 0.508)
		(drill 0.254)
		(layers "F.Cu" "B.Cu")
		(net "ENET10G_3_TX_FAULT")
	)
	(via
		(at 377.1138 -23.636478)
		(size 0.508)
		(drill 0.254)
		(layers "F.Cu" "B.Cu")
		(net "ENET10G_3_TX_FAULT")
	)
	(segment
		(start 372.2116 -20.8534)
		(end 366.8522 -20.8534)
		(width 0.18288)
		(layer "In5.Cu")
		(net "ENET10G_3_TX_FAULT")
	)
	(segment
		(start 377.1138 -23.636478)
		(end 374.994678 -23.636478)
		(width 0.18288)
		(layer "In5.Cu")
		(net "ENET10G_3_TX_FAULT")
	)
	(segment
		(start 366.8522 -20.8534)
		(end 366.0902 -20.0914)
		(width 0.18288)
		(layer "In5.Cu")
		(net "ENET10G_3_TX_FAULT")
	)
	(segment
		(start 374.994678 -23.636478)
		(end 372.2116 -20.8534)
		(width 0.18288)
		(layer "In5.Cu")
		(net "ENET10G_3_TX_FAULT")
	)
	(segment
		(start 364.490254 -18.48993)
		(end 364.490254 -20.7518)
		(width 0.28956)
		(layer "F.Cu")
		(net "ENET10G_3_SDA")
	)
	(segment
		(start 353.120706 -26.533094)
		(end 351.608898 -26.533094)
		(width 0.28956)
		(layer "F.Cu")
		(net "ENET10G_3_SDA")
	)
	(segment
		(start 354.3808 -25.273)
		(end 353.120706 -26.533094)
		(width 0.28956)
		(layer "F.Cu")
		(net "ENET10G_3_SDA")
	)
	(via
		(at 364.490254 -20.7518)
		(size 0.508)
		(drill 0.254)
		(layers "F.Cu" "B.Cu")
		(net "ENET10G_3_SDA")
	)
	(via
		(at 354.3808 -25.273)
		(size 0.508)
		(drill 0.254)
		(layers "F.Cu" "B.Cu")
		(net "ENET10G_3_SDA")
	)
	(segment
		(start 345.53017 -6.299962)
		(end 346.139008 -6.9088)
		(width 0.18288)
		(layer "In2.Cu")
		(net "ENET10G_3_SDA")
	)
	(segment
		(start 347.9292 -6.9088)
		(end 348.5642 -7.5438)
		(width 0.18288)
		(layer "In2.Cu")
		(net "ENET10G_3_SDA")
	)
	(segment
		(start 346.139008 -6.9088)
		(end 347.9292 -6.9088)
		(width 0.18288)
		(layer "In2.Cu")
		(net "ENET10G_3_SDA")
	)
	(segment
		(start 348.7293 -19.6215)
		(end 353.1616 -24.0538)
		(width 0.18288)
		(layer "In2.Cu")
		(net "ENET10G_3_SDA")
	)
	(segment
		(start 354.3808 -24.9174)
		(end 354.3808 -25.273)
		(width 0.18288)
		(layer "In2.Cu")
		(net "ENET10G_3_SDA")
	)
	(segment
		(start 348.7293 -14.5161)
		(end 348.7293 -19.6215)
		(width 0.18288)
		(layer "In2.Cu")
		(net "ENET10G_3_SDA")
	)
	(segment
		(start 353.5172 -24.0538)
		(end 354.3808 -24.9174)
		(width 0.18288)
		(layer "In2.Cu")
		(net "ENET10G_3_SDA")
	)
	(segment
		(start 353.1616 -24.0538)
		(end 353.5172 -24.0538)
		(width 0.18288)
		(layer "In2.Cu")
		(net "ENET10G_3_SDA")
	)
	(segment
		(start 348.5642 -7.5438)
		(end 348.5642 -14.351)
		(width 0.18288)
		(layer "In2.Cu")
		(net "ENET10G_3_SDA")
	)
	(segment
		(start 348.5642 -14.351)
		(end 348.7293 -14.5161)
		(width 0.18288)
		(layer "In2.Cu")
		(net "ENET10G_3_SDA")
	)
	(segment
		(start 354.7872 -24.8666)
		(end 354.3808 -25.273)
		(width 0.18288)
		(layer "In5.Cu")
		(net "ENET10G_3_SDA")
	)
	(segment
		(start 357.7844 -24.8666)
		(end 354.7872 -24.8666)
		(width 0.18288)
		(layer "In5.Cu")
		(net "ENET10G_3_SDA")
	)
	(segment
		(start 362.71708 -21.81352)
		(end 362.1024 -22.4282)
		(width 0.18288)
		(layer "In5.Cu")
		(net "ENET10G_3_SDA")
	)
	(segment
		(start 364.490254 -20.7518)
		(end 363.428534 -21.81352)
		(width 0.18288)
		(layer "In5.Cu")
		(net "ENET10G_3_SDA")
	)
	(segment
		(start 360.2228 -22.4282)
		(end 357.7844 -24.8666)
		(width 0.18288)
		(layer "In5.Cu")
		(net "ENET10G_3_SDA")
	)
	(segment
		(start 362.1024 -22.4282)
		(end 360.2228 -22.4282)
		(width 0.18288)
		(layer "In5.Cu")
		(net "ENET10G_3_SDA")
	)
	(segment
		(start 363.428534 -21.81352)
		(end 362.71708 -21.81352)
		(width 0.18288)
		(layer "In5.Cu")
		(net "ENET10G_3_SDA")
	)
	(segment
		(start 362.090208 -20.180808)
		(end 364.2868 -22.3774)
		(width 0.28956)
		(layer "F.Cu")
		(net "ENET10G_3_RS0")
	)
	(segment
		(start 362.090208 -18.48993)
		(end 362.090208 -20.180808)
		(width 0.28956)
		(layer "F.Cu")
		(net "ENET10G_3_RS0")
	)
	(segment
		(start 377.1646 -26.227278)
		(end 378.031502 -26.227278)
		(width 0.28956)
		(layer "F.Cu")
		(net "ENET10G_3_RS0")
	)
	(segment
		(start 376.22861 -26.227278)
		(end 377.1646 -26.227278)
		(width 0.28956)
		(layer "F.Cu")
		(net "ENET10G_3_RS0")
	)
	(via
		(at 377.1646 -26.227278)
		(size 0.508)
		(drill 0.254)
		(layers "F.Cu" "B.Cu")
		(net "ENET10G_3_RS0")
	)
	(via
		(at 364.2868 -22.3774)
		(size 0.508)
		(drill 0.254)
		(layers "F.Cu" "B.Cu")
		(net "ENET10G_3_RS0")
	)
	(segment
		(start 368.3508 -23.9522)
		(end 366.776 -22.3774)
		(width 0.18288)
		(layer "In5.Cu")
		(net "ENET10G_3_RS0")
	)
	(segment
		(start 366.776 -22.3774)
		(end 364.2868 -22.3774)
		(width 0.18288)
		(layer "In5.Cu")
		(net "ENET10G_3_RS0")
	)
	(segment
		(start 377.1646 -26.227278)
		(end 375.324878 -26.227278)
		(width 0.18288)
		(layer "In5.Cu")
		(net "ENET10G_3_RS0")
	)
	(segment
		(start 373.0498 -23.9522)
		(end 368.3508 -23.9522)
		(width 0.18288)
		(layer "In5.Cu")
		(net "ENET10G_3_RS0")
	)
	(segment
		(start 375.324878 -26.227278)
		(end 373.0498 -23.9522)
		(width 0.18288)
		(layer "In5.Cu")
		(net "ENET10G_3_RS0")
	)
	(segment
		(start 351.577402 -23.256494)
		(end 351.577402 -22.159468)
		(width 0.28956)
		(layer "F.Cu")
		(net "ENET10G_3_LOS")
	)
	(segment
		(start 351.577402 -22.159468)
		(end 352.3996 -22.159468)
		(width 0.28956)
		(layer "F.Cu")
		(net "ENET10G_3_LOS")
	)
	(segment
		(start 361.290362 -18.48993)
		(end 361.290362 -19.9136)
		(width 0.28956)
		(layer "F.Cu")
		(net "ENET10G_3_LOS")
	)
	(via
		(at 352.3996 -22.159468)
		(size 0.508)
		(drill 0.254)
		(layers "F.Cu" "B.Cu")
		(net "ENET10G_3_LOS")
	)
	(via
		(at 361.290362 -19.9136)
		(size 0.508)
		(drill 0.254)
		(layers "F.Cu" "B.Cu")
		(net "ENET10G_3_LOS")
	)
	(segment
		(start 360.553 -19.9136)
		(end 360.08056 -20.38604)
		(width 0.18288)
		(layer "In5.Cu")
		(net "ENET10G_3_LOS")
	)
	(segment
		(start 359.67416 -20.38604)
		(end 358.6226 -21.4376)
		(width 0.18288)
		(layer "In5.Cu")
		(net "ENET10G_3_LOS")
	)
	(segment
		(start 358.6226 -21.4376)
		(end 353.121468 -21.4376)
		(width 0.18288)
		(layer "In5.Cu")
		(net "ENET10G_3_LOS")
	)
	(segment
		(start 361.290362 -19.9136)
		(end 360.553 -19.9136)
		(width 0.18288)
		(layer "In5.Cu")
		(net "ENET10G_3_LOS")
	)
	(segment
		(start 353.121468 -21.4376)
		(end 352.3996 -22.159468)
		(width 0.18288)
		(layer "In5.Cu")
		(net "ENET10G_3_LOS")
	)
	(segment
		(start 360.08056 -20.38604)
		(end 359.67416 -20.38604)
		(width 0.18288)
		(layer "In5.Cu")
		(net "ENET10G_3_LOS")
	)
	(segment
		(start 396.249906 -30.99562)
		(end 396.709646 -30.53588)
		(width 0.1778)
		(layer "F.Cu")
		(net "SAS_BLAD2_RX5_N")
	)
	(segment
		(start 396.709646 -30.53588)
		(end 396.709646 -29.72562)
		(width 0.1778)
		(layer "F.Cu")
		(net "SAS_BLAD2_RX5_N")
	)
	(segment
		(start 396.484856 -29.50083)
		(end 396.484856 -28.4099)
		(width 0.1778)
		(layer "F.Cu")
		(net "SAS_BLAD2_RX5_N")
	)
	(segment
		(start 396.709646 -29.72562)
		(end 396.484856 -29.50083)
		(width 0.1778)
		(layer "F.Cu")
		(net "SAS_BLAD2_RX5_N")
	)
	(via
		(at 396.249906 -30.99562)
		(size 0.508)
		(drill 0.254)
		(layers "F.Cu" "B.Cu")
		(net "SAS_BLAD2_RX5_N")
	)
	(segment
		(start 394.990066 -28.045156)
		(end 394.812266 -27.867356)
		(width 0.1524)
		(layer "In5.Cu")
		(net "SAS_BLAD2_RX5_N")
	)
	(segment
		(start 394.812266 -27.281632)
		(end 394.964666 -27.129232)
		(width 0.1524)
		(layer "In5.Cu")
		(net "SAS_BLAD2_RX5_N")
	)
	(segment
		(start 396.249906 -30.99562)
		(end 396.68196 -31.427674)
		(width 0.1524)
		(layer "In5.Cu")
		(net "SAS_BLAD2_RX5_N")
	)
	(segment
		(start 395.044422 -23.066756)
		(end 394.848334 -22.870668)
		(width 0.1524)
		(layer "In5.Cu")
		(net "SAS_BLAD2_RX5_N")
	)
	(segment
		(start 392.545824 -20.568158)
		(end 391.86231 -19.884644)
		(width 0.1524)
		(layer "In5.Cu")
		(net "SAS_BLAD2_RX5_N")
	)
	(segment
		(start 394.812266 -30.752034)
		(end 394.812266 -29.848556)
		(width 0.1524)
		(layer "In5.Cu")
		(net "SAS_BLAD2_RX5_N")
	)
	(segment
		(start 396.017496 -31.999682)
		(end 395.783816 -31.765748)
		(width 0.1524)
		(layer "In5.Cu")
		(net "SAS_BLAD2_RX5_N")
	)
	(segment
		(start 396.652242 -31.824422)
		(end 396.476982 -31.999682)
		(width 0.1524)
		(layer "In5.Cu")
		(net "SAS_BLAD2_RX5_N")
	)
	(segment
		(start 394.848334 -22.870668)
		(end 394.848334 -22.642068)
		(width 0.1524)
		(layer "In5.Cu")
		(net "SAS_BLAD2_RX5_N")
	)
	(segment
		(start 394.812266 -29.086556)
		(end 394.812266 -28.629356)
		(width 0.1524)
		(layer "In5.Cu")
		(net "SAS_BLAD2_RX5_N")
	)
	(segment
		(start 394.964666 -26.672032)
		(end 394.812266 -26.519632)
		(width 0.1524)
		(layer "In5.Cu")
		(net "SAS_BLAD2_RX5_N")
	)
	(segment
		(start 393.97305 -21.766784)
		(end 393.649708 -21.443442)
		(width 0.1524)
		(layer "In5.Cu")
		(net "SAS_BLAD2_RX5_N")
	)
	(segment
		(start 393.649708 -21.443442)
		(end 393.421108 -21.443442)
		(width 0.1524)
		(layer "In5.Cu")
		(net "SAS_BLAD2_RX5_N")
	)
	(segment
		(start 393.421108 -21.443442)
		(end 393.097766 -21.1201)
		(width 0.1524)
		(layer "In5.Cu")
		(net "SAS_BLAD2_RX5_N")
	)
	(segment
		(start 393.097766 -20.8915)
		(end 392.774424 -20.568158)
		(width 0.1524)
		(layer "In5.Cu")
		(net "SAS_BLAD2_RX5_N")
	)
	(segment
		(start 395.783816 -31.765748)
		(end 395.439138 -31.421324)
		(width 0.1524)
		(layer "In5.Cu")
		(net "SAS_BLAD2_RX5_N")
	)
	(segment
		(start 394.964666 -27.129232)
		(end 394.964666 -26.672032)
		(width 0.1524)
		(layer "In5.Cu")
		(net "SAS_BLAD2_RX5_N")
	)
	(segment
		(start 394.96111 -25.784556)
		(end 395.044422 -25.701244)
		(width 0.1524)
		(layer "In5.Cu")
		(net "SAS_BLAD2_RX5_N")
	)
	(segment
		(start 394.524992 -22.318726)
		(end 394.296392 -22.318726)
		(width 0.1524)
		(layer "In5.Cu")
		(net "SAS_BLAD2_RX5_N")
	)
	(segment
		(start 394.990066 -28.451556)
		(end 394.990066 -28.045156)
		(width 0.1524)
		(layer "In5.Cu")
		(net "SAS_BLAD2_RX5_N")
	)
	(segment
		(start 394.812266 -28.629356)
		(end 394.990066 -28.451556)
		(width 0.1524)
		(layer "In5.Cu")
		(net "SAS_BLAD2_RX5_N")
	)
	(segment
		(start 395.439138 -31.421324)
		(end 394.847826 -30.82925)
		(width 0.1524)
		(layer "In5.Cu")
		(net "SAS_BLAD2_RX5_N")
	)
	(segment
		(start 394.296392 -22.318726)
		(end 393.97305 -21.995384)
		(width 0.1524)
		(layer "In5.Cu")
		(net "SAS_BLAD2_RX5_N")
	)
	(segment
		(start 394.847826 -30.82925)
		(end 394.843762 -30.82544)
		(width 0.1524)
		(layer "In5.Cu")
		(net "SAS_BLAD2_RX5_N")
	)
	(segment
		(start 391.713466 -19.525488)
		(end 391.713466 -17.710912)
		(width 0.1524)
		(layer "In5.Cu")
		(net "SAS_BLAD2_RX5_N")
	)
	(segment
		(start 394.990066 -29.264356)
		(end 394.812266 -29.086556)
		(width 0.1524)
		(layer "In5.Cu")
		(net "SAS_BLAD2_RX5_N")
	)
	(segment
		(start 389.735568 -12.703302)
		(end 389.89 -12.857734)
		(width 0.1524)
		(layer "In5.Cu")
		(net "SAS_BLAD2_RX5_N")
	)
	(segment
		(start 394.848334 -22.642068)
		(end 394.524992 -22.318726)
		(width 0.1524)
		(layer "In5.Cu")
		(net "SAS_BLAD2_RX5_N")
	)
	(segment
		(start 389.89 -12.857734)
		(end 389.89 -13.200126)
		(width 0.1524)
		(layer "In5.Cu")
		(net "SAS_BLAD2_RX5_N")
	)
	(segment
		(start 394.812266 -26.519632)
		(end 394.812266 -26.143712)
		(width 0.1524)
		(layer "In5.Cu")
		(net "SAS_BLAD2_RX5_N")
	)
	(segment
		(start 393.097766 -21.1201)
		(end 393.097766 -20.8915)
		(width 0.1524)
		(layer "In5.Cu")
		(net "SAS_BLAD2_RX5_N")
	)
	(segment
		(start 394.812266 -27.867356)
		(end 394.812266 -27.281632)
		(width 0.1524)
		(layer "In5.Cu")
		(net "SAS_BLAD2_RX5_N")
	)
	(segment
		(start 396.68196 -31.427674)
		(end 396.68196 -31.752794)
		(width 0.1524)
		(layer "In5.Cu")
		(net "SAS_BLAD2_RX5_N")
	)
	(segment
		(start 389.046466 -14.623288)
		(end 389.046466 -13.087858)
		(width 0.1524)
		(layer "In5.Cu")
		(net "SAS_BLAD2_RX5_N")
	)
	(segment
		(start 389.158988 -12.815824)
		(end 389.159242 -12.81557)
		(width 0.1524)
		(layer "In5.Cu")
		(net "SAS_BLAD2_RX5_N")
	)
	(segment
		(start 391.564622 -17.351756)
		(end 389.19531 -14.982444)
		(width 0.1524)
		(layer "In5.Cu")
		(net "SAS_BLAD2_RX5_N")
	)
	(segment
		(start 392.774424 -20.568158)
		(end 392.545824 -20.568158)
		(width 0.1524)
		(layer "In5.Cu")
		(net "SAS_BLAD2_RX5_N")
	)
	(segment
		(start 393.97305 -21.995384)
		(end 393.97305 -21.766784)
		(width 0.1524)
		(layer "In5.Cu")
		(net "SAS_BLAD2_RX5_N")
	)
	(segment
		(start 394.812266 -29.848556)
		(end 394.990066 -29.670756)
		(width 0.1524)
		(layer "In5.Cu")
		(net "SAS_BLAD2_RX5_N")
	)
	(segment
		(start 394.990066 -29.670756)
		(end 394.990066 -29.264356)
		(width 0.1524)
		(layer "In5.Cu")
		(net "SAS_BLAD2_RX5_N")
	)
	(segment
		(start 389.430768 -12.703302)
		(end 389.735568 -12.703302)
		(width 0.1524)
		(layer "In5.Cu")
		(net "SAS_BLAD2_RX5_N")
	)
	(segment
		(start 395.193266 -25.342088)
		(end 395.193266 -23.425912)
		(width 0.1524)
		(layer "In5.Cu")
		(net "SAS_BLAD2_RX5_N")
	)
	(segment
		(start 396.405354 -32.0294)
		(end 396.089124 -32.0294)
		(width 0.1524)
		(layer "In5.Cu")
		(net "SAS_BLAD2_RX5_N")
	)
	(arc
		(start 396.089124 -32.0294)
		(mid 396.05038 -32.021618)
		(end 396.017496 -31.999682)
		(width 0.1524)
		(layer "In5.Cu")
		(net "SAS_BLAD2_RX5_N")
	)
	(arc
		(start 389.159242 -12.81557)
		(mid 389.283862 -12.732491)
		(end 389.430768 -12.703302)
		(width 0.1524)
		(layer "In5.Cu")
		(net "SAS_BLAD2_RX5_N")
	)
	(arc
		(start 396.68196 -31.752794)
		(mid 396.67423 -31.791563)
		(end 396.652242 -31.824422)
		(width 0.1524)
		(layer "In5.Cu")
		(net "SAS_BLAD2_RX5_N")
	)
	(arc
		(start 395.193266 -23.425912)
		(mid 395.154582 -23.231523)
		(end 395.044422 -23.066756)
		(width 0.1524)
		(layer "In5.Cu")
		(net "SAS_BLAD2_RX5_N")
	)
	(arc
		(start 389.046466 -13.087858)
		(mid 389.075656 -12.940641)
		(end 389.158988 -12.815824)
		(width 0.1524)
		(layer "In5.Cu")
		(net "SAS_BLAD2_RX5_N")
	)
	(arc
		(start 394.812266 -26.143712)
		(mid 394.85095 -25.949323)
		(end 394.96111 -25.784556)
		(width 0.1524)
		(layer "In5.Cu")
		(net "SAS_BLAD2_RX5_N")
	)
	(arc
		(start 395.044422 -25.701244)
		(mid 395.15458 -25.536476)
		(end 395.193266 -25.342088)
		(width 0.1524)
		(layer "In5.Cu")
		(net "SAS_BLAD2_RX5_N")
	)
	(arc
		(start 389.19531 -14.982444)
		(mid 389.085152 -14.817676)
		(end 389.046466 -14.623288)
		(width 0.1524)
		(layer "In5.Cu")
		(net "SAS_BLAD2_RX5_N")
	)
	(arc
		(start 391.713466 -17.710912)
		(mid 391.674782 -17.516523)
		(end 391.564622 -17.351756)
		(width 0.1524)
		(layer "In5.Cu")
		(net "SAS_BLAD2_RX5_N")
	)
	(arc
		(start 394.843762 -30.82544)
		(mid 394.820485 -30.791969)
		(end 394.812266 -30.752034)
		(width 0.1524)
		(layer "In5.Cu")
		(net "SAS_BLAD2_RX5_N")
	)
	(arc
		(start 391.86231 -19.884644)
		(mid 391.752152 -19.719876)
		(end 391.713466 -19.525488)
		(width 0.1524)
		(layer "In5.Cu")
		(net "SAS_BLAD2_RX5_N")
	)
	(arc
		(start 396.476982 -31.999682)
		(mid 396.444133 -32.021694)
		(end 396.405354 -32.0294)
		(width 0.1524)
		(layer "In5.Cu")
		(net "SAS_BLAD2_RX5_N")
	)
	(segment
		(start 122.4788 -15.0876)
		(end 122.4788 -23.1394)
		(width 0.1524)
		(layer "In5.Cu")
		(net "ENET1G_2_MDI0N")
	)
	(segment
		(start 123.331732 -14.234668)
		(end 122.4788 -15.0876)
		(width 0.1524)
		(layer "In5.Cu")
		(net "ENET1G_2_MDI0N")
	)
	(segment
		(start 117.5004 -30.2006)
		(end 118.386098 -31.086298)
		(width 0.1524)
		(layer "In5.Cu")
		(net "ENET1G_2_MDI0N")
	)
	(segment
		(start 122.530108 -4.800092)
		(end 122.530108 -4.45516)
		(width 0.1524)
		(layer "In5.Cu")
		(net "ENET1G_2_MDI0N")
	)
	(segment
		(start 122.530108 -4.45516)
		(end 122.682 -4.303268)
		(width 0.1524)
		(layer "In5.Cu")
		(net "ENET1G_2_MDI0N")
	)
	(segment
		(start 118.386098 -31.086298)
		(end 119.423942 -31.086298)
		(width 0.1524)
		(layer "In5.Cu")
		(net "ENET1G_2_MDI0N")
	)
	(segment
		(start 119.423942 -31.086298)
		(end 119.543068 -30.967172)
		(width 0.1524)
		(layer "In5.Cu")
		(net "ENET1G_2_MDI0N")
	)
	(segment
		(start 122.4788 -23.1394)
		(end 117.5004 -28.1178)
		(width 0.1524)
		(layer "In5.Cu")
		(net "ENET1G_2_MDI0N")
	)
	(segment
		(start 119.543068 -30.967172)
		(end 119.679466 -30.8991)
		(width 0.1524)
		(layer "In5.Cu")
		(net "ENET1G_2_MDI0N")
	)
	(segment
		(start 122.682 -4.303268)
		(end 123.179332 -4.303268)
		(width 0.1524)
		(layer "In5.Cu")
		(net "ENET1G_2_MDI0N")
	)
	(segment
		(start 119.679466 -30.8991)
		(end 119.883936 -30.966918)
		(width 0.1524)
		(layer "In5.Cu")
		(net "ENET1G_2_MDI0N")
	)
	(segment
		(start 119.883936 -30.966918)
		(end 120.360186 -31.919164)
		(width 0.1524)
		(layer "In5.Cu")
		(net "ENET1G_2_MDI0N")
	)
	(segment
		(start 117.5004 -28.1178)
		(end 117.5004 -30.2006)
		(width 0.1524)
		(layer "In5.Cu")
		(net "ENET1G_2_MDI0N")
	)
	(segment
		(start 123.179332 -4.303268)
		(end 123.331732 -4.455668)
		(width 0.1524)
		(layer "In5.Cu")
		(net "ENET1G_2_MDI0N")
	)
	(segment
		(start 123.331732 -4.455668)
		(end 123.331732 -14.234668)
		(width 0.1524)
		(layer "In5.Cu")
		(net "ENET1G_2_MDI0N")
	)
	(segment
		(start 338.500466 -30.2006)
		(end 339.386164 -31.086298)
		(width 0.1524)
		(layer "In5.Cu")
		(net "ENET1G_4_MDI0N")
	)
	(segment
		(start 338.500466 -27.284934)
		(end 338.500466 -30.2006)
		(width 0.1524)
		(layer "In5.Cu")
		(net "ENET1G_4_MDI0N")
	)
	(segment
		(start 344.331798 -4.455668)
		(end 344.331798 -15.3416)
		(width 0.1524)
		(layer "In5.Cu")
		(net "ENET1G_4_MDI0N")
	)
	(segment
		(start 341.503 -24.2824)
		(end 338.500466 -27.284934)
		(width 0.1524)
		(layer "In5.Cu")
		(net "ENET1G_4_MDI0N")
	)
	(segment
		(start 343.662 -4.303268)
		(end 344.179398 -4.303268)
		(width 0.1524)
		(layer "In5.Cu")
		(net "ENET1G_4_MDI0N")
	)
	(segment
		(start 340.424008 -31.086298)
		(end 340.543134 -30.967172)
		(width 0.1524)
		(layer "In5.Cu")
		(net "ENET1G_4_MDI0N")
	)
	(segment
		(start 343.530174 -4.435094)
		(end 343.662 -4.303268)
		(width 0.1524)
		(layer "In5.Cu")
		(net "ENET1G_4_MDI0N")
	)
	(segment
		(start 339.386164 -31.086298)
		(end 340.424008 -31.086298)
		(width 0.1524)
		(layer "In5.Cu")
		(net "ENET1G_4_MDI0N")
	)
	(segment
		(start 343.530174 -4.800092)
		(end 343.530174 -4.435094)
		(width 0.1524)
		(layer "In5.Cu")
		(net "ENET1G_4_MDI0N")
	)
	(segment
		(start 340.543134 -30.967172)
		(end 340.679532 -30.8991)
		(width 0.1524)
		(layer "In5.Cu")
		(net "ENET1G_4_MDI0N")
	)
	(segment
		(start 340.884002 -30.966918)
		(end 341.360252 -31.919164)
		(width 0.1524)
		(layer "In5.Cu")
		(net "ENET1G_4_MDI0N")
	)
	(segment
		(start 344.179398 -4.303268)
		(end 344.331798 -4.455668)
		(width 0.1524)
		(layer "In5.Cu")
		(net "ENET1G_4_MDI0N")
	)
	(segment
		(start 344.331798 -15.3416)
		(end 341.503 -18.170398)
		(width 0.1524)
		(layer "In5.Cu")
		(net "ENET1G_4_MDI0N")
	)
	(segment
		(start 341.503 -18.170398)
		(end 341.503 -24.2824)
		(width 0.1524)
		(layer "In5.Cu")
		(net "ENET1G_4_MDI0N")
	)
	(segment
		(start 340.679532 -30.8991)
		(end 340.884002 -30.966918)
		(width 0.1524)
		(layer "In5.Cu")
		(net "ENET1G_4_MDI0N")
	)
	(segment
		(start 119.361204 -30.603444)
		(end 119.302276 -30.632908)
		(width 0.1524)
		(layer "In5.Cu")
		(net "ENET1G_2_MDI0P")
	)
	(segment
		(start 122.8852 -23.307802)
		(end 122.8852 -15.256002)
		(width 0.1524)
		(layer "In5.Cu")
		(net "ENET1G_2_MDI0P")
	)
	(segment
		(start 117.9068 -30.032198)
		(end 117.9068 -28.286202)
		(width 0.1524)
		(layer "In5.Cu")
		(net "ENET1G_2_MDI0P")
	)
	(segment
		(start 119.565928 -30.330902)
		(end 119.497602 -30.535372)
		(width 0.1524)
		(layer "In5.Cu")
		(net "ENET1G_2_MDI0P")
	)
	(segment
		(start 123.347734 -3.896868)
		(end 122.682 -3.896868)
		(width 0.1524)
		(layer "In5.Cu")
		(net "ENET1G_2_MDI0P")
	)
	(segment
		(start 123.738132 -14.40307)
		(end 123.738132 -4.287266)
		(width 0.1524)
		(layer "In5.Cu")
		(net "ENET1G_2_MDI0P")
	)
	(segment
		(start 122.8852 -15.256002)
		(end 123.738132 -14.40307)
		(width 0.1524)
		(layer "In5.Cu")
		(net "ENET1G_2_MDI0P")
	)
	(segment
		(start 119.25554 -30.679898)
		(end 118.5545 -30.679898)
		(width 0.1524)
		(layer "In5.Cu")
		(net "ENET1G_2_MDI0P")
	)
	(segment
		(start 119.302276 -30.632908)
		(end 119.25554 -30.679898)
		(width 0.1524)
		(layer "In5.Cu")
		(net "ENET1G_2_MDI0P")
	)
	(segment
		(start 118.5545 -30.679898)
		(end 117.9068 -30.032198)
		(width 0.1524)
		(layer "In5.Cu")
		(net "ENET1G_2_MDI0P")
	)
	(segment
		(start 123.738132 -4.287266)
		(end 123.347734 -3.896868)
		(width 0.1524)
		(layer "In5.Cu")
		(net "ENET1G_2_MDI0P")
	)
	(segment
		(start 117.9068 -28.286202)
		(end 122.8852 -23.307802)
		(width 0.1524)
		(layer "In5.Cu")
		(net "ENET1G_2_MDI0P")
	)
	(segment
		(start 119.497602 -30.535372)
		(end 119.361204 -30.603444)
		(width 0.1524)
		(layer "In5.Cu")
		(net "ENET1G_2_MDI0P")
	)
	(segment
		(start 122.682 -3.896868)
		(end 122.530108 -3.744976)
		(width 0.1524)
		(layer "In5.Cu")
		(net "ENET1G_2_MDI0P")
	)
	(segment
		(start 119.090186 -29.379164)
		(end 119.565928 -30.330902)
		(width 0.1524)
		(layer "In5.Cu")
		(net "ENET1G_2_MDI0P")
	)
	(segment
		(start 122.530108 -3.744976)
		(end 122.530108 -3.400044)
		(width 0.1524)
		(layer "In5.Cu")
		(net "ENET1G_2_MDI0P")
	)
	(segment
		(start 415.701226 -29.701236)
		(end 415.701226 -30.122368)
		(width 0.1778)
		(layer "F.Cu")
		(net "SAS_BLAD2_RX1_N")
	)
	(segment
		(start 415.494978 -28.4099)
		(end 415.494978 -29.494988)
		(width 0.1778)
		(layer "F.Cu")
		(net "SAS_BLAD2_RX1_N")
	)
	(segment
		(start 415.701226 -30.122368)
		(end 415.259774 -30.56382)
		(width 0.1778)
		(layer "F.Cu")
		(net "SAS_BLAD2_RX1_N")
	)
	(segment
		(start 415.494978 -29.494988)
		(end 415.701226 -29.701236)
		(width 0.1778)
		(layer "F.Cu")
		(net "SAS_BLAD2_RX1_N")
	)
	(via
		(at 415.259774 -30.56382)
		(size 0.508)
		(drill 0.254)
		(layers "F.Cu" "B.Cu")
		(net "SAS_BLAD2_RX1_N")
	)
	(segment
		(start 398.55648 -7.175246)
		(end 396.414752 -7.175246)
		(width 0.1778)
		(layer "B.Cu")
		(net "SAS_BLAD2_RX1_N")
	)
	(segment
		(start 413.638746 -24.402288)
		(end 413.638746 -22.257512)
		(width 0.1778)
		(layer "B.Cu")
		(net "SAS_BLAD2_RX1_N")
	)
	(segment
		(start 415.259774 -30.56382)
		(end 415.719768 -30.103826)
		(width 0.1778)
		(layer "B.Cu")
		(net "SAS_BLAD2_RX1_N")
	)
	(segment
		(start 396.414752 -7.175246)
		(end 395.889988 -7.70001)
		(width 0.1778)
		(layer "B.Cu")
		(net "SAS_BLAD2_RX1_N")
	)
	(segment
		(start 415.719768 -30.103826)
		(end 415.719768 -26.903934)
		(width 0.1778)
		(layer "B.Cu")
		(net "SAS_BLAD2_RX1_N")
	)
	(segment
		(start 415.67354 -26.792682)
		(end 413.890206 -25.009348)
		(width 0.1778)
		(layer "B.Cu")
		(net "SAS_BLAD2_RX1_N")
	)
	(segment
		(start 413.592518 -22.14626)
		(end 398.667732 -7.221474)
		(width 0.1778)
		(layer "B.Cu")
		(net "SAS_BLAD2_RX1_N")
	)
	(arc
		(start 413.890206 -25.009348)
		(mid 413.704104 -24.730827)
		(end 413.638746 -24.402288)
		(width 0.1778)
		(layer "B.Cu")
		(net "SAS_BLAD2_RX1_N")
	)
	(arc
		(start 398.667732 -7.221474)
		(mid 398.616718 -7.187261)
		(end 398.55648 -7.175246)
		(width 0.1778)
		(layer "B.Cu")
		(net "SAS_BLAD2_RX1_N")
	)
	(arc
		(start 413.638746 -22.257512)
		(mid 413.626728 -22.197276)
		(end 413.592518 -22.14626)
		(width 0.1778)
		(layer "B.Cu")
		(net "SAS_BLAD2_RX1_N")
	)
	(arc
		(start 415.719768 -26.903934)
		(mid 415.70775 -26.843698)
		(end 415.67354 -26.792682)
		(width 0.1778)
		(layer "B.Cu")
		(net "SAS_BLAD2_RX1_N")
	)
	(segment
		(start 365.79048 -8.852662)
		(end 365.69015 -8.952992)
		(width 0.24384)
		(layer "F.Cu")
		(net "ENET10G_3_TDP")
	)
	(segment
		(start 365.4552 -5.715)
		(end 365.79048 -6.05028)
		(width 0.24384)
		(layer "F.Cu")
		(net "ENET10G_3_TDP")
	)
	(segment
		(start 365.79048 -6.05028)
		(end 365.79048 -8.852662)
		(width 0.24384)
		(layer "F.Cu")
		(net "ENET10G_3_TDP")
	)
	(segment
		(start 365.69015 -8.952992)
		(end 365.69015 -10.289794)
		(width 0.24384)
		(layer "F.Cu")
		(net "ENET10G_3_TDP")
	)
	(via
		(at 365.4552 -5.715)
		(size 0.508)
		(drill 0.254)
		(layers "F.Cu" "B.Cu")
		(net "ENET10G_3_TDP")
	)
	(segment
		(start 358.151176 -5.715)
		(end 357.787956 -5.715)
		(width 0.24384)
		(layer "B.Cu")
		(net "ENET10G_3_TDP")
	)
	(segment
		(start 361.316016 -5.97916)
		(end 360.871516 -5.97916)
		(width 0.24384)
		(layer "B.Cu")
		(net "ENET10G_3_TDP")
	)
	(segment
		(start 357.462836 -5.853176)
		(end 357.448866 -5.865622)
		(width 0.24384)
		(layer "B.Cu")
		(net "ENET10G_3_TDP")
	)
	(segment
		(start 363.401102 -5.97916)
		(end 362.979716 -5.97916)
		(width 0.24384)
		(layer "B.Cu")
		(net "ENET10G_3_TDP")
	)
	(segment
		(start 354.826062 -7.18185)
		(end 354.826062 -7.218426)
		(width 0.24384)
		(layer "B.Cu")
		(net "ENET10G_3_TDP")
	)
	(segment
		(start 352.607118 -9.43737)
		(end 352.595942 -9.43737)
		(width 0.24384)
		(layer "B.Cu")
		(net "ENET10G_3_TDP")
	)
	(segment
		(start 365.481362 -6.89356)
		(end 364.984538 -6.89356)
		(width 0.24384)
		(layer "B.Cu")
		(net "ENET10G_3_TDP")
	)
	(segment
		(start 355.590094 -6.454394)
		(end 355.553518 -6.454394)
		(width 0.24384)
		(layer "B.Cu")
		(net "ENET10G_3_TDP")
	)
	(segment
		(start 351.144078 -10.90041)
		(end 349.930466 -10.90041)
		(width 0.24384)
		(layer "B.Cu")
		(net "ENET10G_3_TDP")
	)
	(segment
		(start 353.677474 -8.094726)
		(end 353.483418 -8.288782)
		(width 0.24384)
		(layer "B.Cu")
		(net "ENET10G_3_TDP")
	)
	(segment
		(start 351.694242 -10.560558)
		(end 351.503234 -10.751566)
		(width 0.24384)
		(layer "B.Cu")
		(net "ENET10G_3_TDP")
	)
	(segment
		(start 353.18573 -9.06907)
		(end 352.966274 -9.288526)
		(width 0.24384)
		(layer "B.Cu")
		(net "ENET10G_3_TDP")
	)
	(segment
		(start 359.207816 -5.97916)
		(end 358.788716 -5.97916)
		(width 0.24384)
		(layer "B.Cu")
		(net "ENET10G_3_TDP")
	)
	(segment
		(start 357.150416 -5.97916)
		(end 356.485952 -5.97916)
		(width 0.24384)
		(layer "B.Cu")
		(net "ENET10G_3_TDP")
	)
	(segment
		(start 349.930466 -10.90041)
		(end 349.530162 -10.500106)
		(width 0.24384)
		(layer "B.Cu")
		(net "ENET10G_3_TDP")
	)
	(segment
		(start 354.677218 -7.577582)
		(end 354.457762 -7.797038)
		(width 0.24384)
		(layer "B.Cu")
		(net "ENET10G_3_TDP")
	)
	(segment
		(start 351.843086 -10.190226)
		(end 351.843086 -10.201402)
		(width 0.24384)
		(layer "B.Cu")
		(net "ENET10G_3_TDP")
	)
	(segment
		(start 352.236786 -9.586214)
		(end 351.99193 -9.83107)
		(width 0.24384)
		(layer "B.Cu")
		(net "ENET10G_3_TDP")
	)
	(segment
		(start 365.719106 -6.756908)
		(end 365.653828 -6.822186)
		(width 0.24384)
		(layer "B.Cu")
		(net "ENET10G_3_TDP")
	)
	(segment
		(start 362.342176 -5.715)
		(end 361.953556 -5.715)
		(width 0.24384)
		(layer "B.Cu")
		(net "ENET10G_3_TDP")
	)
	(segment
		(start 365.4552 -5.715)
		(end 365.79048 -6.05028)
		(width 0.24384)
		(layer "B.Cu")
		(net "ENET10G_3_TDP")
	)
	(segment
		(start 354.098606 -7.945882)
		(end 354.03663 -7.945882)
		(width 0.24384)
		(layer "B.Cu")
		(net "ENET10G_3_TDP")
	)
	(segment
		(start 353.334574 -8.647938)
		(end 353.334574 -8.709914)
		(width 0.24384)
		(layer "B.Cu")
		(net "ENET10G_3_TDP")
	)
	(segment
		(start 355.194362 -6.603238)
		(end 354.974906 -6.822694)
		(width 0.24384)
		(layer "B.Cu")
		(net "ENET10G_3_TDP")
	)
	(segment
		(start 365.79048 -6.05028)
		(end 365.79048 -6.584442)
		(width 0.24384)
		(layer "B.Cu")
		(net "ENET10G_3_TDP")
	)
	(segment
		(start 364.625382 -6.744716)
		(end 364.184184 -6.303518)
		(width 0.24384)
		(layer "B.Cu")
		(net "ENET10G_3_TDP")
	)
	(segment
		(start 356.126796 -6.128004)
		(end 355.94925 -6.30555)
		(width 0.24384)
		(layer "B.Cu")
		(net "ENET10G_3_TDP")
	)
	(segment
		(start 360.233976 -5.715)
		(end 359.845356 -5.715)
		(width 0.24384)
		(layer "B.Cu")
		(net "ENET10G_3_TDP")
	)
	(arc
		(start 357.448866 -5.865622)
		(mid 357.310031 -5.949687)
		(end 357.150416 -5.97916)
		(width 0.24384)
		(layer "B.Cu")
		(net "ENET10G_3_TDP")
	)
	(arc
		(start 352.966274 -9.288526)
		(mid 352.801506 -9.398684)
		(end 352.607118 -9.43737)
		(width 0.24384)
		(layer "B.Cu")
		(net "ENET10G_3_TDP")
	)
	(arc
		(start 362.660946 -5.84708)
		(mid 362.514707 -5.749303)
		(end 362.342176 -5.715)
		(width 0.24384)
		(layer "B.Cu")
		(net "ENET10G_3_TDP")
	)
	(arc
		(start 355.553518 -6.454394)
		(mid 355.359129 -6.493078)
		(end 355.194362 -6.603238)
		(width 0.24384)
		(layer "B.Cu")
		(net "ENET10G_3_TDP")
	)
	(arc
		(start 361.953556 -5.715)
		(mid 361.781037 -5.749334)
		(end 361.634786 -5.84708)
		(width 0.24384)
		(layer "B.Cu")
		(net "ENET10G_3_TDP")
	)
	(arc
		(start 365.79048 -6.584442)
		(mid 365.771934 -6.67777)
		(end 365.719106 -6.756908)
		(width 0.24384)
		(layer "B.Cu")
		(net "ENET10G_3_TDP")
	)
	(arc
		(start 365.653828 -6.822186)
		(mid 365.574686 -6.875004)
		(end 365.481362 -6.89356)
		(width 0.24384)
		(layer "B.Cu")
		(net "ENET10G_3_TDP")
	)
	(arc
		(start 364.984538 -6.89356)
		(mid 364.790149 -6.854876)
		(end 364.625382 -6.744716)
		(width 0.24384)
		(layer "B.Cu")
		(net "ENET10G_3_TDP")
	)
	(arc
		(start 362.979716 -5.97916)
		(mid 362.819831 -5.949954)
		(end 362.680758 -5.865876)
		(width 0.24384)
		(layer "B.Cu")
		(net "ENET10G_3_TDP")
	)
	(arc
		(start 356.485952 -5.97916)
		(mid 356.291563 -6.017844)
		(end 356.126796 -6.128004)
		(width 0.24384)
		(layer "B.Cu")
		(net "ENET10G_3_TDP")
	)
	(arc
		(start 360.552746 -5.84708)
		(mid 360.406507 -5.749303)
		(end 360.233976 -5.715)
		(width 0.24384)
		(layer "B.Cu")
		(net "ENET10G_3_TDP")
	)
	(arc
		(start 355.94925 -6.30555)
		(mid 355.784482 -6.415708)
		(end 355.590094 -6.454394)
		(width 0.24384)
		(layer "B.Cu")
		(net "ENET10G_3_TDP")
	)
	(arc
		(start 351.503234 -10.751566)
		(mid 351.338466 -10.861724)
		(end 351.144078 -10.90041)
		(width 0.24384)
		(layer "B.Cu")
		(net "ENET10G_3_TDP")
	)
	(arc
		(start 353.483418 -8.288782)
		(mid 353.37326 -8.45355)
		(end 353.334574 -8.647938)
		(width 0.24384)
		(layer "B.Cu")
		(net "ENET10G_3_TDP")
	)
	(arc
		(start 354.03663 -7.945882)
		(mid 353.842241 -7.984566)
		(end 353.677474 -8.094726)
		(width 0.24384)
		(layer "B.Cu")
		(net "ENET10G_3_TDP")
	)
	(arc
		(start 357.469186 -5.84708)
		(mid 357.466026 -5.850143)
		(end 357.462836 -5.853176)
		(width 0.24384)
		(layer "B.Cu")
		(net "ENET10G_3_TDP")
	)
	(arc
		(start 358.469946 -5.84708)
		(mid 358.323707 -5.749303)
		(end 358.151176 -5.715)
		(width 0.24384)
		(layer "B.Cu")
		(net "ENET10G_3_TDP")
	)
	(arc
		(start 359.506774 -5.865876)
		(mid 359.367665 -5.94986)
		(end 359.207816 -5.97916)
		(width 0.24384)
		(layer "B.Cu")
		(net "ENET10G_3_TDP")
	)
	(arc
		(start 358.489758 -5.865876)
		(mid 358.47971 -5.856628)
		(end 358.469946 -5.84708)
		(width 0.24384)
		(layer "B.Cu")
		(net "ENET10G_3_TDP")
	)
	(arc
		(start 359.526586 -5.84708)
		(mid 359.516822 -5.856628)
		(end 359.506774 -5.865876)
		(width 0.24384)
		(layer "B.Cu")
		(net "ENET10G_3_TDP")
	)
	(arc
		(start 361.614974 -5.865876)
		(mid 361.475865 -5.94986)
		(end 361.316016 -5.97916)
		(width 0.24384)
		(layer "B.Cu")
		(net "ENET10G_3_TDP")
	)
	(arc
		(start 360.871516 -5.97916)
		(mid 360.711631 -5.949954)
		(end 360.572558 -5.865876)
		(width 0.24384)
		(layer "B.Cu")
		(net "ENET10G_3_TDP")
	)
	(arc
		(start 358.788716 -5.97916)
		(mid 358.628831 -5.949954)
		(end 358.489758 -5.865876)
		(width 0.24384)
		(layer "B.Cu")
		(net "ENET10G_3_TDP")
	)
	(arc
		(start 352.595942 -9.43737)
		(mid 352.401553 -9.476054)
		(end 352.236786 -9.586214)
		(width 0.24384)
		(layer "B.Cu")
		(net "ENET10G_3_TDP")
	)
	(arc
		(start 360.572558 -5.865876)
		(mid 360.56251 -5.856628)
		(end 360.552746 -5.84708)
		(width 0.24384)
		(layer "B.Cu")
		(net "ENET10G_3_TDP")
	)
	(arc
		(start 353.334574 -8.709914)
		(mid 353.29589 -8.904303)
		(end 353.18573 -9.06907)
		(width 0.24384)
		(layer "B.Cu")
		(net "ENET10G_3_TDP")
	)
	(arc
		(start 351.99193 -9.83107)
		(mid 351.881772 -9.995838)
		(end 351.843086 -10.190226)
		(width 0.24384)
		(layer "B.Cu")
		(net "ENET10G_3_TDP")
	)
	(arc
		(start 351.843086 -10.201402)
		(mid 351.804402 -10.395791)
		(end 351.694242 -10.560558)
		(width 0.24384)
		(layer "B.Cu")
		(net "ENET10G_3_TDP")
	)
	(arc
		(start 354.826062 -7.218426)
		(mid 354.787378 -7.412815)
		(end 354.677218 -7.577582)
		(width 0.24384)
		(layer "B.Cu")
		(net "ENET10G_3_TDP")
	)
	(arc
		(start 361.634786 -5.84708)
		(mid 361.625022 -5.856628)
		(end 361.614974 -5.865876)
		(width 0.24384)
		(layer "B.Cu")
		(net "ENET10G_3_TDP")
	)
	(arc
		(start 362.680758 -5.865876)
		(mid 362.67071 -5.856628)
		(end 362.660946 -5.84708)
		(width 0.24384)
		(layer "B.Cu")
		(net "ENET10G_3_TDP")
	)
	(arc
		(start 357.787956 -5.715)
		(mid 357.615437 -5.749334)
		(end 357.469186 -5.84708)
		(width 0.24384)
		(layer "B.Cu")
		(net "ENET10G_3_TDP")
	)
	(arc
		(start 354.457762 -7.797038)
		(mid 354.292994 -7.907196)
		(end 354.098606 -7.945882)
		(width 0.24384)
		(layer "B.Cu")
		(net "ENET10G_3_TDP")
	)
	(arc
		(start 354.974906 -6.822694)
		(mid 354.864748 -6.987462)
		(end 354.826062 -7.18185)
		(width 0.24384)
		(layer "B.Cu")
		(net "ENET10G_3_TDP")
	)
	(arc
		(start 359.845356 -5.715)
		(mid 359.672837 -5.749334)
		(end 359.526586 -5.84708)
		(width 0.24384)
		(layer "B.Cu")
		(net "ENET10G_3_TDP")
	)
	(arc
		(start 364.184184 -6.303518)
		(mid 363.824903 -6.063454)
		(end 363.401102 -5.97916)
		(width 0.24384)
		(layer "B.Cu")
		(net "ENET10G_3_TDP")
	)
	(segment
		(start 416.529774 -23.8506)
		(end 418.213032 -23.8506)
		(width 0.1778)
		(layer "F.Cu")
		(net "SAS_BLAD2_TX1_N")
	)
	(segment
		(start 416.11931 -24.261064)
		(end 416.529774 -23.8506)
		(width 0.1778)
		(layer "F.Cu")
		(net "SAS_BLAD2_TX1_N")
	)
	(segment
		(start 418.213032 -23.8506)
		(end 418.662612 -23.40102)
		(width 0.1778)
		(layer "F.Cu")
		(net "SAS_BLAD2_TX1_N")
	)
	(segment
		(start 415.895028 -25.899872)
		(end 415.895028 -24.808434)
		(width 0.1778)
		(layer "F.Cu")
		(net "SAS_BLAD2_TX1_N")
	)
	(segment
		(start 416.11931 -24.584152)
		(end 416.11931 -24.261064)
		(width 0.1778)
		(layer "F.Cu")
		(net "SAS_BLAD2_TX1_N")
	)
	(segment
		(start 415.895028 -24.808434)
		(end 416.11931 -24.584152)
		(width 0.1778)
		(layer "F.Cu")
		(net "SAS_BLAD2_TX1_N")
	)
	(via
		(at 418.662612 -23.40102)
		(size 0.508)
		(drill 0.254)
		(layers "F.Cu" "B.Cu")
		(net "SAS_BLAD2_TX1_N")
	)
	(segment
		(start 398.815814 -2.9972)
		(end 396.392908 -2.9972)
		(width 0.1524)
		(layer "In5.Cu")
		(net "SAS_BLAD2_TX1_N")
	)
	(segment
		(start 419.152324 -21.528024)
		(end 419.15207 -21.52777)
		(width 0.1524)
		(layer "In5.Cu")
		(net "SAS_BLAD2_TX1_N")
	)
	(segment
		(start 419.094412 -23.83282)
		(end 419.413182 -23.83282)
		(width 0.1524)
		(layer "In5.Cu")
		(net "SAS_BLAD2_TX1_N")
	)
	(segment
		(start 418.662612 -23.40102)
		(end 419.094412 -23.83282)
		(width 0.1524)
		(layer "In5.Cu")
		(net "SAS_BLAD2_TX1_N")
	)
	(segment
		(start 406.359614 -6.09346)
		(end 399.010886 -3.036062)
		(width 0.1524)
		(layer "In5.Cu")
		(net "SAS_BLAD2_TX1_N")
	)
	(segment
		(start 419.729666 -22.941026)
		(end 419.729412 -22.941026)
		(width 0.1524)
		(layer "In5.Cu")
		(net "SAS_BLAD2_TX1_N")
	)
	(segment
		(start 419.142926 -21.510244)
		(end 413.77616 -13.480288)
		(width 0.1524)
		(layer "In5.Cu")
		(net "SAS_BLAD2_TX1_N")
	)
	(segment
		(start 419.721792 -22.902164)
		(end 419.152324 -21.528024)
		(width 0.1524)
		(layer "In5.Cu")
		(net "SAS_BLAD2_TX1_N")
	)
	(segment
		(start 419.729666 -23.51659)
		(end 419.729666 -22.941026)
		(width 0.1524)
		(layer "In5.Cu")
		(net "SAS_BLAD2_TX1_N")
	)
	(segment
		(start 413.77616 -13.480288)
		(end 413.770826 -13.472414)
		(width 0.1524)
		(layer "In5.Cu")
		(net "SAS_BLAD2_TX1_N")
	)
	(segment
		(start 413.770826 -13.472414)
		(end 406.457404 -6.158992)
		(width 0.1524)
		(layer "In5.Cu")
		(net "SAS_BLAD2_TX1_N")
	)
	(segment
		(start 396.392908 -2.9972)
		(end 395.889988 -3.50012)
		(width 0.1524)
		(layer "In5.Cu")
		(net "SAS_BLAD2_TX1_N")
	)
	(arc
		(start 406.385776 -6.105906)
		(mid 406.372846 -6.099366)
		(end 406.359614 -6.09346)
		(width 0.1524)
		(layer "In5.Cu")
		(net "SAS_BLAD2_TX1_N")
	)
	(arc
		(start 406.41143 -6.1214)
		(mid 406.398795 -6.113336)
		(end 406.385776 -6.105906)
		(width 0.1524)
		(layer "In5.Cu")
		(net "SAS_BLAD2_TX1_N")
	)
	(arc
		(start 419.729412 -22.941026)
		(mid 419.727509 -22.921222)
		(end 419.721792 -22.902164)
		(width 0.1524)
		(layer "In5.Cu")
		(net "SAS_BLAD2_TX1_N")
	)
	(arc
		(start 419.15207 -21.52777)
		(mid 419.147929 -21.518782)
		(end 419.142926 -21.510244)
		(width 0.1524)
		(layer "In5.Cu")
		(net "SAS_BLAD2_TX1_N")
	)
	(arc
		(start 419.636956 -23.74011)
		(mid 419.705508 -23.637559)
		(end 419.729666 -23.51659)
		(width 0.1524)
		(layer "In5.Cu")
		(net "SAS_BLAD2_TX1_N")
	)
	(arc
		(start 399.010886 -3.036062)
		(mid 398.91527 -3.007)
		(end 398.815814 -2.9972)
		(width 0.1524)
		(layer "In5.Cu")
		(net "SAS_BLAD2_TX1_N")
	)
	(arc
		(start 419.413182 -23.83282)
		(mid 419.534295 -23.808729)
		(end 419.636956 -23.74011)
		(width 0.1524)
		(layer "In5.Cu")
		(net "SAS_BLAD2_TX1_N")
	)
	(arc
		(start 406.457404 -6.158992)
		(mid 406.435341 -6.139066)
		(end 406.41143 -6.1214)
		(width 0.1524)
		(layer "In5.Cu")
		(net "SAS_BLAD2_TX1_N")
	)
	(segment
		(start 113.911888 -4.5212)
		(end 108.195872 -4.5212)
		(width 0.24384)
		(layer "F.Cu")
		(net "ENET10G_2_TDP")
	)
	(segment
		(start 114.623596 -5.022596)
		(end 114.271044 -4.670044)
		(width 0.24384)
		(layer "F.Cu")
		(net "ENET10G_2_TDP")
	)
	(segment
		(start 106.769916 -8.952738)
		(end 106.769916 -10.289794)
		(width 0.24384)
		(layer "F.Cu")
		(net "ENET10G_2_TDP")
	)
	(segment
		(start 107.41279 -4.845558)
		(end 107.194604 -5.063744)
		(width 0.24384)
		(layer "F.Cu")
		(net "ENET10G_2_TDP")
	)
	(segment
		(start 106.870246 -5.846826)
		(end 106.870246 -8.852408)
		(width 0.24384)
		(layer "F.Cu")
		(net "ENET10G_2_TDP")
	)
	(segment
		(start 106.870246 -8.852408)
		(end 106.769916 -8.952738)
		(width 0.24384)
		(layer "F.Cu")
		(net "ENET10G_2_TDP")
	)
	(segment
		(start 114.77244 -8.78332)
		(end 114.77244 -5.381752)
		(width 0.24384)
		(layer "F.Cu")
		(net "ENET10G_2_TDP")
	)
	(segment
		(start 115.18392 -9.1948)
		(end 114.77244 -8.78332)
		(width 0.24384)
		(layer "F.Cu")
		(net "ENET10G_2_TDP")
	)
	(via
		(at 115.18392 -9.1948)
		(size 0.508)
		(drill 0.254)
		(layers "F.Cu" "B.Cu")
		(net "ENET10G_2_TDP")
	)
	(arc
		(start 114.271044 -4.670044)
		(mid 114.106276 -4.559886)
		(end 113.911888 -4.5212)
		(width 0.24384)
		(layer "F.Cu")
		(net "ENET10G_2_TDP")
	)
	(arc
		(start 107.194604 -5.063744)
		(mid 106.95454 -5.423025)
		(end 106.870246 -5.846826)
		(width 0.24384)
		(layer "F.Cu")
		(net "ENET10G_2_TDP")
	)
	(arc
		(start 108.195872 -4.5212)
		(mid 107.772073 -4.605499)
		(end 107.41279 -4.845558)
		(width 0.24384)
		(layer "F.Cu")
		(net "ENET10G_2_TDP")
	)
	(arc
		(start 114.77244 -5.381752)
		(mid 114.733756 -5.187363)
		(end 114.623596 -5.022596)
		(width 0.24384)
		(layer "F.Cu")
		(net "ENET10G_2_TDP")
	)
	(segment
		(start 115.509294 -12.200382)
		(end 118.129812 -12.200382)
		(width 0.24384)
		(layer "B.Cu")
		(net "ENET10G_2_TDP")
	)
	(segment
		(start 114.921284 -11.822684)
		(end 115.150138 -12.051538)
		(width 0.24384)
		(layer "B.Cu")
		(net "ENET10G_2_TDP")
	)
	(segment
		(start 118.129812 -12.200382)
		(end 118.530116 -11.800078)
		(width 0.24384)
		(layer "B.Cu")
		(net "ENET10G_2_TDP")
	)
	(segment
		(start 114.77244 -9.60628)
		(end 114.77244 -11.463528)
		(width 0.24384)
		(layer "B.Cu")
		(net "ENET10G_2_TDP")
	)
	(segment
		(start 115.18392 -9.1948)
		(end 114.77244 -9.60628)
		(width 0.24384)
		(layer "B.Cu")
		(net "ENET10G_2_TDP")
	)
	(arc
		(start 115.150138 -12.051538)
		(mid 115.314906 -12.161696)
		(end 115.509294 -12.200382)
		(width 0.24384)
		(layer "B.Cu")
		(net "ENET10G_2_TDP")
	)
	(arc
		(start 114.77244 -11.463528)
		(mid 114.811124 -11.657917)
		(end 114.921284 -11.822684)
		(width 0.24384)
		(layer "B.Cu")
		(net "ENET10G_2_TDP")
	)
	(segment
		(start 390.084818 -29.50083)
		(end 389.860028 -29.72562)
		(width 0.1778)
		(layer "F.Cu")
		(net "SAS_BLAD2_RX8_P")
	)
	(segment
		(start 389.860028 -30.27426)
		(end 390.319768 -30.734)
		(width 0.1778)
		(layer "F.Cu")
		(net "SAS_BLAD2_RX8_P")
	)
	(segment
		(start 390.084818 -28.4099)
		(end 390.084818 -29.50083)
		(width 0.1778)
		(layer "F.Cu")
		(net "SAS_BLAD2_RX8_P")
	)
	(segment
		(start 389.860028 -29.72562)
		(end 389.860028 -30.27426)
		(width 0.1778)
		(layer "F.Cu")
		(net "SAS_BLAD2_RX8_P")
	)
	(via
		(at 390.319768 -30.734)
		(size 0.508)
		(drill 0.254)
		(layers "F.Cu" "B.Cu")
		(net "SAS_BLAD2_RX8_P")
	)
	(segment
		(start 388.146798 -31.77794)
		(end 387.138926 -30.770068)
		(width 0.1778)
		(layer "B.Cu")
		(net "SAS_BLAD2_RX8_P")
	)
	(segment
		(start 389.711438 -31.872428)
		(end 389.703564 -31.880302)
		(width 0.1778)
		(layer "B.Cu")
		(net "SAS_BLAD2_RX8_P")
	)
	(segment
		(start 384.217926 -4.332732)
		(end 384.37439 -4.176268)
		(width 0.1778)
		(layer "B.Cu")
		(net "SAS_BLAD2_RX8_P")
	)
	(segment
		(start 390.319768 -30.734)
		(end 389.860282 -31.193486)
		(width 0.1778)
		(layer "B.Cu")
		(net "SAS_BLAD2_RX8_P")
	)
	(segment
		(start 386.887466 -30.163008)
		(end 386.887466 -27.205432)
		(width 0.1778)
		(layer "B.Cu")
		(net "SAS_BLAD2_RX8_P")
	)
	(segment
		(start 386.841238 -27.09418)
		(end 384.217926 -24.470868)
		(width 0.1778)
		(layer "B.Cu")
		(net "SAS_BLAD2_RX8_P")
	)
	(segment
		(start 389.344154 -32.0294)
		(end 388.753858 -32.0294)
		(width 0.1778)
		(layer "B.Cu")
		(net "SAS_BLAD2_RX8_P")
	)
	(segment
		(start 384.98145 -3.924808)
		(end 385.365244 -3.924808)
		(width 0.1778)
		(layer "B.Cu")
		(net "SAS_BLAD2_RX8_P")
	)
	(segment
		(start 389.860282 -31.193486)
		(end 389.860282 -31.513272)
		(width 0.1778)
		(layer "B.Cu")
		(net "SAS_BLAD2_RX8_P")
	)
	(segment
		(start 385.365244 -3.924808)
		(end 385.890008 -3.400044)
		(width 0.1778)
		(layer "B.Cu")
		(net "SAS_BLAD2_RX8_P")
	)
	(segment
		(start 383.966466 -23.863808)
		(end 383.966466 -4.939792)
		(width 0.1778)
		(layer "B.Cu")
		(net "SAS_BLAD2_RX8_P")
	)
	(arc
		(start 384.37439 -4.176268)
		(mid 384.652911 -3.990166)
		(end 384.98145 -3.924808)
		(width 0.1778)
		(layer "B.Cu")
		(net "SAS_BLAD2_RX8_P")
	)
	(arc
		(start 384.217926 -24.470868)
		(mid 384.031824 -24.192347)
		(end 383.966466 -23.863808)
		(width 0.1778)
		(layer "B.Cu")
		(net "SAS_BLAD2_RX8_P")
	)
	(arc
		(start 383.966466 -4.939792)
		(mid 384.031817 -4.611251)
		(end 384.217926 -4.332732)
		(width 0.1778)
		(layer "B.Cu")
		(net "SAS_BLAD2_RX8_P")
	)
	(arc
		(start 387.138926 -30.770068)
		(mid 386.952824 -30.491547)
		(end 386.887466 -30.163008)
		(width 0.1778)
		(layer "B.Cu")
		(net "SAS_BLAD2_RX8_P")
	)
	(arc
		(start 389.860282 -31.513272)
		(mid 389.821598 -31.707661)
		(end 389.711438 -31.872428)
		(width 0.1778)
		(layer "B.Cu")
		(net "SAS_BLAD2_RX8_P")
	)
	(arc
		(start 386.887466 -27.205432)
		(mid 386.875448 -27.145196)
		(end 386.841238 -27.09418)
		(width 0.1778)
		(layer "B.Cu")
		(net "SAS_BLAD2_RX8_P")
	)
	(arc
		(start 388.753858 -32.0294)
		(mid 388.425317 -31.964049)
		(end 388.146798 -31.77794)
		(width 0.1778)
		(layer "B.Cu")
		(net "SAS_BLAD2_RX8_P")
	)
	(arc
		(start 389.703564 -31.880302)
		(mid 389.538708 -31.990645)
		(end 389.344154 -32.0294)
		(width 0.1778)
		(layer "B.Cu")
		(net "SAS_BLAD2_RX8_P")
	)
	(segment
		(start 113.8174 -7.282688)
		(end 113.8174 -7.017512)
		(width 0.24384)
		(layer "F.Cu")
		(net "ENET10G_2_TDN")
	)
	(segment
		(start 111.940848 -5.47624)
		(end 111.629952 -5.47624)
		(width 0.24384)
		(layer "F.Cu")
		(net "ENET10G_2_TDN")
	)
	(segment
		(start 111.270796 -5.327396)
		(end 111.212884 -5.269484)
		(width 0.24384)
		(layer "F.Cu")
		(net "ENET10G_2_TDN")
	)
	(segment
		(start 114.173 -8.78332)
		(end 114.173 -8.058912)
		(width 0.24384)
		(layer "F.Cu")
		(net "ENET10G_2_TDN")
	)
	(segment
		(start 108.669328 -5.12064)
		(end 108.195872 -5.12064)
		(width 0.24384)
		(layer "F.Cu")
		(net "ENET10G_2_TDN")
	)
	(segment
		(start 109.086396 -5.327396)
		(end 109.028484 -5.269484)
		(width 0.24384)
		(layer "F.Cu")
		(net "ENET10G_2_TDN")
	)
	(segment
		(start 107.469686 -5.846826)
		(end 107.469686 -8.852408)
		(width 0.24384)
		(layer "F.Cu")
		(net "ENET10G_2_TDN")
	)
	(segment
		(start 114.173 -6.241288)
		(end 114.173 -5.520944)
		(width 0.24384)
		(layer "F.Cu")
		(net "ENET10G_2_TDN")
	)
	(segment
		(start 107.836716 -5.269484)
		(end 107.61853 -5.48767)
		(width 0.24384)
		(layer "F.Cu")
		(net "ENET10G_2_TDN")
	)
	(segment
		(start 114.024156 -7.699756)
		(end 113.966244 -7.641844)
		(width 0.24384)
		(layer "F.Cu")
		(net "ENET10G_2_TDN")
	)
	(segment
		(start 110.198916 -5.269484)
		(end 110.141004 -5.327396)
		(width 0.24384)
		(layer "F.Cu")
		(net "ENET10G_2_TDN")
	)
	(segment
		(start 113.966244 -6.658356)
		(end 114.024156 -6.600444)
		(width 0.24384)
		(layer "F.Cu")
		(net "ENET10G_2_TDN")
	)
	(segment
		(start 112.357916 -5.269484)
		(end 112.300004 -5.327396)
		(width 0.24384)
		(layer "F.Cu")
		(net "ENET10G_2_TDN")
	)
	(segment
		(start 113.76152 -9.1948)
		(end 114.173 -8.78332)
		(width 0.24384)
		(layer "F.Cu")
		(net "ENET10G_2_TDN")
	)
	(segment
		(start 109.781848 -5.47624)
		(end 109.445552 -5.47624)
		(width 0.24384)
		(layer "F.Cu")
		(net "ENET10G_2_TDN")
	)
	(segment
		(start 107.570016 -8.952738)
		(end 107.570016 -10.289794)
		(width 0.24384)
		(layer "F.Cu")
		(net "ENET10G_2_TDN")
	)
	(segment
		(start 114.101626 -5.348478)
		(end 113.945162 -5.192014)
		(width 0.24384)
		(layer "F.Cu")
		(net "ENET10G_2_TDN")
	)
	(segment
		(start 107.469686 -8.852408)
		(end 107.570016 -8.952738)
		(width 0.24384)
		(layer "F.Cu")
		(net "ENET10G_2_TDN")
	)
	(segment
		(start 110.853728 -5.12064)
		(end 110.558072 -5.12064)
		(width 0.24384)
		(layer "F.Cu")
		(net "ENET10G_2_TDN")
	)
	(segment
		(start 113.772696 -5.12064)
		(end 112.717072 -5.12064)
		(width 0.24384)
		(layer "F.Cu")
		(net "ENET10G_2_TDN")
	)
	(via
		(at 113.76152 -9.1948)
		(size 0.508)
		(drill 0.254)
		(layers "F.Cu" "B.Cu")
		(net "ENET10G_2_TDN")
	)
	(arc
		(start 109.445552 -5.47624)
		(mid 109.251163 -5.437556)
		(end 109.086396 -5.327396)
		(width 0.24384)
		(layer "F.Cu")
		(net "ENET10G_2_TDN")
	)
	(arc
		(start 110.558072 -5.12064)
		(mid 110.363683 -5.159324)
		(end 110.198916 -5.269484)
		(width 0.24384)
		(layer "F.Cu")
		(net "ENET10G_2_TDN")
	)
	(arc
		(start 114.173 -5.520944)
		(mid 114.154454 -5.427616)
		(end 114.101626 -5.348478)
		(width 0.24384)
		(layer "F.Cu")
		(net "ENET10G_2_TDN")
	)
	(arc
		(start 111.212884 -5.269484)
		(mid 111.048116 -5.159326)
		(end 110.853728 -5.12064)
		(width 0.24384)
		(layer "F.Cu")
		(net "ENET10G_2_TDN")
	)
	(arc
		(start 107.61853 -5.48767)
		(mid 107.508372 -5.652438)
		(end 107.469686 -5.846826)
		(width 0.24384)
		(layer "F.Cu")
		(net "ENET10G_2_TDN")
	)
	(arc
		(start 113.945162 -5.192014)
		(mid 113.86602 -5.139196)
		(end 113.772696 -5.12064)
		(width 0.24384)
		(layer "F.Cu")
		(net "ENET10G_2_TDN")
	)
	(arc
		(start 114.173 -8.058912)
		(mid 114.134316 -7.864523)
		(end 114.024156 -7.699756)
		(width 0.24384)
		(layer "F.Cu")
		(net "ENET10G_2_TDN")
	)
	(arc
		(start 111.629952 -5.47624)
		(mid 111.435563 -5.437556)
		(end 111.270796 -5.327396)
		(width 0.24384)
		(layer "F.Cu")
		(net "ENET10G_2_TDN")
	)
	(arc
		(start 108.195872 -5.12064)
		(mid 108.001483 -5.159324)
		(end 107.836716 -5.269484)
		(width 0.24384)
		(layer "F.Cu")
		(net "ENET10G_2_TDN")
	)
	(arc
		(start 112.300004 -5.327396)
		(mid 112.135236 -5.437554)
		(end 111.940848 -5.47624)
		(width 0.24384)
		(layer "F.Cu")
		(net "ENET10G_2_TDN")
	)
	(arc
		(start 114.024156 -6.600444)
		(mid 114.134314 -6.435676)
		(end 114.173 -6.241288)
		(width 0.24384)
		(layer "F.Cu")
		(net "ENET10G_2_TDN")
	)
	(arc
		(start 113.966244 -7.641844)
		(mid 113.856086 -7.477076)
		(end 113.8174 -7.282688)
		(width 0.24384)
		(layer "F.Cu")
		(net "ENET10G_2_TDN")
	)
	(arc
		(start 112.717072 -5.12064)
		(mid 112.522683 -5.159324)
		(end 112.357916 -5.269484)
		(width 0.24384)
		(layer "F.Cu")
		(net "ENET10G_2_TDN")
	)
	(arc
		(start 109.028484 -5.269484)
		(mid 108.863716 -5.159326)
		(end 108.669328 -5.12064)
		(width 0.24384)
		(layer "F.Cu")
		(net "ENET10G_2_TDN")
	)
	(arc
		(start 110.141004 -5.327396)
		(mid 109.976236 -5.437554)
		(end 109.781848 -5.47624)
		(width 0.24384)
		(layer "F.Cu")
		(net "ENET10G_2_TDN")
	)
	(arc
		(start 113.8174 -7.017512)
		(mid 113.856084 -6.823123)
		(end 113.966244 -6.658356)
		(width 0.24384)
		(layer "F.Cu")
		(net "ENET10G_2_TDN")
	)
	(segment
		(start 113.76152 -9.1948)
		(end 114.172492 -9.605772)
		(width 0.24384)
		(layer "B.Cu")
		(net "ENET10G_2_TDN")
	)
	(segment
		(start 114.0333 -11.0109)
		(end 114.062256 -11.039856)
		(width 0.24384)
		(layer "B.Cu")
		(net "ENET10G_2_TDN")
	)
	(segment
		(start 117.13464 -13.04036)
		(end 117.22608 -12.94892)
		(width 0.24384)
		(layer "B.Cu")
		(net "ENET10G_2_TDN")
	)
	(segment
		(start 115.509294 -12.799822)
		(end 115.71351 -12.799822)
		(width 0.24384)
		(layer "B.Cu")
		(net "ENET10G_2_TDN")
	)
	(segment
		(start 118.129812 -12.799822)
		(end 118.530116 -13.200126)
		(width 0.24384)
		(layer "B.Cu")
		(net "ENET10G_2_TDN")
	)
	(segment
		(start 114.067082 -10.011918)
		(end 114.042444 -10.036556)
		(width 0.24384)
		(layer "B.Cu")
		(net "ENET10G_2_TDN")
	)
	(segment
		(start 114.172492 -9.605772)
		(end 114.172492 -9.777476)
		(width 0.24384)
		(layer "B.Cu")
		(net "ENET10G_2_TDN")
	)
	(segment
		(start 116.466112 -13.1318)
		(end 116.913914 -13.1318)
		(width 0.24384)
		(layer "B.Cu")
		(net "ENET10G_2_TDN")
	)
	(segment
		(start 114.173 -11.307064)
		(end 114.173 -11.463528)
		(width 0.24384)
		(layer "B.Cu")
		(net "ENET10G_2_TDN")
	)
	(segment
		(start 116.072666 -12.948666)
		(end 116.106956 -12.982956)
		(width 0.24384)
		(layer "B.Cu")
		(net "ENET10G_2_TDN")
	)
	(segment
		(start 113.8936 -10.395712)
		(end 113.8936 -10.673588)
		(width 0.24384)
		(layer "B.Cu")
		(net "ENET10G_2_TDN")
	)
	(segment
		(start 117.58549 -12.799822)
		(end 118.129812 -12.799822)
		(width 0.24384)
		(layer "B.Cu")
		(net "ENET10G_2_TDN")
	)
	(segment
		(start 114.497358 -12.24661)
		(end 114.726212 -12.475464)
		(width 0.24384)
		(layer "B.Cu")
		(net "ENET10G_2_TDN")
	)
	(arc
		(start 113.8936 -10.673588)
		(mid 113.92991 -10.856133)
		(end 114.0333 -11.0109)
		(width 0.24384)
		(layer "B.Cu")
		(net "ENET10G_2_TDN")
	)
	(arc
		(start 114.173 -11.463528)
		(mid 114.257299 -11.887327)
		(end 114.497358 -12.24661)
		(width 0.24384)
		(layer "B.Cu")
		(net "ENET10G_2_TDN")
	)
	(arc
		(start 116.106956 -12.982956)
		(mid 116.271724 -13.093114)
		(end 116.466112 -13.1318)
		(width 0.24384)
		(layer "B.Cu")
		(net "ENET10G_2_TDN")
	)
	(arc
		(start 115.71351 -12.799822)
		(mid 115.907899 -12.838506)
		(end 116.072666 -12.948666)
		(width 0.24384)
		(layer "B.Cu")
		(net "ENET10G_2_TDN")
	)
	(arc
		(start 116.913914 -13.1318)
		(mid 117.033375 -13.108038)
		(end 117.13464 -13.04036)
		(width 0.24384)
		(layer "B.Cu")
		(net "ENET10G_2_TDN")
	)
	(arc
		(start 117.22608 -12.94892)
		(mid 117.390936 -12.838577)
		(end 117.58549 -12.799822)
		(width 0.24384)
		(layer "B.Cu")
		(net "ENET10G_2_TDN")
	)
	(arc
		(start 114.042444 -10.036556)
		(mid 113.932286 -10.201324)
		(end 113.8936 -10.395712)
		(width 0.24384)
		(layer "B.Cu")
		(net "ENET10G_2_TDN")
	)
	(arc
		(start 114.062256 -11.039856)
		(mid 114.144226 -11.162438)
		(end 114.173 -11.307064)
		(width 0.24384)
		(layer "B.Cu")
		(net "ENET10G_2_TDN")
	)
	(arc
		(start 114.172492 -9.777476)
		(mid 114.141275 -9.904351)
		(end 114.067082 -10.011918)
		(width 0.24384)
		(layer "B.Cu")
		(net "ENET10G_2_TDN")
	)
	(arc
		(start 114.726212 -12.475464)
		(mid 115.085493 -12.715528)
		(end 115.509294 -12.799822)
		(width 0.24384)
		(layer "B.Cu")
		(net "ENET10G_2_TDN")
	)
	(segment
		(start 345.170252 -35.9791)
		(end 344.669364 -36.980876)
		(width 0.14732)
		(layer "B.Cu")
		(net "ENET1G_3_MDI2P")
	)
	(segment
		(start 346.3036 -35.154108)
		(end 347.370908 -34.0868)
		(width 0.14732)
		(layer "B.Cu")
		(net "ENET1G_3_MDI2P")
	)
	(segment
		(start 344.911426 -37.266372)
		(end 344.946986 -37.301932)
		(width 0.14732)
		(layer "B.Cu")
		(net "ENET1G_3_MDI2P")
	)
	(segment
		(start 347.359732 -3.947668)
		(end 347.530166 -3.777234)
		(width 0.14732)
		(layer "B.Cu")
		(net "ENET1G_3_MDI2P")
	)
	(segment
		(start 346.3036 -36.678108)
		(end 346.3036 -35.154108)
		(width 0.14732)
		(layer "B.Cu")
		(net "ENET1G_3_MDI2P")
	)
	(segment
		(start 347.370908 -34.0868)
		(end 348.457266 -34.0868)
		(width 0.14732)
		(layer "B.Cu")
		(net "ENET1G_3_MDI2P")
	)
	(segment
		(start 344.946986 -37.301932)
		(end 345.679776 -37.301932)
		(width 0.14732)
		(layer "B.Cu")
		(net "ENET1G_3_MDI2P")
	)
	(segment
		(start 344.669364 -36.980876)
		(end 344.735404 -37.178488)
		(width 0.14732)
		(layer "B.Cu")
		(net "ENET1G_3_MDI2P")
	)
	(segment
		(start 350.159066 -18.586958)
		(end 346.383102 -14.810994)
		(width 0.14732)
		(layer "B.Cu")
		(net "ENET1G_3_MDI2P")
	)
	(segment
		(start 347.530166 -3.777234)
		(end 347.530166 -3.400044)
		(width 0.14732)
		(layer "B.Cu")
		(net "ENET1G_3_MDI2P")
	)
	(segment
		(start 345.679776 -37.301932)
		(end 346.3036 -36.678108)
		(width 0.14732)
		(layer "B.Cu")
		(net "ENET1G_3_MDI2P")
	)
	(segment
		(start 350.159066 -32.385)
		(end 350.159066 -18.586958)
		(width 0.14732)
		(layer "B.Cu")
		(net "ENET1G_3_MDI2P")
	)
	(segment
		(start 344.735404 -37.178488)
		(end 344.911426 -37.266372)
		(width 0.14732)
		(layer "B.Cu")
		(net "ENET1G_3_MDI2P")
	)
	(segment
		(start 346.70873 -3.947668)
		(end 347.359732 -3.947668)
		(width 0.14732)
		(layer "B.Cu")
		(net "ENET1G_3_MDI2P")
	)
	(segment
		(start 346.383102 -14.810994)
		(end 346.383102 -4.273296)
		(width 0.14732)
		(layer "B.Cu")
		(net "ENET1G_3_MDI2P")
	)
	(segment
		(start 346.383102 -4.273296)
		(end 346.70873 -3.947668)
		(width 0.14732)
		(layer "B.Cu")
		(net "ENET1G_3_MDI2P")
	)
	(segment
		(start 348.457266 -34.0868)
		(end 350.159066 -32.385)
		(width 0.14732)
		(layer "B.Cu")
		(net "ENET1G_3_MDI2P")
	)
	(segment
		(start 102.070154 -5.91312)
		(end 102.070154 -8.852408)
		(width 0.24384)
		(layer "F.Cu")
		(net "ENET10G_2_RDN")
	)
	(segment
		(start 101.970078 -8.952484)
		(end 101.970078 -10.289794)
		(width 0.24384)
		(layer "F.Cu")
		(net "ENET10G_2_RDN")
	)
	(segment
		(start 101.734874 -5.57784)
		(end 102.070154 -5.91312)
		(width 0.24384)
		(layer "F.Cu")
		(net "ENET10G_2_RDN")
	)
	(segment
		(start 102.070154 -8.852408)
		(end 101.970078 -8.952484)
		(width 0.24384)
		(layer "F.Cu")
		(net "ENET10G_2_RDN")
	)
	(via
		(at 101.734874 -5.57784)
		(size 0.508)
		(drill 0.254)
		(layers "F.Cu" "B.Cu")
		(net "ENET10G_2_RDN")
	)
	(segment
		(start 103.907844 -7.318756)
		(end 103.965756 -7.260844)
		(width 0.24384)
		(layer "B.Cu")
		(net "ENET10G_2_RDN")
	)
	(segment
		(start 101.993954 -5.83692)
		(end 101.993954 -6.584442)
		(width 0.24384)
		(layer "B.Cu")
		(net "ENET10G_2_RDN")
	)
	(segment
		(start 101.734874 -5.57784)
		(end 101.993954 -5.83692)
		(width 0.24384)
		(layer "B.Cu")
		(net "ENET10G_2_RDN")
	)
	(segment
		(start 102.877112 -7.4676)
		(end 103.548688 -7.4676)
		(width 0.24384)
		(layer "B.Cu")
		(net "ENET10G_2_RDN")
	)
	(segment
		(start 104.324912 -7.112)
		(end 115.535456 -7.112)
		(width 0.24384)
		(layer "B.Cu")
		(net "ENET10G_2_RDN")
	)
	(segment
		(start 115.707922 -7.183374)
		(end 116.799868 -8.27532)
		(width 0.24384)
		(layer "B.Cu")
		(net "ENET10G_2_RDN")
	)
	(segment
		(start 118.129812 -8.599678)
		(end 118.530116 -8.999982)
		(width 0.24384)
		(layer "B.Cu")
		(net "ENET10G_2_RDN")
	)
	(segment
		(start 102.142798 -6.943598)
		(end 102.517956 -7.318756)
		(width 0.24384)
		(layer "B.Cu")
		(net "ENET10G_2_RDN")
	)
	(segment
		(start 117.58295 -8.599678)
		(end 118.129812 -8.599678)
		(width 0.24384)
		(layer "B.Cu")
		(net "ENET10G_2_RDN")
	)
	(arc
		(start 103.965756 -7.260844)
		(mid 104.130524 -7.150686)
		(end 104.324912 -7.112)
		(width 0.24384)
		(layer "B.Cu")
		(net "ENET10G_2_RDN")
	)
	(arc
		(start 116.799868 -8.27532)
		(mid 117.159149 -8.515384)
		(end 117.58295 -8.599678)
		(width 0.24384)
		(layer "B.Cu")
		(net "ENET10G_2_RDN")
	)
	(arc
		(start 101.993954 -6.584442)
		(mid 102.032638 -6.778831)
		(end 102.142798 -6.943598)
		(width 0.24384)
		(layer "B.Cu")
		(net "ENET10G_2_RDN")
	)
	(arc
		(start 103.548688 -7.4676)
		(mid 103.743077 -7.428916)
		(end 103.907844 -7.318756)
		(width 0.24384)
		(layer "B.Cu")
		(net "ENET10G_2_RDN")
	)
	(arc
		(start 102.517956 -7.318756)
		(mid 102.682724 -7.428914)
		(end 102.877112 -7.4676)
		(width 0.24384)
		(layer "B.Cu")
		(net "ENET10G_2_RDN")
	)
	(arc
		(start 115.535456 -7.112)
		(mid 115.628784 -7.130546)
		(end 115.707922 -7.183374)
		(width 0.24384)
		(layer "B.Cu")
		(net "ENET10G_2_RDN")
	)
	(segment
		(start 346.450666 -34.9758)
		(end 346.450666 -38.508686)
		(width 0.1524)
		(layer "In5.Cu")
		(net "ENET1G_3_MDI1P")
	)
	(segment
		(start 348.838266 -8.587232)
		(end 348.838266 -20.0152)
		(width 0.1524)
		(layer "In5.Cu")
		(net "ENET1G_3_MDI1P")
	)
	(segment
		(start 348.347792 -8.096758)
		(end 348.838266 -8.587232)
		(width 0.1524)
		(layer "In5.Cu")
		(net "ENET1G_3_MDI1P")
	)
	(segment
		(start 347.885766 -33.5407)
		(end 346.450666 -34.9758)
		(width 0.1524)
		(layer "In5.Cu")
		(net "ENET1G_3_MDI1P")
	)
	(segment
		(start 346.450666 -38.508686)
		(end 346.440252 -38.5191)
		(width 0.1524)
		(layer "In5.Cu")
		(net "ENET1G_3_MDI1P")
	)
	(segment
		(start 348.838266 -20.0152)
		(end 347.339666 -21.5138)
		(width 0.1524)
		(layer "In5.Cu")
		(net "ENET1G_3_MDI1P")
	)
	(segment
		(start 347.339666 -21.5138)
		(end 347.339666 -27.8638)
		(width 0.1524)
		(layer "In5.Cu")
		(net "ENET1G_3_MDI1P")
	)
	(segment
		(start 347.339666 -27.8638)
		(end 346.806266 -28.3972)
		(width 0.1524)
		(layer "In5.Cu")
		(net "ENET1G_3_MDI1P")
	)
	(segment
		(start 347.530166 -7.957058)
		(end 347.669866 -8.096758)
		(width 0.1524)
		(layer "In5.Cu")
		(net "ENET1G_3_MDI1P")
	)
	(segment
		(start 346.806266 -28.3972)
		(end 346.806266 -30.0482)
		(width 0.1524)
		(layer "In5.Cu")
		(net "ENET1G_3_MDI1P")
	)
	(segment
		(start 347.530166 -7.600188)
		(end 347.530166 -7.957058)
		(width 0.1524)
		(layer "In5.Cu")
		(net "ENET1G_3_MDI1P")
	)
	(segment
		(start 347.669866 -8.096758)
		(end 348.347792 -8.096758)
		(width 0.1524)
		(layer "In5.Cu")
		(net "ENET1G_3_MDI1P")
	)
	(segment
		(start 347.885766 -31.1277)
		(end 347.885766 -33.5407)
		(width 0.1524)
		(layer "In5.Cu")
		(net "ENET1G_3_MDI1P")
	)
	(segment
		(start 346.806266 -30.0482)
		(end 347.885766 -31.1277)
		(width 0.1524)
		(layer "In5.Cu")
		(net "ENET1G_3_MDI1P")
	)
	(segment
		(start 119.883936 -37.566854)
		(end 120.360186 -38.5191)
		(width 0.1524)
		(layer "In2.Cu")
		(net "ENET1G_1_MDI3P")
	)
	(segment
		(start 125.349 -16.602202)
		(end 125.349 -18.264124)
		(width 0.1524)
		(layer "In2.Cu")
		(net "ENET1G_1_MDI3P")
	)
	(segment
		(start 125.1966 -22.531324)
		(end 125.349 -22.683724)
		(width 0.1524)
		(layer "In2.Cu")
		(net "ENET1G_1_MDI3P")
	)
	(segment
		(start 125.349 -20.702524)
		(end 125.1966 -20.854924)
		(width 0.1524)
		(layer "In2.Cu")
		(net "ENET1G_1_MDI3P")
	)
	(segment
		(start 123.32208 -14.575282)
		(end 125.349 -16.602202)
		(width 0.1524)
		(layer "In2.Cu")
		(net "ENET1G_1_MDI3P")
	)
	(segment
		(start 129.2606 -33.537398)
		(end 129.0066 -33.791398)
		(width 0.1524)
		(layer "In2.Cu")
		(net "ENET1G_1_MDI3P")
	)
	(segment
		(start 119.253 -37.857176)
		(end 119.543068 -37.567108)
		(width 0.1524)
		(layer "In2.Cu")
		(net "ENET1G_1_MDI3P")
	)
	(segment
		(start 124.530104 -2.444496)
		(end 124.377704 -2.596896)
		(width 0.1524)
		(layer "In2.Cu")
		(net "ENET1G_1_MDI3P")
	)
	(segment
		(start 125.349 -25.4)
		(end 129.2606 -29.3116)
		(width 0.1524)
		(layer "In2.Cu")
		(net "ENET1G_1_MDI3P")
	)
	(segment
		(start 125.349 -18.264124)
		(end 125.1966 -18.416524)
		(width 0.1524)
		(layer "In2.Cu")
		(net "ENET1G_1_MDI3P")
	)
	(segment
		(start 119.679466 -37.499036)
		(end 119.883936 -37.566854)
		(width 0.1524)
		(layer "In2.Cu")
		(net "ENET1G_1_MDI3P")
	)
	(segment
		(start 125.1966 -18.416524)
		(end 125.1966 -18.873724)
		(width 0.1524)
		(layer "In2.Cu")
		(net "ENET1G_1_MDI3P")
	)
	(segment
		(start 125.1966 -20.092924)
		(end 125.349 -20.245324)
		(width 0.1524)
		(layer "In2.Cu")
		(net "ENET1G_1_MDI3P")
	)
	(segment
		(start 119.9896 -39.7764)
		(end 119.253 -39.0398)
		(width 0.1524)
		(layer "In2.Cu")
		(net "ENET1G_1_MDI3P")
	)
	(segment
		(start 119.543068 -37.567108)
		(end 119.679466 -37.499036)
		(width 0.1524)
		(layer "In2.Cu")
		(net "ENET1G_1_MDI3P")
	)
	(segment
		(start 119.253 -39.0398)
		(end 119.253 -37.857176)
		(width 0.1524)
		(layer "In2.Cu")
		(net "ENET1G_1_MDI3P")
	)
	(segment
		(start 123.32208 -2.987294)
		(end 123.32208 -14.575282)
		(width 0.1524)
		(layer "In2.Cu")
		(net "ENET1G_1_MDI3P")
	)
	(segment
		(start 128.482598 -39.7764)
		(end 119.9896 -39.7764)
		(width 0.1524)
		(layer "In2.Cu")
		(net "ENET1G_1_MDI3P")
	)
	(segment
		(start 125.349 -21.921724)
		(end 125.1966 -22.074124)
		(width 0.1524)
		(layer "In2.Cu")
		(net "ENET1G_1_MDI3P")
	)
	(segment
		(start 125.1966 -22.074124)
		(end 125.1966 -22.531324)
		(width 0.1524)
		(layer "In2.Cu")
		(net "ENET1G_1_MDI3P")
	)
	(segment
		(start 129.0066 -33.791398)
		(end 129.0066 -39.252398)
		(width 0.1524)
		(layer "In2.Cu")
		(net "ENET1G_1_MDI3P")
	)
	(segment
		(start 125.349 -22.683724)
		(end 125.349 -25.4)
		(width 0.1524)
		(layer "In2.Cu")
		(net "ENET1G_1_MDI3P")
	)
	(segment
		(start 129.2606 -29.3116)
		(end 129.2606 -33.537398)
		(width 0.1524)
		(layer "In2.Cu")
		(net "ENET1G_1_MDI3P")
	)
	(segment
		(start 125.349 -21.464524)
		(end 125.349 -21.921724)
		(width 0.1524)
		(layer "In2.Cu")
		(net "ENET1G_1_MDI3P")
	)
	(segment
		(start 125.1966 -20.854924)
		(end 125.1966 -21.312124)
		(width 0.1524)
		(layer "In2.Cu")
		(net "ENET1G_1_MDI3P")
	)
	(segment
		(start 125.349 -19.483324)
		(end 125.1966 -19.635724)
		(width 0.1524)
		(layer "In2.Cu")
		(net "ENET1G_1_MDI3P")
	)
	(segment
		(start 125.349 -20.245324)
		(end 125.349 -20.702524)
		(width 0.1524)
		(layer "In2.Cu")
		(net "ENET1G_1_MDI3P")
	)
	(segment
		(start 125.1966 -18.873724)
		(end 125.349 -19.026124)
		(width 0.1524)
		(layer "In2.Cu")
		(net "ENET1G_1_MDI3P")
	)
	(segment
		(start 125.1966 -21.312124)
		(end 125.349 -21.464524)
		(width 0.1524)
		(layer "In2.Cu")
		(net "ENET1G_1_MDI3P")
	)
	(segment
		(start 129.0066 -39.252398)
		(end 128.482598 -39.7764)
		(width 0.1524)
		(layer "In2.Cu")
		(net "ENET1G_1_MDI3P")
	)
	(segment
		(start 124.530104 -2.100072)
		(end 124.530104 -2.444496)
		(width 0.1524)
		(layer "In2.Cu")
		(net "ENET1G_1_MDI3P")
	)
	(segment
		(start 123.712478 -2.596896)
		(end 123.32208 -2.987294)
		(width 0.1524)
		(layer "In2.Cu")
		(net "ENET1G_1_MDI3P")
	)
	(segment
		(start 125.349 -19.026124)
		(end 125.349 -19.483324)
		(width 0.1524)
		(layer "In2.Cu")
		(net "ENET1G_1_MDI3P")
	)
	(segment
		(start 124.377704 -2.596896)
		(end 123.712478 -2.596896)
		(width 0.1524)
		(layer "In2.Cu")
		(net "ENET1G_1_MDI3P")
	)
	(segment
		(start 125.1966 -19.635724)
		(end 125.1966 -20.092924)
		(width 0.1524)
		(layer "In2.Cu")
		(net "ENET1G_1_MDI3P")
	)
	(segment
		(start 25.841706 -16.754602)
		(end 23.555452 -16.754602)
		(width 0.28956)
		(layer "F.Cu")
		(net "PS_EN_PSU_N")
	)
	(segment
		(start 23.555452 -16.754602)
		(end 22.809962 -17.500092)
		(width 0.28956)
		(layer "F.Cu")
		(net "PS_EN_PSU_N")
	)
	(segment
		(start 345.53017 -2.455926)
		(end 345.53017 -2.100072)
		(width 0.1524)
		(layer "In2.Cu")
		(net "ENET1G_3_MDI3P")
	)
	(segment
		(start 340.486746 -37.566854)
		(end 340.1822 -37.8714)
		(width 0.1524)
		(layer "In2.Cu")
		(net "ENET1G_3_MDI3P")
	)
	(segment
		(start 346.3036 -19.867372)
		(end 346.1512 -19.714972)
		(width 0.1524)
		(layer "In2.Cu")
		(net "ENET1G_3_MDI3P")
	)
	(segment
		(start 345.3892 -2.596896)
		(end 345.53017 -2.455926)
		(width 0.1524)
		(layer "In2.Cu")
		(net "ENET1G_3_MDI3P")
	)
	(segment
		(start 346.3036 -21.086572)
		(end 346.1512 -20.934172)
		(width 0.1524)
		(layer "In2.Cu")
		(net "ENET1G_3_MDI3P")
	)
	(segment
		(start 346.3036 -17.886172)
		(end 346.3036 -16.475202)
		(width 0.1524)
		(layer "In2.Cu")
		(net "ENET1G_3_MDI3P")
	)
	(segment
		(start 346.1512 -18.038572)
		(end 346.3036 -17.886172)
		(width 0.1524)
		(layer "In2.Cu")
		(net "ENET1G_3_MDI3P")
	)
	(segment
		(start 346.3036 -16.475202)
		(end 344.3224 -14.494002)
		(width 0.1524)
		(layer "In2.Cu")
		(net "ENET1G_3_MDI3P")
	)
	(segment
		(start 346.3036 -25.8318)
		(end 346.3036 -22.305772)
		(width 0.1524)
		(layer "In2.Cu")
		(net "ENET1G_3_MDI3P")
	)
	(segment
		(start 346.1512 -18.495772)
		(end 346.1512 -18.038572)
		(width 0.1524)
		(layer "In2.Cu")
		(net "ENET1G_3_MDI3P")
	)
	(segment
		(start 346.1512 -22.153372)
		(end 346.1512 -21.696172)
		(width 0.1524)
		(layer "In2.Cu")
		(net "ENET1G_3_MDI3P")
	)
	(segment
		(start 350.006666 -39.252398)
		(end 350.006666 -33.791398)
		(width 0.1524)
		(layer "In2.Cu")
		(net "ENET1G_3_MDI3P")
	)
	(segment
		(start 346.1512 -21.696172)
		(end 346.3036 -21.543772)
		(width 0.1524)
		(layer "In2.Cu")
		(net "ENET1G_3_MDI3P")
	)
	(segment
		(start 340.884002 -37.566854)
		(end 340.679532 -37.499036)
		(width 0.1524)
		(layer "In2.Cu")
		(net "ENET1G_3_MDI3P")
	)
	(segment
		(start 346.1512 -19.257772)
		(end 346.3036 -19.105372)
		(width 0.1524)
		(layer "In2.Cu")
		(net "ENET1G_3_MDI3P")
	)
	(segment
		(start 340.1822 -38.998398)
		(end 340.960202 -39.7764)
		(width 0.1524)
		(layer "In2.Cu")
		(net "ENET1G_3_MDI3P")
	)
	(segment
		(start 346.3036 -20.324572)
		(end 346.3036 -19.867372)
		(width 0.1524)
		(layer "In2.Cu")
		(net "ENET1G_3_MDI3P")
	)
	(segment
		(start 340.679532 -37.499036)
		(end 340.678008 -37.499544)
		(width 0.1524)
		(layer "In2.Cu")
		(net "ENET1G_3_MDI3P")
	)
	(segment
		(start 346.1512 -20.476972)
		(end 346.3036 -20.324572)
		(width 0.1524)
		(layer "In2.Cu")
		(net "ENET1G_3_MDI3P")
	)
	(segment
		(start 346.1512 -20.934172)
		(end 346.1512 -20.476972)
		(width 0.1524)
		(layer "In2.Cu")
		(net "ENET1G_3_MDI3P")
	)
	(segment
		(start 344.3224 -3.133598)
		(end 344.859102 -2.596896)
		(width 0.1524)
		(layer "In2.Cu")
		(net "ENET1G_3_MDI3P")
	)
	(segment
		(start 340.960202 -39.7764)
		(end 349.482664 -39.7764)
		(width 0.1524)
		(layer "In2.Cu")
		(net "ENET1G_3_MDI3P")
	)
	(segment
		(start 340.678008 -37.499544)
		(end 340.543134 -37.566854)
		(width 0.1524)
		(layer "In2.Cu")
		(net "ENET1G_3_MDI3P")
	)
	(segment
		(start 350.260666 -33.537398)
		(end 350.260666 -29.788866)
		(width 0.1524)
		(layer "In2.Cu")
		(net "ENET1G_3_MDI3P")
	)
	(segment
		(start 340.1822 -37.8714)
		(end 340.1822 -38.998398)
		(width 0.1524)
		(layer "In2.Cu")
		(net "ENET1G_3_MDI3P")
	)
	(segment
		(start 344.3224 -14.494002)
		(end 344.3224 -3.133598)
		(width 0.1524)
		(layer "In2.Cu")
		(net "ENET1G_3_MDI3P")
	)
	(segment
		(start 346.3036 -19.105372)
		(end 346.3036 -18.648172)
		(width 0.1524)
		(layer "In2.Cu")
		(net "ENET1G_3_MDI3P")
	)
	(segment
		(start 344.859102 -2.596896)
		(end 345.3892 -2.596896)
		(width 0.1524)
		(layer "In2.Cu")
		(net "ENET1G_3_MDI3P")
	)
	(segment
		(start 349.482664 -39.7764)
		(end 350.006666 -39.252398)
		(width 0.1524)
		(layer "In2.Cu")
		(net "ENET1G_3_MDI3P")
	)
	(segment
		(start 346.1512 -19.714972)
		(end 346.1512 -19.257772)
		(width 0.1524)
		(layer "In2.Cu")
		(net "ENET1G_3_MDI3P")
	)
	(segment
		(start 346.3036 -21.543772)
		(end 346.3036 -21.086572)
		(width 0.1524)
		(layer "In2.Cu")
		(net "ENET1G_3_MDI3P")
	)
	(segment
		(start 350.260666 -29.788866)
		(end 346.3036 -25.8318)
		(width 0.1524)
		(layer "In2.Cu")
		(net "ENET1G_3_MDI3P")
	)
	(segment
		(start 346.3036 -18.648172)
		(end 346.1512 -18.495772)
		(width 0.1524)
		(layer "In2.Cu")
		(net "ENET1G_3_MDI3P")
	)
	(segment
		(start 341.360252 -38.5191)
		(end 340.884002 -37.566854)
		(width 0.1524)
		(layer "In2.Cu")
		(net "ENET1G_3_MDI3P")
	)
	(segment
		(start 340.543134 -37.566854)
		(end 340.486746 -37.566854)
		(width 0.1524)
		(layer "In2.Cu")
		(net "ENET1G_3_MDI3P")
	)
	(segment
		(start 350.006666 -33.791398)
		(end 350.260666 -33.537398)
		(width 0.1524)
		(layer "In2.Cu")
		(net "ENET1G_3_MDI3P")
	)
	(segment
		(start 346.3036 -22.305772)
		(end 346.1512 -22.153372)
		(width 0.1524)
		(layer "In2.Cu")
		(net "ENET1G_3_MDI3P")
	)
	(segment
		(start 102.669594 -8.852408)
		(end 102.769924 -8.952738)
		(width 0.24384)
		(layer "F.Cu")
		(net "ENET10G_2_RDP")
	)
	(segment
		(start 102.769924 -8.952738)
		(end 102.769924 -10.289794)
		(width 0.24384)
		(layer "F.Cu")
		(net "ENET10G_2_RDP")
	)
	(segment
		(start 102.669594 -5.91312)
		(end 102.669594 -8.852408)
		(width 0.24384)
		(layer "F.Cu")
		(net "ENET10G_2_RDP")
	)
	(segment
		(start 103.004874 -5.57784)
		(end 102.669594 -5.91312)
		(width 0.24384)
		(layer "F.Cu")
		(net "ENET10G_2_RDP")
	)
	(via
		(at 103.004874 -5.57784)
		(size 0.508)
		(drill 0.254)
		(layers "F.Cu" "B.Cu")
		(net "ENET10G_2_RDP")
	)
	(segment
		(start 109.235748 -6.1976)
		(end 109.716824 -6.1976)
		(width 0.24384)
		(layer "B.Cu")
		(net "ENET10G_2_RDP")
	)
	(segment
		(start 102.593394 -5.98932)
		(end 102.593394 -6.44525)
		(width 0.24384)
		(layer "B.Cu")
		(net "ENET10G_2_RDP")
	)
	(segment
		(start 102.664768 -6.617716)
		(end 102.843838 -6.796786)
		(width 0.24384)
		(layer "B.Cu")
		(net "ENET10G_2_RDP")
	)
	(segment
		(start 108.03382 -6.346444)
		(end 108.051092 -6.363716)
		(width 0.24384)
		(layer "B.Cu")
		(net "ENET10G_2_RDP")
	)
	(segment
		(start 113.401348 -6.1976)
		(end 113.835688 -6.1976)
		(width 0.24384)
		(layer "B.Cu")
		(net "ENET10G_2_RDP")
	)
	(segment
		(start 117.58295 -8.000238)
		(end 118.130066 -8.000238)
		(width 0.24384)
		(layer "B.Cu")
		(net "ENET10G_2_RDP")
	)
	(segment
		(start 107.254548 -6.1976)
		(end 107.674664 -6.1976)
		(width 0.24384)
		(layer "B.Cu")
		(net "ENET10G_2_RDP")
	)
	(segment
		(start 103.510588 -6.86816)
		(end 103.54183 -6.836918)
		(width 0.24384)
		(layer "B.Cu")
		(net "ENET10G_2_RDP")
	)
	(segment
		(start 110.452408 -6.51256)
		(end 110.701328 -6.51256)
		(width 0.24384)
		(layer "B.Cu")
		(net "ENET10G_2_RDP")
	)
	(segment
		(start 106.971084 -6.363716)
		(end 107.054142 -6.280658)
		(width 0.24384)
		(layer "B.Cu")
		(net "ENET10G_2_RDP")
	)
	(segment
		(start 113.117884 -6.363716)
		(end 113.200942 -6.280658)
		(width 0.24384)
		(layer "B.Cu")
		(net "ENET10G_2_RDP")
	)
	(segment
		(start 114.194844 -6.346444)
		(end 114.212116 -6.363716)
		(width 0.24384)
		(layer "B.Cu")
		(net "ENET10G_2_RDP")
	)
	(segment
		(start 103.004874 -5.57784)
		(end 102.593394 -5.98932)
		(width 0.24384)
		(layer "B.Cu")
		(net "ENET10G_2_RDP")
	)
	(segment
		(start 118.130066 -8.000238)
		(end 118.530116 -7.600188)
		(width 0.24384)
		(layer "B.Cu")
		(net "ENET10G_2_RDP")
	)
	(segment
		(start 110.07598 -6.346444)
		(end 110.093252 -6.363716)
		(width 0.24384)
		(layer "B.Cu")
		(net "ENET10G_2_RDP")
	)
	(segment
		(start 105.204768 -6.223)
		(end 105.669334 -6.223)
		(width 0.24384)
		(layer "B.Cu")
		(net "ENET10G_2_RDP")
	)
	(segment
		(start 104.324912 -6.51256)
		(end 104.605328 -6.51256)
		(width 0.24384)
		(layer "B.Cu")
		(net "ENET10G_2_RDP")
	)
	(segment
		(start 108.410248 -6.51256)
		(end 108.593128 -6.51256)
		(width 0.24384)
		(layer "B.Cu")
		(net "ENET10G_2_RDP")
	)
	(segment
		(start 103.016304 -6.86816)
		(end 103.510588 -6.86816)
		(width 0.24384)
		(layer "B.Cu")
		(net "ENET10G_2_RDP")
	)
	(segment
		(start 106.368088 -6.51256)
		(end 106.611928 -6.51256)
		(width 0.24384)
		(layer "B.Cu")
		(net "ENET10G_2_RDP")
	)
	(segment
		(start 112.494568 -6.51256)
		(end 112.758728 -6.51256)
		(width 0.24384)
		(layer "B.Cu")
		(net "ENET10G_2_RDP")
	)
	(segment
		(start 108.952284 -6.363716)
		(end 109.035342 -6.280658)
		(width 0.24384)
		(layer "B.Cu")
		(net "ENET10G_2_RDP")
	)
	(segment
		(start 112.11814 -6.346444)
		(end 112.135412 -6.363716)
		(width 0.24384)
		(layer "B.Cu")
		(net "ENET10G_2_RDP")
	)
	(segment
		(start 116.033804 -6.661404)
		(end 117.223794 -7.851394)
		(width 0.24384)
		(layer "B.Cu")
		(net "ENET10G_2_RDP")
	)
	(segment
		(start 114.571272 -6.51256)
		(end 115.674648 -6.51256)
		(width 0.24384)
		(layer "B.Cu")
		(net "ENET10G_2_RDP")
	)
	(segment
		(start 104.964484 -6.363716)
		(end 105.034842 -6.293358)
		(width 0.24384)
		(layer "B.Cu")
		(net "ENET10G_2_RDP")
	)
	(segment
		(start 111.343948 -6.1976)
		(end 111.758984 -6.1976)
		(width 0.24384)
		(layer "B.Cu")
		(net "ENET10G_2_RDP")
	)
	(segment
		(start 111.060484 -6.363716)
		(end 111.143542 -6.280658)
		(width 0.24384)
		(layer "B.Cu")
		(net "ENET10G_2_RDP")
	)
	(arc
		(start 110.701328 -6.51256)
		(mid 110.895717 -6.473876)
		(end 111.060484 -6.363716)
		(width 0.24384)
		(layer "B.Cu")
		(net "ENET10G_2_RDP")
	)
	(arc
		(start 102.843838 -6.796786)
		(mid 102.92298 -6.849604)
		(end 103.016304 -6.86816)
		(width 0.24384)
		(layer "B.Cu")
		(net "ENET10G_2_RDP")
	)
	(arc
		(start 108.593128 -6.51256)
		(mid 108.787517 -6.473876)
		(end 108.952284 -6.363716)
		(width 0.24384)
		(layer "B.Cu")
		(net "ENET10G_2_RDP")
	)
	(arc
		(start 112.135412 -6.363716)
		(mid 112.30018 -6.473874)
		(end 112.494568 -6.51256)
		(width 0.24384)
		(layer "B.Cu")
		(net "ENET10G_2_RDP")
	)
	(arc
		(start 109.716824 -6.1976)
		(mid 109.911213 -6.236284)
		(end 110.07598 -6.346444)
		(width 0.24384)
		(layer "B.Cu")
		(net "ENET10G_2_RDP")
	)
	(arc
		(start 102.593394 -6.44525)
		(mid 102.61194 -6.538578)
		(end 102.664768 -6.617716)
		(width 0.24384)
		(layer "B.Cu")
		(net "ENET10G_2_RDP")
	)
	(arc
		(start 106.008932 -6.363716)
		(mid 106.1737 -6.473874)
		(end 106.368088 -6.51256)
		(width 0.24384)
		(layer "B.Cu")
		(net "ENET10G_2_RDP")
	)
	(arc
		(start 115.674648 -6.51256)
		(mid 115.869037 -6.551244)
		(end 116.033804 -6.661404)
		(width 0.24384)
		(layer "B.Cu")
		(net "ENET10G_2_RDP")
	)
	(arc
		(start 104.605328 -6.51256)
		(mid 104.799717 -6.473876)
		(end 104.964484 -6.363716)
		(width 0.24384)
		(layer "B.Cu")
		(net "ENET10G_2_RDP")
	)
	(arc
		(start 114.212116 -6.363716)
		(mid 114.376884 -6.473874)
		(end 114.571272 -6.51256)
		(width 0.24384)
		(layer "B.Cu")
		(net "ENET10G_2_RDP")
	)
	(arc
		(start 105.034842 -6.293358)
		(mid 105.112805 -6.241265)
		(end 105.204768 -6.223)
		(width 0.24384)
		(layer "B.Cu")
		(net "ENET10G_2_RDP")
	)
	(arc
		(start 111.143542 -6.280658)
		(mid 111.235475 -6.219167)
		(end 111.343948 -6.1976)
		(width 0.24384)
		(layer "B.Cu")
		(net "ENET10G_2_RDP")
	)
	(arc
		(start 107.674664 -6.1976)
		(mid 107.869053 -6.236284)
		(end 108.03382 -6.346444)
		(width 0.24384)
		(layer "B.Cu")
		(net "ENET10G_2_RDP")
	)
	(arc
		(start 113.835688 -6.1976)
		(mid 114.030077 -6.236284)
		(end 114.194844 -6.346444)
		(width 0.24384)
		(layer "B.Cu")
		(net "ENET10G_2_RDP")
	)
	(arc
		(start 108.051092 -6.363716)
		(mid 108.21586 -6.473874)
		(end 108.410248 -6.51256)
		(width 0.24384)
		(layer "B.Cu")
		(net "ENET10G_2_RDP")
	)
	(arc
		(start 112.758728 -6.51256)
		(mid 112.953117 -6.473876)
		(end 113.117884 -6.363716)
		(width 0.24384)
		(layer "B.Cu")
		(net "ENET10G_2_RDP")
	)
	(arc
		(start 106.611928 -6.51256)
		(mid 106.806317 -6.473876)
		(end 106.971084 -6.363716)
		(width 0.24384)
		(layer "B.Cu")
		(net "ENET10G_2_RDP")
	)
	(arc
		(start 103.54183 -6.836918)
		(mid 103.901111 -6.596854)
		(end 104.324912 -6.51256)
		(width 0.24384)
		(layer "B.Cu")
		(net "ENET10G_2_RDP")
	)
	(arc
		(start 109.035342 -6.280658)
		(mid 109.127275 -6.219167)
		(end 109.235748 -6.1976)
		(width 0.24384)
		(layer "B.Cu")
		(net "ENET10G_2_RDP")
	)
	(arc
		(start 113.200942 -6.280658)
		(mid 113.292875 -6.219167)
		(end 113.401348 -6.1976)
		(width 0.24384)
		(layer "B.Cu")
		(net "ENET10G_2_RDP")
	)
	(arc
		(start 117.223794 -7.851394)
		(mid 117.388562 -7.961552)
		(end 117.58295 -8.000238)
		(width 0.24384)
		(layer "B.Cu")
		(net "ENET10G_2_RDP")
	)
	(arc
		(start 105.669334 -6.223)
		(mid 105.853128 -6.259577)
		(end 106.008932 -6.363716)
		(width 0.24384)
		(layer "B.Cu")
		(net "ENET10G_2_RDP")
	)
	(arc
		(start 111.758984 -6.1976)
		(mid 111.953373 -6.236284)
		(end 112.11814 -6.346444)
		(width 0.24384)
		(layer "B.Cu")
		(net "ENET10G_2_RDP")
	)
	(arc
		(start 110.093252 -6.363716)
		(mid 110.25802 -6.473874)
		(end 110.452408 -6.51256)
		(width 0.24384)
		(layer "B.Cu")
		(net "ENET10G_2_RDP")
	)
	(arc
		(start 107.054142 -6.280658)
		(mid 107.146075 -6.219167)
		(end 107.254548 -6.1976)
		(width 0.24384)
		(layer "B.Cu")
		(net "ENET10G_2_RDP")
	)
	(segment
		(start 406.147524 -30.60192)
		(end 405.688292 -30.142688)
		(width 0.1778)
		(layer "F.Cu")
		(net "SAS_BLAD2_RX4_P")
	)
	(segment
		(start 405.688292 -29.7688)
		(end 405.228552 -29.30906)
		(width 0.1778)
		(layer "F.Cu")
		(net "SAS_BLAD2_RX4_P")
	)
	(segment
		(start 408.895296 -29.70022)
		(end 408.895296 -30.151324)
		(width 0.1778)
		(layer "F.Cu")
		(net "SAS_BLAD2_RX4_P")
	)
	(segment
		(start 409.09494 -29.500576)
		(end 408.895296 -29.70022)
		(width 0.1778)
		(layer "F.Cu")
		(net "SAS_BLAD2_RX4_P")
	)
	(segment
		(start 409.09494 -28.4099)
		(end 409.09494 -29.500576)
		(width 0.1778)
		(layer "F.Cu")
		(net "SAS_BLAD2_RX4_P")
	)
	(segment
		(start 408.4447 -30.60192)
		(end 406.147524 -30.60192)
		(width 0.1778)
		(layer "F.Cu")
		(net "SAS_BLAD2_RX4_P")
	)
	(segment
		(start 408.895296 -30.151324)
		(end 408.4447 -30.60192)
		(width 0.1778)
		(layer "F.Cu")
		(net "SAS_BLAD2_RX4_P")
	)
	(segment
		(start 405.688292 -30.142688)
		(end 405.688292 -29.7688)
		(width 0.1778)
		(layer "F.Cu")
		(net "SAS_BLAD2_RX4_P")
	)
	(via
		(at 405.228552 -29.30906)
		(size 0.508)
		(drill 0.254)
		(layers "F.Cu" "B.Cu")
		(net "SAS_BLAD2_RX4_P")
	)
	(segment
		(start 391.289794 -15.23873)
		(end 390.8298 -14.12748)
		(width 0.1524)
		(layer "In5.Cu")
		(net "SAS_BLAD2_RX4_P")
	)
	(segment
		(start 403.092666 -26.332688)
		(end 403.092666 -25.635712)
		(width 0.1524)
		(layer "In5.Cu")
		(net "SAS_BLAD2_RX4_P")
	)
	(segment
		(start 390.8298 -14.12748)
		(end 390.690862 -13.292582)
		(width 0.1524)
		(layer "In5.Cu")
		(net "SAS_BLAD2_RX4_P")
	)
	(segment
		(start 391.757662 -6.796786)
		(end 391.889996 -6.664452)
		(width 0.1524)
		(layer "In5.Cu")
		(net "SAS_BLAD2_RX4_P")
	)
	(segment
		(start 405.630888 -28.436824)
		(end 405.468582 -28.274518)
		(width 0.1524)
		(layer "In5.Cu")
		(net "SAS_BLAD2_RX4_P")
	)
	(segment
		(start 405.396954 -28.2448)
		(end 405.004778 -28.2448)
		(width 0.1524)
		(layer "In5.Cu")
		(net "SAS_BLAD2_RX4_P")
	)
	(segment
		(start 393.563094 -17.51203)
		(end 391.289794 -15.23873)
		(width 0.1524)
		(layer "In5.Cu")
		(net "SAS_BLAD2_RX4_P")
	)
	(segment
		(start 402.943822 -25.276556)
		(end 396.438374 -18.771108)
		(width 0.1524)
		(layer "In5.Cu")
		(net "SAS_BLAD2_RX4_P")
	)
	(segment
		(start 405.228552 -29.30906)
		(end 405.660606 -28.877006)
		(width 0.1524)
		(layer "In5.Cu")
		(net "SAS_BLAD2_RX4_P")
	)
	(segment
		(start 390.8552 -7.008114)
		(end 390.878568 -6.984746)
		(width 0.1524)
		(layer "In5.Cu")
		(net "SAS_BLAD2_RX4_P")
	)
	(segment
		(start 391.331958 -6.796786)
		(end 391.757662 -6.796786)
		(width 0.1524)
		(layer "In5.Cu")
		(net "SAS_BLAD2_RX4_P")
	)
	(segment
		(start 394.705586 -17.78)
		(end 394.209778 -17.78)
		(width 0.1524)
		(layer "In5.Cu")
		(net "SAS_BLAD2_RX4_P")
	)
	(segment
		(start 404.358094 -27.97683)
		(end 403.360382 -26.979372)
		(width 0.1524)
		(layer "In5.Cu")
		(net "SAS_BLAD2_RX4_P")
	)
	(segment
		(start 391.889996 -6.664452)
		(end 391.889996 -6.299962)
		(width 0.1524)
		(layer "In5.Cu")
		(net "SAS_BLAD2_RX4_P")
	)
	(segment
		(start 395.3256 -18.028666)
		(end 394.744448 -17.787874)
		(width 0.1524)
		(layer "In5.Cu")
		(net "SAS_BLAD2_RX4_P")
	)
	(segment
		(start 396.42288 -18.758662)
		(end 395.343126 -18.038064)
		(width 0.1524)
		(layer "In5.Cu")
		(net "SAS_BLAD2_RX4_P")
	)
	(segment
		(start 405.660606 -28.877006)
		(end 405.660606 -28.508452)
		(width 0.1524)
		(layer "In5.Cu")
		(net "SAS_BLAD2_RX4_P")
	)
	(segment
		(start 390.690862 -13.292582)
		(end 390.690862 -7.403846)
		(width 0.1524)
		(layer "In5.Cu")
		(net "SAS_BLAD2_RX4_P")
	)
	(arc
		(start 396.438374 -18.771108)
		(mid 396.430932 -18.764506)
		(end 396.42288 -18.758662)
		(width 0.1524)
		(layer "In5.Cu")
		(net "SAS_BLAD2_RX4_P")
	)
	(arc
		(start 403.092666 -25.635712)
		(mid 403.053982 -25.441323)
		(end 402.943822 -25.276556)
		(width 0.1524)
		(layer "In5.Cu")
		(net "SAS_BLAD2_RX4_P")
	)
	(arc
		(start 403.360382 -26.979372)
		(mid 403.162162 -26.68267)
		(end 403.092666 -26.332688)
		(width 0.1524)
		(layer "In5.Cu")
		(net "SAS_BLAD2_RX4_P")
	)
	(arc
		(start 405.004778 -28.2448)
		(mid 404.654769 -28.175161)
		(end 404.358094 -27.97683)
		(width 0.1524)
		(layer "In5.Cu")
		(net "SAS_BLAD2_RX4_P")
	)
	(arc
		(start 394.744448 -17.787874)
		(mid 394.725406 -17.782009)
		(end 394.705586 -17.78)
		(width 0.1524)
		(layer "In5.Cu")
		(net "SAS_BLAD2_RX4_P")
	)
	(arc
		(start 390.878568 -6.984746)
		(mid 391.086557 -6.845646)
		(end 391.331958 -6.796786)
		(width 0.1524)
		(layer "In5.Cu")
		(net "SAS_BLAD2_RX4_P")
	)
	(arc
		(start 390.690862 -7.403846)
		(mid 390.733585 -7.189602)
		(end 390.8552 -7.008114)
		(width 0.1524)
		(layer "In5.Cu")
		(net "SAS_BLAD2_RX4_P")
	)
	(arc
		(start 395.343126 -18.038064)
		(mid 395.33459 -18.032943)
		(end 395.3256 -18.028666)
		(width 0.1524)
		(layer "In5.Cu")
		(net "SAS_BLAD2_RX4_P")
	)
	(arc
		(start 405.660606 -28.508452)
		(mid 405.652876 -28.469683)
		(end 405.630888 -28.436824)
		(width 0.1524)
		(layer "In5.Cu")
		(net "SAS_BLAD2_RX4_P")
	)
	(arc
		(start 405.468582 -28.274518)
		(mid 405.435733 -28.252506)
		(end 405.396954 -28.2448)
		(width 0.1524)
		(layer "In5.Cu")
		(net "SAS_BLAD2_RX4_P")
	)
	(arc
		(start 394.209778 -17.78)
		(mid 393.859769 -17.710361)
		(end 393.563094 -17.51203)
		(width 0.1524)
		(layer "In5.Cu")
		(net "SAS_BLAD2_RX4_P")
	)
	(segment
		(start 119.497602 -37.135308)
		(end 119.565928 -36.930838)
		(width 0.1524)
		(layer "In2.Cu")
		(net "ENET1G_1_MDI3N")
	)
	(segment
		(start 123.72848 -3.155696)
		(end 123.72848 -14.40688)
		(width 0.1524)
		(layer "In2.Cu")
		(net "ENET1G_1_MDI3N")
	)
	(segment
		(start 119.565928 -36.930838)
		(end 119.090186 -35.9791)
		(width 0.1524)
		(layer "In2.Cu")
		(net "ENET1G_1_MDI3N")
	)
	(segment
		(start 129.667 -29.143198)
		(end 129.667 -33.7058)
		(width 0.1524)
		(layer "In2.Cu")
		(net "ENET1G_1_MDI3N")
	)
	(segment
		(start 128.651 -40.1828)
		(end 119.821198 -40.1828)
		(width 0.1524)
		(layer "In2.Cu")
		(net "ENET1G_1_MDI3N")
	)
	(segment
		(start 123.72848 -14.40688)
		(end 125.7554 -16.4338)
		(width 0.1524)
		(layer "In2.Cu")
		(net "ENET1G_1_MDI3N")
	)
	(segment
		(start 119.361204 -37.20338)
		(end 119.497602 -37.135308)
		(width 0.1524)
		(layer "In2.Cu")
		(net "ENET1G_1_MDI3N")
	)
	(segment
		(start 118.8466 -37.688774)
		(end 119.302276 -37.232844)
		(width 0.1524)
		(layer "In2.Cu")
		(net "ENET1G_1_MDI3N")
	)
	(segment
		(start 129.413 -33.9598)
		(end 129.413 -39.4208)
		(width 0.1524)
		(layer "In2.Cu")
		(net "ENET1G_1_MDI3N")
	)
	(segment
		(start 125.7554 -25.231598)
		(end 129.667 -29.143198)
		(width 0.1524)
		(layer "In2.Cu")
		(net "ENET1G_1_MDI3N")
	)
	(segment
		(start 119.821198 -40.1828)
		(end 118.8466 -39.208202)
		(width 0.1524)
		(layer "In2.Cu")
		(net "ENET1G_1_MDI3N")
	)
	(segment
		(start 123.88088 -3.003296)
		(end 123.72848 -3.155696)
		(width 0.1524)
		(layer "In2.Cu")
		(net "ENET1G_1_MDI3N")
	)
	(segment
		(start 119.302276 -37.232844)
		(end 119.361204 -37.20338)
		(width 0.1524)
		(layer "In2.Cu")
		(net "ENET1G_1_MDI3N")
	)
	(segment
		(start 124.530104 -3.50012)
		(end 124.530104 -3.0988)
		(width 0.1524)
		(layer "In2.Cu")
		(net "ENET1G_1_MDI3N")
	)
	(segment
		(start 118.8466 -39.208202)
		(end 118.8466 -37.688774)
		(width 0.1524)
		(layer "In2.Cu")
		(net "ENET1G_1_MDI3N")
	)
	(segment
		(start 124.530104 -3.0988)
		(end 124.4346 -3.003296)
		(width 0.1524)
		(layer "In2.Cu")
		(net "ENET1G_1_MDI3N")
	)
	(segment
		(start 124.4346 -3.003296)
		(end 123.88088 -3.003296)
		(width 0.1524)
		(layer "In2.Cu")
		(net "ENET1G_1_MDI3N")
	)
	(segment
		(start 129.413 -39.4208)
		(end 128.651 -40.1828)
		(width 0.1524)
		(layer "In2.Cu")
		(net "ENET1G_1_MDI3N")
	)
	(segment
		(start 125.7554 -16.4338)
		(end 125.7554 -25.231598)
		(width 0.1524)
		(layer "In2.Cu")
		(net "ENET1G_1_MDI3N")
	)
	(segment
		(start 129.667 -33.7058)
		(end 129.413 -33.9598)
		(width 0.1524)
		(layer "In2.Cu")
		(net "ENET1G_1_MDI3N")
	)
	(segment
		(start 361.02671 -4.441444)
		(end 361.440984 -4.855718)
		(width 0.24384)
		(layer "F.Cu")
		(net "ENET10G_3_RDP")
	)
	(segment
		(start 361.589828 -5.214874)
		(end 361.589828 -8.852662)
		(width 0.24384)
		(layer "F.Cu")
		(net "ENET10G_3_RDP")
	)
	(segment
		(start 361.690158 -8.952992)
		(end 361.690158 -10.289794)
		(width 0.24384)
		(layer "F.Cu")
		(net "ENET10G_3_RDP")
	)
	(segment
		(start 354.253546 -4.2926)
		(end 360.667554 -4.2926)
		(width 0.24384)
		(layer "F.Cu")
		(net "ENET10G_3_RDP")
	)
	(segment
		(start 361.589828 -8.852662)
		(end 361.690158 -8.952992)
		(width 0.24384)
		(layer "F.Cu")
		(net "ENET10G_3_RDP")
	)
	(segment
		(start 353.918266 -3.95732)
		(end 354.253546 -4.2926)
		(width 0.24384)
		(layer "F.Cu")
		(net "ENET10G_3_RDP")
	)
	(via
		(at 353.918266 -3.95732)
		(size 0.508)
		(drill 0.254)
		(layers "F.Cu" "B.Cu")
		(net "ENET10G_3_RDP")
	)
	(arc
		(start 361.440984 -4.855718)
		(mid 361.551142 -5.020486)
		(end 361.589828 -5.214874)
		(width 0.24384)
		(layer "F.Cu")
		(net "ENET10G_3_RDP")
	)
	(arc
		(start 360.667554 -4.2926)
		(mid 360.861943 -4.331284)
		(end 361.02671 -4.441444)
		(width 0.24384)
		(layer "F.Cu")
		(net "ENET10G_3_RDP")
	)
	(segment
		(start 353.918266 -3.95732)
		(end 353.582986 -4.2926)
		(width 0.24384)
		(layer "B.Cu")
		(net "ENET10G_3_RDP")
	)
	(segment
		(start 353.582986 -4.2926)
		(end 351.477834 -4.2926)
		(width 0.24384)
		(layer "B.Cu")
		(net "ENET10G_3_RDP")
	)
	(segment
		(start 350.332294 -6.700266)
		(end 349.930466 -6.700266)
		(width 0.24384)
		(layer "B.Cu")
		(net "ENET10G_3_RDP")
	)
	(segment
		(start 350.540066 -5.230368)
		(end 350.540066 -6.492494)
		(width 0.24384)
		(layer "B.Cu")
		(net "ENET10G_3_RDP")
	)
	(segment
		(start 349.930466 -6.700266)
		(end 349.530162 -6.299962)
		(width 0.24384)
		(layer "B.Cu")
		(net "ENET10G_3_RDP")
	)
	(arc
		(start 350.81464 -4.567174)
		(mid 350.611437 -4.871478)
		(end 350.540066 -5.230368)
		(width 0.24384)
		(layer "B.Cu")
		(net "ENET10G_3_RDP")
	)
	(arc
		(start 351.477834 -4.2926)
		(mid 351.118937 -4.363953)
		(end 350.81464 -4.567174)
		(width 0.24384)
		(layer "B.Cu")
		(net "ENET10G_3_RDP")
	)
	(arc
		(start 350.47936 -6.639306)
		(mid 350.4119 -6.684445)
		(end 350.332294 -6.700266)
		(width 0.24384)
		(layer "B.Cu")
		(net "ENET10G_3_RDP")
	)
	(arc
		(start 350.540066 -6.492494)
		(mid 350.524285 -6.571922)
		(end 350.47936 -6.639306)
		(width 0.24384)
		(layer "B.Cu")
		(net "ENET10G_3_RDP")
	)
	(segment
		(start 358.370378 -4.89204)
		(end 358.752394 -4.89204)
		(width 0.24384)
		(layer "F.Cu")
		(net "ENET10G_3_RDN")
	)
	(segment
		(start 355.500178 -5.2324)
		(end 355.763576 -5.2324)
		(width 0.24384)
		(layer "F.Cu")
		(net "ENET10G_3_RDN")
	)
	(segment
		(start 355.994716 -5.136642)
		(end 356.090474 -5.040884)
		(width 0.24384)
		(layer "F.Cu")
		(net "ENET10G_3_RDN")
	)
	(segment
		(start 360.004106 -5.11556)
		(end 360.1212 -4.998466)
		(width 0.24384)
		(layer "F.Cu")
		(net "ENET10G_3_RDN")
	)
	(segment
		(start 360.990388 -5.354066)
		(end 360.990388 -5.789422)
		(width 0.24384)
		(layer "F.Cu")
		(net "ENET10G_3_RDN")
	)
	(segment
		(start 353.918266 -5.22732)
		(end 354.104702 -5.040884)
		(width 0.24384)
		(layer "F.Cu")
		(net "ENET10G_3_RDN")
	)
	(segment
		(start 360.990388 -7.3406)
		(end 360.990388 -8.852662)
		(width 0.24384)
		(layer "F.Cu")
		(net "ENET10G_3_RDN")
	)
	(segment
		(start 360.809032 -7.159244)
		(end 360.990388 -7.3406)
		(width 0.24384)
		(layer "F.Cu")
		(net "ENET10G_3_RDN")
	)
	(segment
		(start 360.660188 -6.5405)
		(end 360.660188 -6.800088)
		(width 0.24384)
		(layer "F.Cu")
		(net "ENET10G_3_RDN")
	)
	(segment
		(start 359.513378 -5.2324)
		(end 359.721912 -5.2324)
		(width 0.24384)
		(layer "F.Cu")
		(net "ENET10G_3_RDN")
	)
	(segment
		(start 357.038402 -5.040884)
		(end 357.081074 -5.083556)
		(width 0.24384)
		(layer "F.Cu")
		(net "ENET10G_3_RDN")
	)
	(segment
		(start 359.11155 -5.040884)
		(end 359.154222 -5.083556)
		(width 0.24384)
		(layer "F.Cu")
		(net "ENET10G_3_RDN")
	)
	(segment
		(start 360.841544 -6.148832)
		(end 360.809286 -6.18109)
		(width 0.24384)
		(layer "F.Cu")
		(net "ENET10G_3_RDN")
	)
	(segment
		(start 355.09835 -5.040884)
		(end 355.141022 -5.083556)
		(width 0.24384)
		(layer "F.Cu")
		(net "ENET10G_3_RDN")
	)
	(segment
		(start 360.700828 -4.963414)
		(end 360.919014 -5.1816)
		(width 0.24384)
		(layer "F.Cu")
		(net "ENET10G_3_RDN")
	)
	(segment
		(start 357.44023 -5.2324)
		(end 357.684324 -5.2324)
		(width 0.24384)
		(layer "F.Cu")
		(net "ENET10G_3_RDN")
	)
	(segment
		(start 354.463858 -4.89204)
		(end 354.739194 -4.89204)
		(width 0.24384)
		(layer "F.Cu")
		(net "ENET10G_3_RDN")
	)
	(segment
		(start 356.44963 -4.89204)
		(end 356.679246 -4.89204)
		(width 0.24384)
		(layer "F.Cu")
		(net "ENET10G_3_RDN")
	)
	(segment
		(start 357.915464 -5.136642)
		(end 358.011222 -5.040884)
		(width 0.24384)
		(layer "F.Cu")
		(net "ENET10G_3_RDN")
	)
	(segment
		(start 360.990388 -8.852662)
		(end 360.890058 -8.952992)
		(width 0.24384)
		(layer "F.Cu")
		(net "ENET10G_3_RDN")
	)
	(segment
		(start 360.890312 -8.953246)
		(end 360.890312 -10.289794)
		(width 0.24384)
		(layer "F.Cu")
		(net "ENET10G_3_RDN")
	)
	(segment
		(start 360.377994 -4.89204)
		(end 360.528362 -4.89204)
		(width 0.24384)
		(layer "F.Cu")
		(net "ENET10G_3_RDN")
	)
	(segment
		(start 360.890058 -8.952992)
		(end 360.890312 -8.953246)
		(width 0.24384)
		(layer "F.Cu")
		(net "ENET10G_3_RDN")
	)
	(via
		(at 353.918266 -5.22732)
		(size 0.508)
		(drill 0.254)
		(layers "F.Cu" "B.Cu")
		(net "ENET10G_3_RDN")
	)
	(arc
		(start 354.104702 -5.040884)
		(mid 354.26947 -4.930726)
		(end 354.463858 -4.89204)
		(width 0.24384)
		(layer "F.Cu")
		(net "ENET10G_3_RDN")
	)
	(arc
		(start 359.154222 -5.083556)
		(mid 359.31899 -5.193714)
		(end 359.513378 -5.2324)
		(width 0.24384)
		(layer "F.Cu")
		(net "ENET10G_3_RDN")
	)
	(arc
		(start 360.528362 -4.89204)
		(mid 360.62169 -4.910586)
		(end 360.700828 -4.963414)
		(width 0.24384)
		(layer "F.Cu")
		(net "ENET10G_3_RDN")
	)
	(arc
		(start 356.090474 -5.040884)
		(mid 356.255242 -4.930726)
		(end 356.44963 -4.89204)
		(width 0.24384)
		(layer "F.Cu")
		(net "ENET10G_3_RDN")
	)
	(arc
		(start 358.011222 -5.040884)
		(mid 358.17599 -4.930726)
		(end 358.370378 -4.89204)
		(width 0.24384)
		(layer "F.Cu")
		(net "ENET10G_3_RDN")
	)
	(arc
		(start 356.679246 -4.89204)
		(mid 356.873635 -4.930724)
		(end 357.038402 -5.040884)
		(width 0.24384)
		(layer "F.Cu")
		(net "ENET10G_3_RDN")
	)
	(arc
		(start 359.721912 -5.2324)
		(mid 359.87463 -5.20204)
		(end 360.004106 -5.11556)
		(width 0.24384)
		(layer "F.Cu")
		(net "ENET10G_3_RDN")
	)
	(arc
		(start 360.809286 -6.18109)
		(mid 360.698943 -6.345946)
		(end 360.660188 -6.5405)
		(width 0.24384)
		(layer "F.Cu")
		(net "ENET10G_3_RDN")
	)
	(arc
		(start 354.739194 -4.89204)
		(mid 354.933583 -4.930724)
		(end 355.09835 -5.040884)
		(width 0.24384)
		(layer "F.Cu")
		(net "ENET10G_3_RDN")
	)
	(arc
		(start 355.141022 -5.083556)
		(mid 355.30579 -5.193714)
		(end 355.500178 -5.2324)
		(width 0.24384)
		(layer "F.Cu")
		(net "ENET10G_3_RDN")
	)
	(arc
		(start 357.684324 -5.2324)
		(mid 357.809422 -5.207516)
		(end 357.915464 -5.136642)
		(width 0.24384)
		(layer "F.Cu")
		(net "ENET10G_3_RDN")
	)
	(arc
		(start 360.919014 -5.1816)
		(mid 360.971832 -5.260742)
		(end 360.990388 -5.354066)
		(width 0.24384)
		(layer "F.Cu")
		(net "ENET10G_3_RDN")
	)
	(arc
		(start 355.763576 -5.2324)
		(mid 355.888674 -5.207516)
		(end 355.994716 -5.136642)
		(width 0.24384)
		(layer "F.Cu")
		(net "ENET10G_3_RDN")
	)
	(arc
		(start 360.1212 -4.998466)
		(mid 360.239004 -4.919689)
		(end 360.377994 -4.89204)
		(width 0.24384)
		(layer "F.Cu")
		(net "ENET10G_3_RDN")
	)
	(arc
		(start 360.990388 -5.789422)
		(mid 360.951767 -5.983962)
		(end 360.841544 -6.148832)
		(width 0.24384)
		(layer "F.Cu")
		(net "ENET10G_3_RDN")
	)
	(arc
		(start 357.081074 -5.083556)
		(mid 357.245842 -5.193714)
		(end 357.44023 -5.2324)
		(width 0.24384)
		(layer "F.Cu")
		(net "ENET10G_3_RDN")
	)
	(arc
		(start 358.752394 -4.89204)
		(mid 358.946783 -4.930724)
		(end 359.11155 -5.040884)
		(width 0.24384)
		(layer "F.Cu")
		(net "ENET10G_3_RDN")
	)
	(arc
		(start 360.660188 -6.800088)
		(mid 360.698872 -6.994477)
		(end 360.809032 -7.159244)
		(width 0.24384)
		(layer "F.Cu")
		(net "ENET10G_3_RDN")
	)
	(segment
		(start 349.930466 -7.299706)
		(end 349.530162 -7.70001)
		(width 0.24384)
		(layer "B.Cu")
		(net "ENET10G_3_RDN")
	)
	(segment
		(start 353.372674 -4.89204)
		(end 353.097338 -4.89204)
		(width 0.24384)
		(layer "B.Cu")
		(net "ENET10G_3_RDN")
	)
	(segment
		(start 351.81286 -5.082794)
		(end 351.724214 -4.994148)
		(width 0.24384)
		(layer "B.Cu")
		(net "ENET10G_3_RDN")
	)
	(segment
		(start 352.346514 -5.22224)
		(end 352.14941 -5.22224)
		(width 0.24384)
		(layer "B.Cu")
		(net "ENET10G_3_RDN")
	)
	(segment
		(start 352.738182 -5.040884)
		(end 352.70567 -5.073396)
		(width 0.24384)
		(layer "B.Cu")
		(net "ENET10G_3_RDN")
	)
	(segment
		(start 350.332294 -7.299706)
		(end 349.930466 -7.299706)
		(width 0.24384)
		(layer "B.Cu")
		(net "ENET10G_3_RDN")
	)
	(segment
		(start 351.139506 -5.230368)
		(end 351.139506 -6.492494)
		(width 0.24384)
		(layer "B.Cu")
		(net "ENET10G_3_RDN")
	)
	(segment
		(start 353.918266 -5.22732)
		(end 353.73183 -5.040884)
		(width 0.24384)
		(layer "B.Cu")
		(net "ENET10G_3_RDN")
	)
	(arc
		(start 351.238566 -4.9911)
		(mid 351.165269 -5.100891)
		(end 351.139506 -5.230368)
		(width 0.24384)
		(layer "B.Cu")
		(net "ENET10G_3_RDN")
	)
	(arc
		(start 353.73183 -5.040884)
		(mid 353.567062 -4.930726)
		(end 353.372674 -4.89204)
		(width 0.24384)
		(layer "B.Cu")
		(net "ENET10G_3_RDN")
	)
	(arc
		(start 352.70567 -5.073396)
		(mid 352.540902 -5.183554)
		(end 352.346514 -5.22224)
		(width 0.24384)
		(layer "B.Cu")
		(net "ENET10G_3_RDN")
	)
	(arc
		(start 351.724214 -4.994148)
		(mid 351.611188 -4.918563)
		(end 351.477834 -4.89204)
		(width 0.24384)
		(layer "B.Cu")
		(net "ENET10G_3_RDN")
	)
	(arc
		(start 352.14941 -5.22224)
		(mid 351.967268 -5.185992)
		(end 351.81286 -5.082794)
		(width 0.24384)
		(layer "B.Cu")
		(net "ENET10G_3_RDN")
	)
	(arc
		(start 351.477834 -4.89204)
		(mid 351.348347 -4.917779)
		(end 351.238566 -4.9911)
		(width 0.24384)
		(layer "B.Cu")
		(net "ENET10G_3_RDN")
	)
	(arc
		(start 350.903794 -7.062978)
		(mid 350.641615 -7.238257)
		(end 350.332294 -7.299706)
		(width 0.24384)
		(layer "B.Cu")
		(net "ENET10G_3_RDN")
	)
	(arc
		(start 351.139506 -6.492494)
		(mid 351.078296 -6.801137)
		(end 350.903794 -7.062978)
		(width 0.24384)
		(layer "B.Cu")
		(net "ENET10G_3_RDN")
	)
	(arc
		(start 353.097338 -4.89204)
		(mid 352.902949 -4.930724)
		(end 352.738182 -5.040884)
		(width 0.24384)
		(layer "B.Cu")
		(net "ENET10G_3_RDN")
	)
	(segment
		(start 414.295082 -24.986996)
		(end 414.070038 -24.761952)
		(width 0.1778)
		(layer "F.Cu")
		(net "SAS_BLAD2_TX2_P")
	)
	(segment
		(start 414.295082 -25.899872)
		(end 414.295082 -24.986996)
		(width 0.1778)
		(layer "F.Cu")
		(net "SAS_BLAD2_TX2_P")
	)
	(segment
		(start 414.070038 -24.761952)
		(end 414.070038 -18.97634)
		(width 0.1778)
		(layer "F.Cu")
		(net "SAS_BLAD2_TX2_P")
	)
	(segment
		(start 414.070038 -18.97634)
		(end 414.529778 -18.5166)
		(width 0.1778)
		(layer "F.Cu")
		(net "SAS_BLAD2_TX2_P")
	)
	(via
		(at 414.529778 -18.5166)
		(size 0.508)
		(drill 0.254)
		(layers "F.Cu" "B.Cu")
		(net "SAS_BLAD2_TX2_P")
	)
	(segment
		(start 403.195536 -10.8204)
		(end 402.738336 -10.8204)
		(width 0.1524)
		(layer "In5.Cu")
		(net "SAS_BLAD2_TX2_P")
	)
	(segment
		(start 401.295108 -10.99693)
		(end 400.837908 -10.99693)
		(width 0.1524)
		(layer "In5.Cu")
		(net "SAS_BLAD2_TX2_P")
	)
	(segment
		(start 414.529778 -18.5166)
		(end 414.098232 -18.085054)
		(width 0.1524)
		(layer "In5.Cu")
		(net "SAS_BLAD2_TX2_P")
	)
	(segment
		(start 400.661632 -10.8204)
		(end 400.204432 -10.8204)
		(width 0.1524)
		(layer "In5.Cu")
		(net "SAS_BLAD2_TX2_P")
	)
	(segment
		(start 400.204432 -10.8204)
		(end 400.028156 -10.99693)
		(width 0.1524)
		(layer "In5.Cu")
		(net "SAS_BLAD2_TX2_P")
	)
	(segment
		(start 402.56206 -10.99693)
		(end 402.10486 -10.99693)
		(width 0.1524)
		(layer "In5.Cu")
		(net "SAS_BLAD2_TX2_P")
	)
	(segment
		(start 414.098232 -18.085054)
		(end 414.098232 -17.616678)
		(width 0.1524)
		(layer "In5.Cu")
		(net "SAS_BLAD2_TX2_P")
	)
	(segment
		(start 403.371812 -10.99693)
		(end 403.195536 -10.8204)
		(width 0.1524)
		(layer "In5.Cu")
		(net "SAS_BLAD2_TX2_P")
	)
	(segment
		(start 400.028156 -10.99693)
		(end 396.386812 -10.99693)
		(width 0.1524)
		(layer "In5.Cu")
		(net "SAS_BLAD2_TX2_P")
	)
	(segment
		(start 407.478484 -10.99693)
		(end 403.371812 -10.99693)
		(width 0.1524)
		(layer "In5.Cu")
		(net "SAS_BLAD2_TX2_P")
	)
	(segment
		(start 400.837908 -10.99693)
		(end 400.661632 -10.8204)
		(width 0.1524)
		(layer "In5.Cu")
		(net "SAS_BLAD2_TX2_P")
	)
	(segment
		(start 413.830516 -16.969994)
		(end 408.125168 -11.2649)
		(width 0.1524)
		(layer "In5.Cu")
		(net "SAS_BLAD2_TX2_P")
	)
	(segment
		(start 401.928584 -10.8204)
		(end 401.471384 -10.8204)
		(width 0.1524)
		(layer "In5.Cu")
		(net "SAS_BLAD2_TX2_P")
	)
	(segment
		(start 401.471384 -10.8204)
		(end 401.295108 -10.99693)
		(width 0.1524)
		(layer "In5.Cu")
		(net "SAS_BLAD2_TX2_P")
	)
	(segment
		(start 396.386812 -10.99693)
		(end 395.889988 -10.500106)
		(width 0.1524)
		(layer "In5.Cu")
		(net "SAS_BLAD2_TX2_P")
	)
	(segment
		(start 402.738336 -10.8204)
		(end 402.56206 -10.99693)
		(width 0.1524)
		(layer "In5.Cu")
		(net "SAS_BLAD2_TX2_P")
	)
	(segment
		(start 402.10486 -10.99693)
		(end 401.928584 -10.8204)
		(width 0.1524)
		(layer "In5.Cu")
		(net "SAS_BLAD2_TX2_P")
	)
	(arc
		(start 408.125168 -11.2649)
		(mid 407.828481 -11.066597)
		(end 407.478484 -10.99693)
		(width 0.1524)
		(layer "In5.Cu")
		(net "SAS_BLAD2_TX2_P")
	)
	(arc
		(start 414.098232 -17.616678)
		(mid 414.028695 -17.266713)
		(end 413.830516 -16.969994)
		(width 0.1524)
		(layer "In5.Cu")
		(net "SAS_BLAD2_TX2_P")
	)
	(segment
		(start 339.530182 -4.467352)
		(end 339.530182 -4.800092)
		(width 0.1524)
		(layer "In2.Cu")
		(net "ENET1G_4_MDI3N")
	)
	(segment
		(start 339.694266 -4.303268)
		(end 339.530182 -4.467352)
		(width 0.1524)
		(layer "In2.Cu")
		(net "ENET1G_4_MDI3N")
	)
	(segment
		(start 338.652866 -31.9532)
		(end 338.652866 -27.589734)
		(width 0.1524)
		(layer "In2.Cu")
		(net "ENET1G_4_MDI3N")
	)
	(segment
		(start 340.331806 -4.641342)
		(end 339.993732 -4.303268)
		(width 0.1524)
		(layer "In2.Cu")
		(net "ENET1G_4_MDI3N")
	)
	(segment
		(start 347.898466 -32.7914)
		(end 346.679266 -34.0106)
		(width 0.1524)
		(layer "In2.Cu")
		(net "ENET1G_4_MDI3N")
	)
	(segment
		(start 348.299532 -30.8991)
		(end 348.163134 -30.967172)
		(width 0.1524)
		(layer "In2.Cu")
		(net "ENET1G_4_MDI3N")
	)
	(segment
		(start 340.331806 -19.698208)
		(end 340.331806 -4.641342)
		(width 0.1524)
		(layer "In2.Cu")
		(net "ENET1G_4_MDI3N")
	)
	(segment
		(start 347.898466 -31.23184)
		(end 347.898466 -32.7914)
		(width 0.1524)
		(layer "In2.Cu")
		(net "ENET1G_4_MDI3N")
	)
	(segment
		(start 348.163134 -30.967172)
		(end 347.898466 -31.23184)
		(width 0.1524)
		(layer "In2.Cu")
		(net "ENET1G_4_MDI3N")
	)
	(segment
		(start 341.6046 -20.971002)
		(end 340.331806 -19.698208)
		(width 0.1524)
		(layer "In2.Cu")
		(net "ENET1G_4_MDI3N")
	)
	(segment
		(start 348.504002 -30.966918)
		(end 348.299532 -30.8991)
		(width 0.1524)
		(layer "In2.Cu")
		(net "ENET1G_4_MDI3N")
	)
	(segment
		(start 346.679266 -34.0106)
		(end 340.710266 -34.0106)
		(width 0.1524)
		(layer "In2.Cu")
		(net "ENET1G_4_MDI3N")
	)
	(segment
		(start 339.993732 -4.303268)
		(end 339.694266 -4.303268)
		(width 0.1524)
		(layer "In2.Cu")
		(net "ENET1G_4_MDI3N")
	)
	(segment
		(start 348.980252 -31.919164)
		(end 348.504002 -30.966918)
		(width 0.1524)
		(layer "In2.Cu")
		(net "ENET1G_4_MDI3N")
	)
	(segment
		(start 341.6046 -24.638)
		(end 341.6046 -20.971002)
		(width 0.1524)
		(layer "In2.Cu")
		(net "ENET1G_4_MDI3N")
	)
	(segment
		(start 340.710266 -34.0106)
		(end 338.652866 -31.9532)
		(width 0.1524)
		(layer "In2.Cu")
		(net "ENET1G_4_MDI3N")
	)
	(segment
		(start 338.652866 -27.589734)
		(end 341.6046 -24.638)
		(width 0.1524)
		(layer "In2.Cu")
		(net "ENET1G_4_MDI3N")
	)
	(segment
		(start 323.76999 -8.952738)
		(end 323.76999 -10.290048)
		(width 0.24384)
		(layer "F.Cu")
		(net "ENET10G_4_RDP")
	)
	(segment
		(start 323.66966 -8.852408)
		(end 323.76999 -8.952738)
		(width 0.24384)
		(layer "F.Cu")
		(net "ENET10G_4_RDP")
	)
	(segment
		(start 323.66966 -5.91312)
		(end 323.66966 -8.852408)
		(width 0.24384)
		(layer "F.Cu")
		(net "ENET10G_4_RDP")
	)
	(segment
		(start 324.00494 -5.57784)
		(end 323.66966 -5.91312)
		(width 0.24384)
		(layer "F.Cu")
		(net "ENET10G_4_RDP")
	)
	(via
		(at 324.00494 -5.57784)
		(size 0.508)
		(drill 0.254)
		(layers "F.Cu" "B.Cu")
		(net "ENET10G_4_RDP")
	)
	(segment
		(start 338.583016 -8.000238)
		(end 339.130132 -8.000238)
		(width 0.24384)
		(layer "B.Cu")
		(net "ENET10G_4_RDP")
	)
	(segment
		(start 339.130132 -8.000238)
		(end 339.530182 -7.600188)
		(width 0.24384)
		(layer "B.Cu")
		(net "ENET10G_4_RDP")
	)
	(segment
		(start 328.254614 -6.1976)
		(end 328.67473 -6.1976)
		(width 0.24384)
		(layer "B.Cu")
		(net "ENET10G_4_RDP")
	)
	(segment
		(start 323.59346 -5.98932)
		(end 323.59346 -6.44525)
		(width 0.24384)
		(layer "B.Cu")
		(net "ENET10G_4_RDP")
	)
	(segment
		(start 334.11795 -6.363716)
		(end 334.201008 -6.280658)
		(width 0.24384)
		(layer "B.Cu")
		(net "ENET10G_4_RDP")
	)
	(segment
		(start 323.664834 -6.617716)
		(end 323.843904 -6.796786)
		(width 0.24384)
		(layer "B.Cu")
		(net "ENET10G_4_RDP")
	)
	(segment
		(start 333.118206 -6.346444)
		(end 333.135478 -6.363716)
		(width 0.24384)
		(layer "B.Cu")
		(net "ENET10G_4_RDP")
	)
	(segment
		(start 329.95235 -6.363716)
		(end 330.035408 -6.280658)
		(width 0.24384)
		(layer "B.Cu")
		(net "ENET10G_4_RDP")
	)
	(segment
		(start 329.033886 -6.346444)
		(end 329.051158 -6.363716)
		(width 0.24384)
		(layer "B.Cu")
		(net "ENET10G_4_RDP")
	)
	(segment
		(start 325.324978 -6.51256)
		(end 325.605394 -6.51256)
		(width 0.24384)
		(layer "B.Cu")
		(net "ENET10G_4_RDP")
	)
	(segment
		(start 330.235814 -6.1976)
		(end 330.71689 -6.1976)
		(width 0.24384)
		(layer "B.Cu")
		(net "ENET10G_4_RDP")
	)
	(segment
		(start 335.19491 -6.346444)
		(end 335.212182 -6.363716)
		(width 0.24384)
		(layer "B.Cu")
		(net "ENET10G_4_RDP")
	)
	(segment
		(start 327.97115 -6.363716)
		(end 328.054208 -6.280658)
		(width 0.24384)
		(layer "B.Cu")
		(net "ENET10G_4_RDP")
	)
	(segment
		(start 329.410314 -6.51256)
		(end 329.593194 -6.51256)
		(width 0.24384)
		(layer "B.Cu")
		(net "ENET10G_4_RDP")
	)
	(segment
		(start 324.01637 -6.86816)
		(end 324.510654 -6.86816)
		(width 0.24384)
		(layer "B.Cu")
		(net "ENET10G_4_RDP")
	)
	(segment
		(start 326.204834 -6.223)
		(end 326.6694 -6.223)
		(width 0.24384)
		(layer "B.Cu")
		(net "ENET10G_4_RDP")
	)
	(segment
		(start 335.571338 -6.51256)
		(end 336.674714 -6.51256)
		(width 0.24384)
		(layer "B.Cu")
		(net "ENET10G_4_RDP")
	)
	(segment
		(start 331.452474 -6.51256)
		(end 331.701394 -6.51256)
		(width 0.24384)
		(layer "B.Cu")
		(net "ENET10G_4_RDP")
	)
	(segment
		(start 332.06055 -6.363716)
		(end 332.143608 -6.280658)
		(width 0.24384)
		(layer "B.Cu")
		(net "ENET10G_4_RDP")
	)
	(segment
		(start 327.368154 -6.51256)
		(end 327.611994 -6.51256)
		(width 0.24384)
		(layer "B.Cu")
		(net "ENET10G_4_RDP")
	)
	(segment
		(start 333.494634 -6.51256)
		(end 333.758794 -6.51256)
		(width 0.24384)
		(layer "B.Cu")
		(net "ENET10G_4_RDP")
	)
	(segment
		(start 325.96455 -6.363716)
		(end 326.034908 -6.293358)
		(width 0.24384)
		(layer "B.Cu")
		(net "ENET10G_4_RDP")
	)
	(segment
		(start 332.344014 -6.1976)
		(end 332.75905 -6.1976)
		(width 0.24384)
		(layer "B.Cu")
		(net "ENET10G_4_RDP")
	)
	(segment
		(start 334.401414 -6.1976)
		(end 334.835754 -6.1976)
		(width 0.24384)
		(layer "B.Cu")
		(net "ENET10G_4_RDP")
	)
	(segment
		(start 337.03387 -6.661404)
		(end 338.22386 -7.851394)
		(width 0.24384)
		(layer "B.Cu")
		(net "ENET10G_4_RDP")
	)
	(segment
		(start 324.00494 -5.57784)
		(end 323.59346 -5.98932)
		(width 0.24384)
		(layer "B.Cu")
		(net "ENET10G_4_RDP")
	)
	(segment
		(start 331.076046 -6.346444)
		(end 331.093318 -6.363716)
		(width 0.24384)
		(layer "B.Cu")
		(net "ENET10G_4_RDP")
	)
	(segment
		(start 324.510654 -6.86816)
		(end 324.541896 -6.836918)
		(width 0.24384)
		(layer "B.Cu")
		(net "ENET10G_4_RDP")
	)
	(arc
		(start 334.835754 -6.1976)
		(mid 335.030143 -6.236284)
		(end 335.19491 -6.346444)
		(width 0.24384)
		(layer "B.Cu")
		(net "ENET10G_4_RDP")
	)
	(arc
		(start 326.6694 -6.223)
		(mid 326.853194 -6.259577)
		(end 327.008998 -6.363716)
		(width 0.24384)
		(layer "B.Cu")
		(net "ENET10G_4_RDP")
	)
	(arc
		(start 334.201008 -6.280658)
		(mid 334.292941 -6.219167)
		(end 334.401414 -6.1976)
		(width 0.24384)
		(layer "B.Cu")
		(net "ENET10G_4_RDP")
	)
	(arc
		(start 330.71689 -6.1976)
		(mid 330.911279 -6.236284)
		(end 331.076046 -6.346444)
		(width 0.24384)
		(layer "B.Cu")
		(net "ENET10G_4_RDP")
	)
	(arc
		(start 331.093318 -6.363716)
		(mid 331.258086 -6.473874)
		(end 331.452474 -6.51256)
		(width 0.24384)
		(layer "B.Cu")
		(net "ENET10G_4_RDP")
	)
	(arc
		(start 333.135478 -6.363716)
		(mid 333.300246 -6.473874)
		(end 333.494634 -6.51256)
		(width 0.24384)
		(layer "B.Cu")
		(net "ENET10G_4_RDP")
	)
	(arc
		(start 333.758794 -6.51256)
		(mid 333.953183 -6.473876)
		(end 334.11795 -6.363716)
		(width 0.24384)
		(layer "B.Cu")
		(net "ENET10G_4_RDP")
	)
	(arc
		(start 325.605394 -6.51256)
		(mid 325.799783 -6.473876)
		(end 325.96455 -6.363716)
		(width 0.24384)
		(layer "B.Cu")
		(net "ENET10G_4_RDP")
	)
	(arc
		(start 332.75905 -6.1976)
		(mid 332.953439 -6.236284)
		(end 333.118206 -6.346444)
		(width 0.24384)
		(layer "B.Cu")
		(net "ENET10G_4_RDP")
	)
	(arc
		(start 336.674714 -6.51256)
		(mid 336.869103 -6.551244)
		(end 337.03387 -6.661404)
		(width 0.24384)
		(layer "B.Cu")
		(net "ENET10G_4_RDP")
	)
	(arc
		(start 335.212182 -6.363716)
		(mid 335.37695 -6.473874)
		(end 335.571338 -6.51256)
		(width 0.24384)
		(layer "B.Cu")
		(net "ENET10G_4_RDP")
	)
	(arc
		(start 329.593194 -6.51256)
		(mid 329.787583 -6.473876)
		(end 329.95235 -6.363716)
		(width 0.24384)
		(layer "B.Cu")
		(net "ENET10G_4_RDP")
	)
	(arc
		(start 327.611994 -6.51256)
		(mid 327.806383 -6.473876)
		(end 327.97115 -6.363716)
		(width 0.24384)
		(layer "B.Cu")
		(net "ENET10G_4_RDP")
	)
	(arc
		(start 324.541896 -6.836918)
		(mid 324.901177 -6.596854)
		(end 325.324978 -6.51256)
		(width 0.24384)
		(layer "B.Cu")
		(net "ENET10G_4_RDP")
	)
	(arc
		(start 332.143608 -6.280658)
		(mid 332.235541 -6.219167)
		(end 332.344014 -6.1976)
		(width 0.24384)
		(layer "B.Cu")
		(net "ENET10G_4_RDP")
	)
	(arc
		(start 328.67473 -6.1976)
		(mid 328.869119 -6.236284)
		(end 329.033886 -6.346444)
		(width 0.24384)
		(layer "B.Cu")
		(net "ENET10G_4_RDP")
	)
	(arc
		(start 328.054208 -6.280658)
		(mid 328.146141 -6.219167)
		(end 328.254614 -6.1976)
		(width 0.24384)
		(layer "B.Cu")
		(net "ENET10G_4_RDP")
	)
	(arc
		(start 323.843904 -6.796786)
		(mid 323.923046 -6.849604)
		(end 324.01637 -6.86816)
		(width 0.24384)
		(layer "B.Cu")
		(net "ENET10G_4_RDP")
	)
	(arc
		(start 323.59346 -6.44525)
		(mid 323.612006 -6.538578)
		(end 323.664834 -6.617716)
		(width 0.24384)
		(layer "B.Cu")
		(net "ENET10G_4_RDP")
	)
	(arc
		(start 327.008998 -6.363716)
		(mid 327.173766 -6.473874)
		(end 327.368154 -6.51256)
		(width 0.24384)
		(layer "B.Cu")
		(net "ENET10G_4_RDP")
	)
	(arc
		(start 330.035408 -6.280658)
		(mid 330.127341 -6.219167)
		(end 330.235814 -6.1976)
		(width 0.24384)
		(layer "B.Cu")
		(net "ENET10G_4_RDP")
	)
	(arc
		(start 331.701394 -6.51256)
		(mid 331.895783 -6.473876)
		(end 332.06055 -6.363716)
		(width 0.24384)
		(layer "B.Cu")
		(net "ENET10G_4_RDP")
	)
	(arc
		(start 326.034908 -6.293358)
		(mid 326.112871 -6.241265)
		(end 326.204834 -6.223)
		(width 0.24384)
		(layer "B.Cu")
		(net "ENET10G_4_RDP")
	)
	(arc
		(start 329.051158 -6.363716)
		(mid 329.215926 -6.473874)
		(end 329.410314 -6.51256)
		(width 0.24384)
		(layer "B.Cu")
		(net "ENET10G_4_RDP")
	)
	(arc
		(start 338.22386 -7.851394)
		(mid 338.388628 -7.961552)
		(end 338.583016 -8.000238)
		(width 0.24384)
		(layer "B.Cu")
		(net "ENET10G_4_RDP")
	)
	(segment
		(start 413.719518 -18.97634)
		(end 413.259778 -18.5166)
		(width 0.1778)
		(layer "F.Cu")
		(net "SAS_BLAD2_TX2_N")
	)
	(segment
		(start 413.494982 -25.899872)
		(end 413.494728 -25.899618)
		(width 0.1778)
		(layer "F.Cu")
		(net "SAS_BLAD2_TX2_N")
	)
	(segment
		(start 413.494728 -24.986742)
		(end 413.719518 -24.761952)
		(width 0.1778)
		(layer "F.Cu")
		(net "SAS_BLAD2_TX2_N")
	)
	(segment
		(start 413.494728 -25.899618)
		(end 413.494728 -24.986742)
		(width 0.1778)
		(layer "F.Cu")
		(net "SAS_BLAD2_TX2_N")
	)
	(segment
		(start 413.719518 -24.761952)
		(end 413.719518 -18.97634)
		(width 0.1778)
		(layer "F.Cu")
		(net "SAS_BLAD2_TX2_N")
	)
	(via
		(at 413.259778 -18.5166)
		(size 0.508)
		(drill 0.254)
		(layers "F.Cu" "B.Cu")
		(net "SAS_BLAD2_TX2_N")
	)
	(segment
		(start 407.478484 -11.40333)
		(end 396.386812 -11.40333)
		(width 0.1524)
		(layer "In5.Cu")
		(net "SAS_BLAD2_TX2_N")
	)
	(segment
		(start 413.691832 -18.084546)
		(end 413.691832 -17.616678)
		(width 0.1524)
		(layer "In5.Cu")
		(net "SAS_BLAD2_TX2_N")
	)
	(segment
		(start 413.542988 -17.257522)
		(end 407.83764 -11.552174)
		(width 0.1524)
		(layer "In5.Cu")
		(net "SAS_BLAD2_TX2_N")
	)
	(segment
		(start 396.386812 -11.40333)
		(end 395.889988 -11.900154)
		(width 0.1524)
		(layer "In5.Cu")
		(net "SAS_BLAD2_TX2_N")
	)
	(segment
		(start 413.259778 -18.5166)
		(end 413.691832 -18.084546)
		(width 0.1524)
		(layer "In5.Cu")
		(net "SAS_BLAD2_TX2_N")
	)
	(arc
		(start 413.691832 -17.616678)
		(mid 413.653148 -17.422289)
		(end 413.542988 -17.257522)
		(width 0.1524)
		(layer "In5.Cu")
		(net "SAS_BLAD2_TX2_N")
	)
	(arc
		(start 407.83764 -11.552174)
		(mid 407.672872 -11.442016)
		(end 407.478484 -11.40333)
		(width 0.1524)
		(layer "In5.Cu")
		(net "SAS_BLAD2_TX2_N")
	)
	(segment
		(start 410.694886 -28.4099)
		(end 410.694886 -29.501084)
		(width 0.1778)
		(layer "F.Cu")
		(net "SAS_BLAD2_RX3_N")
	)
	(segment
		(start 410.919422 -29.72562)
		(end 410.919422 -30.135068)
		(width 0.1778)
		(layer "F.Cu")
		(net "SAS_BLAD2_RX3_N")
	)
	(segment
		(start 410.694886 -29.501084)
		(end 410.919422 -29.72562)
		(width 0.1778)
		(layer "F.Cu")
		(net "SAS_BLAD2_RX3_N")
	)
	(segment
		(start 410.919422 -30.135068)
		(end 410.459682 -30.594808)
		(width 0.1778)
		(layer "F.Cu")
		(net "SAS_BLAD2_RX3_N")
	)
	(via
		(at 410.459682 -30.594808)
		(size 0.508)
		(drill 0.254)
		(layers "F.Cu" "B.Cu")
		(net "SAS_BLAD2_RX3_N")
	)
	(segment
		(start 408.576272 -26.75763)
		(end 406.414732 -24.82469)
		(width 0.1778)
		(layer "B.Cu")
		(net "SAS_BLAD2_RX3_N")
	)
	(segment
		(start 410.873448 -29.054044)
		(end 408.582876 -26.763726)
		(width 0.1778)
		(layer "B.Cu")
		(net "SAS_BLAD2_RX3_N")
	)
	(segment
		(start 394.669518 -4.41706)
		(end 394.574014 -4.321556)
		(width 0.1778)
		(layer "B.Cu")
		(net "SAS_BLAD2_RX3_N")
	)
	(segment
		(start 402.584666 -18.796254)
		(end 400.118072 -17.275556)
		(width 0.1778)
		(layer "B.Cu")
		(net "SAS_BLAD2_RX3_N")
	)
	(segment
		(start 394.715746 -13.383768)
		(end 394.715746 -4.528312)
		(width 0.1778)
		(layer "B.Cu")
		(net "SAS_BLAD2_RX3_N")
	)
	(segment
		(start 406.412954 -24.823166)
		(end 402.584666 -18.796254)
		(width 0.1778)
		(layer "B.Cu")
		(net "SAS_BLAD2_RX3_N")
	)
	(segment
		(start 400.118072 -17.275556)
		(end 400.112484 -17.271238)
		(width 0.1778)
		(layer "B.Cu")
		(net "SAS_BLAD2_RX3_N")
	)
	(segment
		(start 410.459682 -30.594808)
		(end 410.919676 -30.134814)
		(width 0.1778)
		(layer "B.Cu")
		(net "SAS_BLAD2_RX3_N")
	)
	(segment
		(start 400.109436 -17.268698)
		(end 396.742666 -14.5542)
		(width 0.1778)
		(layer "B.Cu")
		(net "SAS_BLAD2_RX3_N")
	)
	(segment
		(start 394.075666 -4.275328)
		(end 393.889992 -4.461002)
		(width 0.1778)
		(layer "B.Cu")
		(net "SAS_BLAD2_RX3_N")
	)
	(segment
		(start 396.742666 -14.5542)
		(end 395.657578 -14.3256)
		(width 0.1778)
		(layer "B.Cu")
		(net "SAS_BLAD2_RX3_N")
	)
	(segment
		(start 408.57678 -26.758138)
		(end 408.576272 -26.75763)
		(width 0.1778)
		(layer "B.Cu")
		(net "SAS_BLAD2_RX3_N")
	)
	(segment
		(start 406.414732 -24.82469)
		(end 406.412954 -24.823166)
		(width 0.1778)
		(layer "B.Cu")
		(net "SAS_BLAD2_RX3_N")
	)
	(segment
		(start 395.298168 -14.176502)
		(end 394.86459 -13.742924)
		(width 0.1778)
		(layer "B.Cu")
		(net "SAS_BLAD2_RX3_N")
	)
	(segment
		(start 393.889992 -4.461002)
		(end 393.889992 -4.800092)
		(width 0.1778)
		(layer "B.Cu")
		(net "SAS_BLAD2_RX3_N")
	)
	(segment
		(start 410.919676 -30.134814)
		(end 410.919676 -29.165296)
		(width 0.1778)
		(layer "B.Cu")
		(net "SAS_BLAD2_RX3_N")
	)
	(segment
		(start 394.462762 -4.275328)
		(end 394.075666 -4.275328)
		(width 0.1778)
		(layer "B.Cu")
		(net "SAS_BLAD2_RX3_N")
	)
	(arc
		(start 408.582876 -26.763726)
		(mid 408.579865 -26.760892)
		(end 408.57678 -26.758138)
		(width 0.1778)
		(layer "B.Cu")
		(net "SAS_BLAD2_RX3_N")
	)
	(arc
		(start 410.919676 -29.165296)
		(mid 410.907658 -29.10506)
		(end 410.873448 -29.054044)
		(width 0.1778)
		(layer "B.Cu")
		(net "SAS_BLAD2_RX3_N")
	)
	(arc
		(start 394.715746 -4.528312)
		(mid 394.703728 -4.468076)
		(end 394.669518 -4.41706)
		(width 0.1778)
		(layer "B.Cu")
		(net "SAS_BLAD2_RX3_N")
	)
	(arc
		(start 395.657578 -14.3256)
		(mid 395.463023 -14.286847)
		(end 395.298168 -14.176502)
		(width 0.1778)
		(layer "B.Cu")
		(net "SAS_BLAD2_RX3_N")
	)
	(arc
		(start 394.574014 -4.321556)
		(mid 394.523 -4.287343)
		(end 394.462762 -4.275328)
		(width 0.1778)
		(layer "B.Cu")
		(net "SAS_BLAD2_RX3_N")
	)
	(arc
		(start 400.112484 -17.271238)
		(mid 400.110954 -17.269976)
		(end 400.109436 -17.268698)
		(width 0.1778)
		(layer "B.Cu")
		(net "SAS_BLAD2_RX3_N")
	)
	(arc
		(start 394.86459 -13.742924)
		(mid 394.754432 -13.578156)
		(end 394.715746 -13.383768)
		(width 0.1778)
		(layer "B.Cu")
		(net "SAS_BLAD2_RX3_N")
	)
	(segment
		(start 124.648976 -37.301932)
		(end 125.349 -36.601908)
		(width 0.14732)
		(layer "B.Cu")
		(net "ENET1G_1_MDI2P")
	)
	(segment
		(start 129.159 -29.819092)
		(end 127.508 -28.168092)
		(width 0.14732)
		(layer "B.Cu")
		(net "ENET1G_1_MDI2P")
	)
	(segment
		(start 126.111 -14.934692)
		(end 125.383036 -14.206728)
		(width 0.14732)
		(layer "B.Cu")
		(net "ENET1G_1_MDI2P")
	)
	(segment
		(start 125.383036 -4.273296)
		(end 125.708664 -3.947668)
		(width 0.14732)
		(layer "B.Cu")
		(net "ENET1G_1_MDI2P")
	)
	(segment
		(start 124.170186 -35.9791)
		(end 123.669298 -36.980876)
		(width 0.14732)
		(layer "B.Cu")
		(net "ENET1G_1_MDI2P")
	)
	(segment
		(start 123.867164 -37.244274)
		(end 123.91136 -37.266372)
		(width 0.14732)
		(layer "B.Cu")
		(net "ENET1G_1_MDI2P")
	)
	(segment
		(start 129.159 -32.385)
		(end 129.159 -29.819092)
		(width 0.14732)
		(layer "B.Cu")
		(net "ENET1G_1_MDI2P")
	)
	(segment
		(start 125.708664 -3.947668)
		(end 126.328932 -3.947668)
		(width 0.14732)
		(layer "B.Cu")
		(net "ENET1G_1_MDI2P")
	)
	(segment
		(start 125.349 -36.601908)
		(end 125.349 -35.255708)
		(width 0.14732)
		(layer "B.Cu")
		(net "ENET1G_1_MDI2P")
	)
	(segment
		(start 123.91136 -37.266372)
		(end 123.94692 -37.301932)
		(width 0.14732)
		(layer "B.Cu")
		(net "ENET1G_1_MDI2P")
	)
	(segment
		(start 123.669298 -36.980876)
		(end 123.735338 -37.178488)
		(width 0.14732)
		(layer "B.Cu")
		(net "ENET1G_1_MDI2P")
	)
	(segment
		(start 123.94692 -37.301932)
		(end 124.648976 -37.301932)
		(width 0.14732)
		(layer "B.Cu")
		(net "ENET1G_1_MDI2P")
	)
	(segment
		(start 123.735338 -37.178488)
		(end 123.867164 -37.244274)
		(width 0.14732)
		(layer "B.Cu")
		(net "ENET1G_1_MDI2P")
	)
	(segment
		(start 127.508 -28.168092)
		(end 127.508 -25.120092)
		(width 0.14732)
		(layer "B.Cu")
		(net "ENET1G_1_MDI2P")
	)
	(segment
		(start 126.111 -23.723092)
		(end 126.111 -14.934692)
		(width 0.14732)
		(layer "B.Cu")
		(net "ENET1G_1_MDI2P")
	)
	(segment
		(start 127.508 -25.120092)
		(end 126.111 -23.723092)
		(width 0.14732)
		(layer "B.Cu")
		(net "ENET1G_1_MDI2P")
	)
	(segment
		(start 126.975108 -33.6296)
		(end 127.9144 -33.6296)
		(width 0.14732)
		(layer "B.Cu")
		(net "ENET1G_1_MDI2P")
	)
	(segment
		(start 126.328932 -3.947668)
		(end 126.5301 -3.7465)
		(width 0.14732)
		(layer "B.Cu")
		(net "ENET1G_1_MDI2P")
	)
	(segment
		(start 126.5301 -3.7465)
		(end 126.5301 -3.400044)
		(width 0.14732)
		(layer "B.Cu")
		(net "ENET1G_1_MDI2P")
	)
	(segment
		(start 125.349 -35.255708)
		(end 126.975108 -33.6296)
		(width 0.14732)
		(layer "B.Cu")
		(net "ENET1G_1_MDI2P")
	)
	(segment
		(start 125.383036 -14.206728)
		(end 125.383036 -4.273296)
		(width 0.14732)
		(layer "B.Cu")
		(net "ENET1G_1_MDI2P")
	)
	(segment
		(start 127.9144 -33.6296)
		(end 129.159 -32.385)
		(width 0.14732)
		(layer "B.Cu")
		(net "ENET1G_1_MDI2P")
	)
	(segment
		(start 366.7252 -5.715)
		(end 366.38992 -6.05028)
		(width 0.24384)
		(layer "F.Cu")
		(net "ENET10G_3_TDN")
	)
	(segment
		(start 366.38992 -8.852662)
		(end 366.49025 -8.952992)
		(width 0.24384)
		(layer "F.Cu")
		(net "ENET10G_3_TDN")
	)
	(segment
		(start 366.49025 -8.952992)
		(end 366.49025 -10.289794)
		(width 0.24384)
		(layer "F.Cu")
		(net "ENET10G_3_TDN")
	)
	(segment
		(start 366.38992 -6.05028)
		(end 366.38992 -8.852662)
		(width 0.24384)
		(layer "F.Cu")
		(net "ENET10G_3_TDN")
	)
	(via
		(at 366.7252 -5.715)
		(size 0.508)
		(drill 0.254)
		(layers "F.Cu" "B.Cu")
		(net "ENET10G_3_TDN")
	)
	(segment
		(start 349.930466 -11.49985)
		(end 349.530162 -11.900154)
		(width 0.24384)
		(layer "B.Cu")
		(net "ENET10G_3_TDN")
	)
	(segment
		(start 365.620554 -7.493)
		(end 364.984538 -7.493)
		(width 0.24384)
		(layer "B.Cu")
		(net "ENET10G_3_TDN")
	)
	(segment
		(start 363.401102 -6.5786)
		(end 356.625144 -6.5786)
		(width 0.24384)
		(layer "B.Cu")
		(net "ENET10G_3_TDN")
	)
	(segment
		(start 366.38992 -6.05028)
		(end 366.38992 -6.723634)
		(width 0.24384)
		(layer "B.Cu")
		(net "ENET10G_3_TDN")
	)
	(segment
		(start 351.144078 -11.49985)
		(end 349.930466 -11.49985)
		(width 0.24384)
		(layer "B.Cu")
		(net "ENET10G_3_TDN")
	)
	(segment
		(start 356.452678 -6.649974)
		(end 351.92716 -11.175492)
		(width 0.24384)
		(layer "B.Cu")
		(net "ENET10G_3_TDN")
	)
	(segment
		(start 364.201456 -7.168642)
		(end 363.760258 -6.727444)
		(width 0.24384)
		(layer "B.Cu")
		(net "ENET10G_3_TDN")
	)
	(segment
		(start 366.7252 -5.715)
		(end 366.38992 -6.05028)
		(width 0.24384)
		(layer "B.Cu")
		(net "ENET10G_3_TDN")
	)
	(segment
		(start 366.241076 -7.08279)
		(end 365.97971 -7.344156)
		(width 0.24384)
		(layer "B.Cu")
		(net "ENET10G_3_TDN")
	)
	(arc
		(start 363.760258 -6.727444)
		(mid 363.59549 -6.617286)
		(end 363.401102 -6.5786)
		(width 0.24384)
		(layer "B.Cu")
		(net "ENET10G_3_TDN")
	)
	(arc
		(start 366.38992 -6.723634)
		(mid 366.351236 -6.918023)
		(end 366.241076 -7.08279)
		(width 0.24384)
		(layer "B.Cu")
		(net "ENET10G_3_TDN")
	)
	(arc
		(start 364.984538 -7.493)
		(mid 364.560739 -7.408701)
		(end 364.201456 -7.168642)
		(width 0.24384)
		(layer "B.Cu")
		(net "ENET10G_3_TDN")
	)
	(arc
		(start 351.92716 -11.175492)
		(mid 351.567879 -11.415556)
		(end 351.144078 -11.49985)
		(width 0.24384)
		(layer "B.Cu")
		(net "ENET10G_3_TDN")
	)
	(arc
		(start 356.625144 -6.5786)
		(mid 356.531816 -6.597146)
		(end 356.452678 -6.649974)
		(width 0.24384)
		(layer "B.Cu")
		(net "ENET10G_3_TDN")
	)
	(arc
		(start 365.97971 -7.344156)
		(mid 365.814942 -7.454314)
		(end 365.620554 -7.493)
		(width 0.24384)
		(layer "B.Cu")
		(net "ENET10G_3_TDN")
	)
	(segment
		(start 123.401328 -37.516816)
		(end 123.59894 -37.451284)
		(width 0.14732)
		(layer "B.Cu")
		(net "ENET1G_1_MDI2N")
	)
	(segment
		(start 126.5682 -21.077682)
		(end 126.4158 -20.925282)
		(width 0.14732)
		(layer "B.Cu")
		(net "ENET1G_1_MDI2N")
	)
	(segment
		(start 129.4638 -29.6926)
		(end 127.8128 -28.0416)
		(width 0.14732)
		(layer "B.Cu")
		(net "ENET1G_1_MDI2N")
	)
	(segment
		(start 126.4158 -23.5966)
		(end 126.4158 -22.860762)
		(width 0.14732)
		(layer "B.Cu")
		(net "ENET1G_1_MDI2N")
	)
	(segment
		(start 126.4158 -18.547842)
		(end 126.4158 -14.8082)
		(width 0.14732)
		(layer "B.Cu")
		(net "ENET1G_1_MDI2N")
	)
	(segment
		(start 124.775468 -37.606732)
		(end 125.6538 -36.7284)
		(width 0.14732)
		(layer "B.Cu")
		(net "ENET1G_1_MDI2N")
	)
	(segment
		(start 126.4158 -21.672042)
		(end 126.5682 -21.519642)
		(width 0.14732)
		(layer "B.Cu")
		(net "ENET1G_1_MDI2N")
	)
	(segment
		(start 126.5682 -18.700242)
		(end 126.4158 -18.547842)
		(width 0.14732)
		(layer "B.Cu")
		(net "ENET1G_1_MDI2N")
	)
	(segment
		(start 127.1016 -33.9344)
		(end 128.040892 -33.9344)
		(width 0.14732)
		(layer "B.Cu")
		(net "ENET1G_1_MDI2N")
	)
	(segment
		(start 128.040892 -33.9344)
		(end 129.4638 -32.511492)
		(width 0.14732)
		(layer "B.Cu")
		(net "ENET1G_1_MDI2N")
	)
	(segment
		(start 123.59894 -37.451284)
		(end 123.730766 -37.51707)
		(width 0.14732)
		(layer "B.Cu")
		(net "ENET1G_1_MDI2N")
	)
	(segment
		(start 123.820428 -37.606732)
		(end 124.775468 -37.606732)
		(width 0.14732)
		(layer "B.Cu")
		(net "ENET1G_1_MDI2N")
	)
	(segment
		(start 126.4158 -22.860762)
		(end 126.5682 -22.708362)
		(width 0.14732)
		(layer "B.Cu")
		(net "ENET1G_1_MDI2N")
	)
	(segment
		(start 125.6538 -35.3822)
		(end 127.1016 -33.9344)
		(width 0.14732)
		(layer "B.Cu")
		(net "ENET1G_1_MDI2N")
	)
	(segment
		(start 127.8128 -24.9936)
		(end 126.4158 -23.5966)
		(width 0.14732)
		(layer "B.Cu")
		(net "ENET1G_1_MDI2N")
	)
	(segment
		(start 126.4158 -22.114002)
		(end 126.4158 -21.672042)
		(width 0.14732)
		(layer "B.Cu")
		(net "ENET1G_1_MDI2N")
	)
	(segment
		(start 125.835156 -4.252468)
		(end 126.350268 -4.252468)
		(width 0.14732)
		(layer "B.Cu")
		(net "ENET1G_1_MDI2N")
	)
	(segment
		(start 126.5682 -20.330922)
		(end 126.5682 -19.888962)
		(width 0.14732)
		(layer "B.Cu")
		(net "ENET1G_1_MDI2N")
	)
	(segment
		(start 126.5682 -19.142202)
		(end 126.5682 -18.700242)
		(width 0.14732)
		(layer "B.Cu")
		(net "ENET1G_1_MDI2N")
	)
	(segment
		(start 126.4158 -19.294602)
		(end 126.5682 -19.142202)
		(width 0.14732)
		(layer "B.Cu")
		(net "ENET1G_1_MDI2N")
	)
	(segment
		(start 127.8128 -28.0416)
		(end 127.8128 -24.9936)
		(width 0.14732)
		(layer "B.Cu")
		(net "ENET1G_1_MDI2N")
	)
	(segment
		(start 126.350268 -4.252468)
		(end 126.5301 -4.4323)
		(width 0.14732)
		(layer "B.Cu")
		(net "ENET1G_1_MDI2N")
	)
	(segment
		(start 126.5682 -22.708362)
		(end 126.5682 -22.266402)
		(width 0.14732)
		(layer "B.Cu")
		(net "ENET1G_1_MDI2N")
	)
	(segment
		(start 125.687836 -14.080236)
		(end 125.687836 -4.399788)
		(width 0.14732)
		(layer "B.Cu")
		(net "ENET1G_1_MDI2N")
	)
	(segment
		(start 126.4158 -19.736562)
		(end 126.4158 -19.294602)
		(width 0.14732)
		(layer "B.Cu")
		(net "ENET1G_1_MDI2N")
	)
	(segment
		(start 126.5682 -21.519642)
		(end 126.5682 -21.077682)
		(width 0.14732)
		(layer "B.Cu")
		(net "ENET1G_1_MDI2N")
	)
	(segment
		(start 126.5682 -22.266402)
		(end 126.4158 -22.114002)
		(width 0.14732)
		(layer "B.Cu")
		(net "ENET1G_1_MDI2N")
	)
	(segment
		(start 122.900186 -38.5191)
		(end 123.401328 -37.516816)
		(width 0.14732)
		(layer "B.Cu")
		(net "ENET1G_1_MDI2N")
	)
	(segment
		(start 125.6538 -36.7284)
		(end 125.6538 -35.3822)
		(width 0.14732)
		(layer "B.Cu")
		(net "ENET1G_1_MDI2N")
	)
	(segment
		(start 126.5682 -19.888962)
		(end 126.4158 -19.736562)
		(width 0.14732)
		(layer "B.Cu")
		(net "ENET1G_1_MDI2N")
	)
	(segment
		(start 126.4158 -14.8082)
		(end 125.687836 -14.080236)
		(width 0.14732)
		(layer "B.Cu")
		(net "ENET1G_1_MDI2N")
	)
	(segment
		(start 126.4158 -20.925282)
		(end 126.4158 -20.483322)
		(width 0.14732)
		(layer "B.Cu")
		(net "ENET1G_1_MDI2N")
	)
	(segment
		(start 125.687836 -4.399788)
		(end 125.835156 -4.252468)
		(width 0.14732)
		(layer "B.Cu")
		(net "ENET1G_1_MDI2N")
	)
	(segment
		(start 129.4638 -32.511492)
		(end 129.4638 -29.6926)
		(width 0.14732)
		(layer "B.Cu")
		(net "ENET1G_1_MDI2N")
	)
	(segment
		(start 123.730766 -37.51707)
		(end 123.820428 -37.606732)
		(width 0.14732)
		(layer "B.Cu")
		(net "ENET1G_1_MDI2N")
	)
	(segment
		(start 126.5301 -4.4323)
		(end 126.5301 -4.800092)
		(width 0.14732)
		(layer "B.Cu")
		(net "ENET1G_1_MDI2N")
	)
	(segment
		(start 126.4158 -20.483322)
		(end 126.5682 -20.330922)
		(width 0.14732)
		(layer "B.Cu")
		(net "ENET1G_1_MDI2N")
	)
	(segment
		(start 347.98127 -30.603444)
		(end 347.922342 -30.632908)
		(width 0.1524)
		(layer "In2.Cu")
		(net "ENET1G_4_MDI3P")
	)
	(segment
		(start 339.530182 -3.732784)
		(end 339.530182 -3.400044)
		(width 0.1524)
		(layer "In2.Cu")
		(net "ENET1G_4_MDI3P")
	)
	(segment
		(start 347.492066 -31.063438)
		(end 347.492066 -32.622998)
		(width 0.1524)
		(layer "In2.Cu")
		(net "ENET1G_4_MDI3P")
	)
	(segment
		(start 339.694266 -3.896868)
		(end 339.530182 -3.732784)
		(width 0.1524)
		(layer "In2.Cu")
		(net "ENET1G_4_MDI3P")
	)
	(segment
		(start 346.510864 -33.6042)
		(end 340.878668 -33.6042)
		(width 0.1524)
		(layer "In2.Cu")
		(net "ENET1G_4_MDI3P")
	)
	(segment
		(start 342.011 -20.8026)
		(end 340.738206 -19.529806)
		(width 0.1524)
		(layer "In2.Cu")
		(net "ENET1G_4_MDI3P")
	)
	(segment
		(start 347.492066 -32.622998)
		(end 346.510864 -33.6042)
		(width 0.1524)
		(layer "In2.Cu")
		(net "ENET1G_4_MDI3P")
	)
	(segment
		(start 340.878668 -33.6042)
		(end 339.059266 -31.784798)
		(width 0.1524)
		(layer "In2.Cu")
		(net "ENET1G_4_MDI3P")
	)
	(segment
		(start 347.922342 -30.632908)
		(end 347.492066 -31.063438)
		(width 0.1524)
		(layer "In2.Cu")
		(net "ENET1G_4_MDI3P")
	)
	(segment
		(start 339.059266 -27.758136)
		(end 342.011 -24.806402)
		(width 0.1524)
		(layer "In2.Cu")
		(net "ENET1G_4_MDI3P")
	)
	(segment
		(start 342.011 -24.806402)
		(end 342.011 -20.8026)
		(width 0.1524)
		(layer "In2.Cu")
		(net "ENET1G_4_MDI3P")
	)
	(segment
		(start 340.738206 -4.47294)
		(end 340.162134 -3.896868)
		(width 0.1524)
		(layer "In2.Cu")
		(net "ENET1G_4_MDI3P")
	)
	(segment
		(start 340.738206 -19.529806)
		(end 340.738206 -4.47294)
		(width 0.1524)
		(layer "In2.Cu")
		(net "ENET1G_4_MDI3P")
	)
	(segment
		(start 347.710252 -29.379164)
		(end 348.185994 -30.330902)
		(width 0.1524)
		(layer "In2.Cu")
		(net "ENET1G_4_MDI3P")
	)
	(segment
		(start 340.162134 -3.896868)
		(end 339.694266 -3.896868)
		(width 0.1524)
		(layer "In2.Cu")
		(net "ENET1G_4_MDI3P")
	)
	(segment
		(start 339.059266 -31.784798)
		(end 339.059266 -27.758136)
		(width 0.1524)
		(layer "In2.Cu")
		(net "ENET1G_4_MDI3P")
	)
	(segment
		(start 348.185994 -30.330902)
		(end 348.117668 -30.535372)
		(width 0.1524)
		(layer "In2.Cu")
		(net "ENET1G_4_MDI3P")
	)
	(segment
		(start 348.117668 -30.535372)
		(end 347.98127 -30.603444)
		(width 0.1524)
		(layer "In2.Cu")
		(net "ENET1G_4_MDI3P")
	)
	(segment
		(start 334.761586 -9.1948)
		(end 335.173066 -8.78332)
		(width 0.24384)
		(layer "F.Cu")
		(net "ENET10G_4_TDN")
	)
	(segment
		(start 330.086462 -5.327396)
		(end 330.02855 -5.269484)
		(width 0.24384)
		(layer "F.Cu")
		(net "ENET10G_4_TDN")
	)
	(segment
		(start 332.940914 -5.47624)
		(end 332.630018 -5.47624)
		(width 0.24384)
		(layer "F.Cu")
		(net "ENET10G_4_TDN")
	)
	(segment
		(start 328.469752 -5.846826)
		(end 328.469752 -8.852408)
		(width 0.24384)
		(layer "F.Cu")
		(net "ENET10G_4_TDN")
	)
	(segment
		(start 334.772762 -5.12064)
		(end 333.717138 -5.12064)
		(width 0.24384)
		(layer "F.Cu")
		(net "ENET10G_4_TDN")
	)
	(segment
		(start 334.96631 -6.658356)
		(end 335.024222 -6.600444)
		(width 0.24384)
		(layer "F.Cu")
		(net "ENET10G_4_TDN")
	)
	(segment
		(start 330.781914 -5.47624)
		(end 330.445618 -5.47624)
		(width 0.24384)
		(layer "F.Cu")
		(net "ENET10G_4_TDN")
	)
	(segment
		(start 335.024222 -7.699756)
		(end 334.96631 -7.641844)
		(width 0.24384)
		(layer "F.Cu")
		(net "ENET10G_4_TDN")
	)
	(segment
		(start 328.469752 -8.852408)
		(end 328.570082 -8.952738)
		(width 0.24384)
		(layer "F.Cu")
		(net "ENET10G_4_TDN")
	)
	(segment
		(start 328.836782 -5.269484)
		(end 328.618596 -5.48767)
		(width 0.24384)
		(layer "F.Cu")
		(net "ENET10G_4_TDN")
	)
	(segment
		(start 331.853794 -5.12064)
		(end 331.558138 -5.12064)
		(width 0.24384)
		(layer "F.Cu")
		(net "ENET10G_4_TDN")
	)
	(segment
		(start 335.173066 -8.78332)
		(end 335.173066 -8.058912)
		(width 0.24384)
		(layer "F.Cu")
		(net "ENET10G_4_TDN")
	)
	(segment
		(start 328.570082 -8.952738)
		(end 328.570082 -10.290048)
		(width 0.24384)
		(layer "F.Cu")
		(net "ENET10G_4_TDN")
	)
	(segment
		(start 335.173066 -6.241288)
		(end 335.173066 -5.520944)
		(width 0.24384)
		(layer "F.Cu")
		(net "ENET10G_4_TDN")
	)
	(segment
		(start 333.357982 -5.269484)
		(end 333.30007 -5.327396)
		(width 0.24384)
		(layer "F.Cu")
		(net "ENET10G_4_TDN")
	)
	(segment
		(start 332.270862 -5.327396)
		(end 332.21295 -5.269484)
		(width 0.24384)
		(layer "F.Cu")
		(net "ENET10G_4_TDN")
	)
	(segment
		(start 329.669394 -5.12064)
		(end 329.195938 -5.12064)
		(width 0.24384)
		(layer "F.Cu")
		(net "ENET10G_4_TDN")
	)
	(segment
		(start 335.101692 -5.348478)
		(end 334.945228 -5.192014)
		(width 0.24384)
		(layer "F.Cu")
		(net "ENET10G_4_TDN")
	)
	(segment
		(start 334.817466 -7.282688)
		(end 334.817466 -7.017512)
		(width 0.24384)
		(layer "F.Cu")
		(net "ENET10G_4_TDN")
	)
	(segment
		(start 331.198982 -5.269484)
		(end 331.14107 -5.327396)
		(width 0.24384)
		(layer "F.Cu")
		(net "ENET10G_4_TDN")
	)
	(via
		(at 334.761586 -9.1948)
		(size 0.508)
		(drill 0.254)
		(layers "F.Cu" "B.Cu")
		(net "ENET10G_4_TDN")
	)
	(arc
		(start 328.618596 -5.48767)
		(mid 328.508438 -5.652438)
		(end 328.469752 -5.846826)
		(width 0.24384)
		(layer "F.Cu")
		(net "ENET10G_4_TDN")
	)
	(arc
		(start 334.817466 -7.017512)
		(mid 334.85615 -6.823123)
		(end 334.96631 -6.658356)
		(width 0.24384)
		(layer "F.Cu")
		(net "ENET10G_4_TDN")
	)
	(arc
		(start 332.630018 -5.47624)
		(mid 332.435629 -5.437556)
		(end 332.270862 -5.327396)
		(width 0.24384)
		(layer "F.Cu")
		(net "ENET10G_4_TDN")
	)
	(arc
		(start 333.30007 -5.327396)
		(mid 333.135302 -5.437554)
		(end 332.940914 -5.47624)
		(width 0.24384)
		(layer "F.Cu")
		(net "ENET10G_4_TDN")
	)
	(arc
		(start 335.173066 -8.058912)
		(mid 335.134382 -7.864523)
		(end 335.024222 -7.699756)
		(width 0.24384)
		(layer "F.Cu")
		(net "ENET10G_4_TDN")
	)
	(arc
		(start 332.21295 -5.269484)
		(mid 332.048182 -5.159326)
		(end 331.853794 -5.12064)
		(width 0.24384)
		(layer "F.Cu")
		(net "ENET10G_4_TDN")
	)
	(arc
		(start 333.717138 -5.12064)
		(mid 333.522749 -5.159324)
		(end 333.357982 -5.269484)
		(width 0.24384)
		(layer "F.Cu")
		(net "ENET10G_4_TDN")
	)
	(arc
		(start 334.945228 -5.192014)
		(mid 334.866086 -5.139196)
		(end 334.772762 -5.12064)
		(width 0.24384)
		(layer "F.Cu")
		(net "ENET10G_4_TDN")
	)
	(arc
		(start 329.195938 -5.12064)
		(mid 329.001549 -5.159324)
		(end 328.836782 -5.269484)
		(width 0.24384)
		(layer "F.Cu")
		(net "ENET10G_4_TDN")
	)
	(arc
		(start 335.173066 -5.520944)
		(mid 335.15452 -5.427616)
		(end 335.101692 -5.348478)
		(width 0.24384)
		(layer "F.Cu")
		(net "ENET10G_4_TDN")
	)
	(arc
		(start 331.14107 -5.327396)
		(mid 330.976302 -5.437554)
		(end 330.781914 -5.47624)
		(width 0.24384)
		(layer "F.Cu")
		(net "ENET10G_4_TDN")
	)
	(arc
		(start 335.024222 -6.600444)
		(mid 335.13438 -6.435676)
		(end 335.173066 -6.241288)
		(width 0.24384)
		(layer "F.Cu")
		(net "ENET10G_4_TDN")
	)
	(arc
		(start 331.558138 -5.12064)
		(mid 331.363749 -5.159324)
		(end 331.198982 -5.269484)
		(width 0.24384)
		(layer "F.Cu")
		(net "ENET10G_4_TDN")
	)
	(arc
		(start 330.445618 -5.47624)
		(mid 330.251229 -5.437556)
		(end 330.086462 -5.327396)
		(width 0.24384)
		(layer "F.Cu")
		(net "ENET10G_4_TDN")
	)
	(arc
		(start 330.02855 -5.269484)
		(mid 329.863782 -5.159326)
		(end 329.669394 -5.12064)
		(width 0.24384)
		(layer "F.Cu")
		(net "ENET10G_4_TDN")
	)
	(arc
		(start 334.96631 -7.641844)
		(mid 334.856152 -7.477076)
		(end 334.817466 -7.282688)
		(width 0.24384)
		(layer "F.Cu")
		(net "ENET10G_4_TDN")
	)
	(segment
		(start 335.173066 -11.307064)
		(end 335.173066 -11.463528)
		(width 0.24384)
		(layer "B.Cu")
		(net "ENET10G_4_TDN")
	)
	(segment
		(start 336.50936 -12.799822)
		(end 336.713576 -12.799822)
		(width 0.24384)
		(layer "B.Cu")
		(net "ENET10G_4_TDN")
	)
	(segment
		(start 338.134706 -13.04036)
		(end 338.226146 -12.94892)
		(width 0.24384)
		(layer "B.Cu")
		(net "ENET10G_4_TDN")
	)
	(segment
		(start 335.033366 -11.0109)
		(end 335.062322 -11.039856)
		(width 0.24384)
		(layer "B.Cu")
		(net "ENET10G_4_TDN")
	)
	(segment
		(start 337.072732 -12.948666)
		(end 337.107022 -12.982956)
		(width 0.24384)
		(layer "B.Cu")
		(net "ENET10G_4_TDN")
	)
	(segment
		(start 339.129878 -12.799822)
		(end 339.530182 -13.200126)
		(width 0.24384)
		(layer "B.Cu")
		(net "ENET10G_4_TDN")
	)
	(segment
		(start 335.067148 -10.011918)
		(end 335.04251 -10.036556)
		(width 0.24384)
		(layer "B.Cu")
		(net "ENET10G_4_TDN")
	)
	(segment
		(start 335.172558 -9.605772)
		(end 335.172558 -9.777476)
		(width 0.24384)
		(layer "B.Cu")
		(net "ENET10G_4_TDN")
	)
	(segment
		(start 335.497424 -12.24661)
		(end 335.726278 -12.475464)
		(width 0.24384)
		(layer "B.Cu")
		(net "ENET10G_4_TDN")
	)
	(segment
		(start 334.761586 -9.1948)
		(end 335.172558 -9.605772)
		(width 0.24384)
		(layer "B.Cu")
		(net "ENET10G_4_TDN")
	)
	(segment
		(start 334.893666 -10.395712)
		(end 334.893666 -10.673588)
		(width 0.24384)
		(layer "B.Cu")
		(net "ENET10G_4_TDN")
	)
	(segment
		(start 337.466178 -13.1318)
		(end 337.91398 -13.1318)
		(width 0.24384)
		(layer "B.Cu")
		(net "ENET10G_4_TDN")
	)
	(segment
		(start 338.585556 -12.799822)
		(end 339.129878 -12.799822)
		(width 0.24384)
		(layer "B.Cu")
		(net "ENET10G_4_TDN")
	)
	(arc
		(start 338.226146 -12.94892)
		(mid 338.391002 -12.838577)
		(end 338.585556 -12.799822)
		(width 0.24384)
		(layer "B.Cu")
		(net "ENET10G_4_TDN")
	)
	(arc
		(start 335.726278 -12.475464)
		(mid 336.085559 -12.715528)
		(end 336.50936 -12.799822)
		(width 0.24384)
		(layer "B.Cu")
		(net "ENET10G_4_TDN")
	)
	(arc
		(start 335.04251 -10.036556)
		(mid 334.932352 -10.201324)
		(end 334.893666 -10.395712)
		(width 0.24384)
		(layer "B.Cu")
		(net "ENET10G_4_TDN")
	)
	(arc
		(start 334.893666 -10.673588)
		(mid 334.929976 -10.856133)
		(end 335.033366 -11.0109)
		(width 0.24384)
		(layer "B.Cu")
		(net "ENET10G_4_TDN")
	)
	(arc
		(start 337.91398 -13.1318)
		(mid 338.033441 -13.108038)
		(end 338.134706 -13.04036)
		(width 0.24384)
		(layer "B.Cu")
		(net "ENET10G_4_TDN")
	)
	(arc
		(start 336.713576 -12.799822)
		(mid 336.907965 -12.838506)
		(end 337.072732 -12.948666)
		(width 0.24384)
		(layer "B.Cu")
		(net "ENET10G_4_TDN")
	)
	(arc
		(start 335.172558 -9.777476)
		(mid 335.141341 -9.904351)
		(end 335.067148 -10.011918)
		(width 0.24384)
		(layer "B.Cu")
		(net "ENET10G_4_TDN")
	)
	(arc
		(start 335.062322 -11.039856)
		(mid 335.144292 -11.162438)
		(end 335.173066 -11.307064)
		(width 0.24384)
		(layer "B.Cu")
		(net "ENET10G_4_TDN")
	)
	(arc
		(start 337.107022 -12.982956)
		(mid 337.27179 -13.093114)
		(end 337.466178 -13.1318)
		(width 0.24384)
		(layer "B.Cu")
		(net "ENET10G_4_TDN")
	)
	(arc
		(start 335.173066 -11.463528)
		(mid 335.257365 -11.887327)
		(end 335.497424 -12.24661)
		(width 0.24384)
		(layer "B.Cu")
		(net "ENET10G_4_TDN")
	)
	(segment
		(start 136.038336 -5.040884)
		(end 136.081008 -5.083556)
		(width 0.24384)
		(layer "F.Cu")
		(net "ENET10G_1_RDN")
	)
	(segment
		(start 139.990322 -8.852662)
		(end 139.889992 -8.952992)
		(width 0.24384)
		(layer "F.Cu")
		(net "ENET10G_1_RDN")
	)
	(segment
		(start 136.915398 -5.136642)
		(end 137.011156 -5.040884)
		(width 0.24384)
		(layer "F.Cu")
		(net "ENET10G_1_RDN")
	)
	(segment
		(start 139.890246 -8.953246)
		(end 139.890246 -10.290048)
		(width 0.24384)
		(layer "F.Cu")
		(net "ENET10G_1_RDN")
	)
	(segment
		(start 134.99465 -5.136642)
		(end 135.090408 -5.040884)
		(width 0.24384)
		(layer "F.Cu")
		(net "ENET10G_1_RDN")
	)
	(segment
		(start 139.990322 -5.354066)
		(end 139.990322 -5.789422)
		(width 0.24384)
		(layer "F.Cu")
		(net "ENET10G_1_RDN")
	)
	(segment
		(start 139.841478 -6.148832)
		(end 139.80922 -6.18109)
		(width 0.24384)
		(layer "F.Cu")
		(net "ENET10G_1_RDN")
	)
	(segment
		(start 134.500112 -5.2324)
		(end 134.76351 -5.2324)
		(width 0.24384)
		(layer "F.Cu")
		(net "ENET10G_1_RDN")
	)
	(segment
		(start 139.377928 -4.89204)
		(end 139.528296 -4.89204)
		(width 0.24384)
		(layer "F.Cu")
		(net "ENET10G_1_RDN")
	)
	(segment
		(start 139.00404 -5.11556)
		(end 139.121134 -4.998466)
		(width 0.24384)
		(layer "F.Cu")
		(net "ENET10G_1_RDN")
	)
	(segment
		(start 139.660122 -6.5405)
		(end 139.660122 -6.800088)
		(width 0.24384)
		(layer "F.Cu")
		(net "ENET10G_1_RDN")
	)
	(segment
		(start 132.9182 -5.22732)
		(end 133.104636 -5.040884)
		(width 0.24384)
		(layer "F.Cu")
		(net "ENET10G_1_RDN")
	)
	(segment
		(start 137.370312 -4.89204)
		(end 137.752328 -4.89204)
		(width 0.24384)
		(layer "F.Cu")
		(net "ENET10G_1_RDN")
	)
	(segment
		(start 133.463792 -4.89204)
		(end 133.739128 -4.89204)
		(width 0.24384)
		(layer "F.Cu")
		(net "ENET10G_1_RDN")
	)
	(segment
		(start 139.808966 -7.159244)
		(end 139.990322 -7.3406)
		(width 0.24384)
		(layer "F.Cu")
		(net "ENET10G_1_RDN")
	)
	(segment
		(start 139.700762 -4.963414)
		(end 139.918948 -5.1816)
		(width 0.24384)
		(layer "F.Cu")
		(net "ENET10G_1_RDN")
	)
	(segment
		(start 134.098284 -5.040884)
		(end 134.140956 -5.083556)
		(width 0.24384)
		(layer "F.Cu")
		(net "ENET10G_1_RDN")
	)
	(segment
		(start 135.449564 -4.89204)
		(end 135.67918 -4.89204)
		(width 0.24384)
		(layer "F.Cu")
		(net "ENET10G_1_RDN")
	)
	(segment
		(start 139.889992 -8.952992)
		(end 139.890246 -8.953246)
		(width 0.24384)
		(layer "F.Cu")
		(net "ENET10G_1_RDN")
	)
	(segment
		(start 138.111484 -5.040884)
		(end 138.154156 -5.083556)
		(width 0.24384)
		(layer "F.Cu")
		(net "ENET10G_1_RDN")
	)
	(segment
		(start 138.513312 -5.2324)
		(end 138.721846 -5.2324)
		(width 0.24384)
		(layer "F.Cu")
		(net "ENET10G_1_RDN")
	)
	(segment
		(start 136.440164 -5.2324)
		(end 136.684258 -5.2324)
		(width 0.24384)
		(layer "F.Cu")
		(net "ENET10G_1_RDN")
	)
	(segment
		(start 139.990322 -7.3406)
		(end 139.990322 -8.852662)
		(width 0.24384)
		(layer "F.Cu")
		(net "ENET10G_1_RDN")
	)
	(via
		(at 132.9182 -5.22732)
		(size 0.508)
		(drill 0.254)
		(layers "F.Cu" "B.Cu")
		(net "ENET10G_1_RDN")
	)
	(arc
		(start 136.684258 -5.2324)
		(mid 136.809356 -5.207516)
		(end 136.915398 -5.136642)
		(width 0.24384)
		(layer "F.Cu")
		(net "ENET10G_1_RDN")
	)
	(arc
		(start 134.140956 -5.083556)
		(mid 134.305724 -5.193714)
		(end 134.500112 -5.2324)
		(width 0.24384)
		(layer "F.Cu")
		(net "ENET10G_1_RDN")
	)
	(arc
		(start 139.660122 -6.800088)
		(mid 139.698806 -6.994477)
		(end 139.808966 -7.159244)
		(width 0.24384)
		(layer "F.Cu")
		(net "ENET10G_1_RDN")
	)
	(arc
		(start 134.76351 -5.2324)
		(mid 134.888608 -5.207516)
		(end 134.99465 -5.136642)
		(width 0.24384)
		(layer "F.Cu")
		(net "ENET10G_1_RDN")
	)
	(arc
		(start 136.081008 -5.083556)
		(mid 136.245776 -5.193714)
		(end 136.440164 -5.2324)
		(width 0.24384)
		(layer "F.Cu")
		(net "ENET10G_1_RDN")
	)
	(arc
		(start 133.104636 -5.040884)
		(mid 133.269404 -4.930726)
		(end 133.463792 -4.89204)
		(width 0.24384)
		(layer "F.Cu")
		(net "ENET10G_1_RDN")
	)
	(arc
		(start 135.67918 -4.89204)
		(mid 135.873569 -4.930724)
		(end 136.038336 -5.040884)
		(width 0.24384)
		(layer "F.Cu")
		(net "ENET10G_1_RDN")
	)
	(arc
		(start 139.80922 -6.18109)
		(mid 139.698877 -6.345946)
		(end 139.660122 -6.5405)
		(width 0.24384)
		(layer "F.Cu")
		(net "ENET10G_1_RDN")
	)
	(arc
		(start 138.154156 -5.083556)
		(mid 138.318924 -5.193714)
		(end 138.513312 -5.2324)
		(width 0.24384)
		(layer "F.Cu")
		(net "ENET10G_1_RDN")
	)
	(arc
		(start 139.121134 -4.998466)
		(mid 139.238938 -4.919689)
		(end 139.377928 -4.89204)
		(width 0.24384)
		(layer "F.Cu")
		(net "ENET10G_1_RDN")
	)
	(arc
		(start 137.752328 -4.89204)
		(mid 137.946717 -4.930724)
		(end 138.111484 -5.040884)
		(width 0.24384)
		(layer "F.Cu")
		(net "ENET10G_1_RDN")
	)
	(arc
		(start 139.990322 -5.789422)
		(mid 139.951701 -5.983962)
		(end 139.841478 -6.148832)
		(width 0.24384)
		(layer "F.Cu")
		(net "ENET10G_1_RDN")
	)
	(arc
		(start 138.721846 -5.2324)
		(mid 138.874564 -5.20204)
		(end 139.00404 -5.11556)
		(width 0.24384)
		(layer "F.Cu")
		(net "ENET10G_1_RDN")
	)
	(arc
		(start 135.090408 -5.040884)
		(mid 135.255176 -4.930726)
		(end 135.449564 -4.89204)
		(width 0.24384)
		(layer "F.Cu")
		(net "ENET10G_1_RDN")
	)
	(arc
		(start 137.011156 -5.040884)
		(mid 137.175924 -4.930726)
		(end 137.370312 -4.89204)
		(width 0.24384)
		(layer "F.Cu")
		(net "ENET10G_1_RDN")
	)
	(arc
		(start 133.739128 -4.89204)
		(mid 133.933517 -4.930724)
		(end 134.098284 -5.040884)
		(width 0.24384)
		(layer "F.Cu")
		(net "ENET10G_1_RDN")
	)
	(arc
		(start 139.528296 -4.89204)
		(mid 139.621624 -4.910586)
		(end 139.700762 -4.963414)
		(width 0.24384)
		(layer "F.Cu")
		(net "ENET10G_1_RDN")
	)
	(arc
		(start 139.918948 -5.1816)
		(mid 139.971766 -5.260742)
		(end 139.990322 -5.354066)
		(width 0.24384)
		(layer "F.Cu")
		(net "ENET10G_1_RDN")
	)
	(segment
		(start 130.812794 -5.082794)
		(end 130.724148 -4.994148)
		(width 0.24384)
		(layer "B.Cu")
		(net "ENET10G_1_RDN")
	)
	(segment
		(start 131.738116 -5.040884)
		(end 131.705604 -5.073396)
		(width 0.24384)
		(layer "B.Cu")
		(net "ENET10G_1_RDN")
	)
	(segment
		(start 131.346448 -5.22224)
		(end 131.149344 -5.22224)
		(width 0.24384)
		(layer "B.Cu")
		(net "ENET10G_1_RDN")
	)
	(segment
		(start 132.372608 -4.89204)
		(end 132.097272 -4.89204)
		(width 0.24384)
		(layer "B.Cu")
		(net "ENET10G_1_RDN")
	)
	(segment
		(start 132.9182 -5.22732)
		(end 132.731764 -5.040884)
		(width 0.24384)
		(layer "B.Cu")
		(net "ENET10G_1_RDN")
	)
	(segment
		(start 130.13944 -5.230368)
		(end 130.13944 -6.492494)
		(width 0.24384)
		(layer "B.Cu")
		(net "ENET10G_1_RDN")
	)
	(segment
		(start 128.9304 -7.299706)
		(end 128.530096 -7.70001)
		(width 0.24384)
		(layer "B.Cu")
		(net "ENET10G_1_RDN")
	)
	(segment
		(start 129.332228 -7.299706)
		(end 128.9304 -7.299706)
		(width 0.24384)
		(layer "B.Cu")
		(net "ENET10G_1_RDN")
	)
	(arc
		(start 132.097272 -4.89204)
		(mid 131.902883 -4.930724)
		(end 131.738116 -5.040884)
		(width 0.24384)
		(layer "B.Cu")
		(net "ENET10G_1_RDN")
	)
	(arc
		(start 131.149344 -5.22224)
		(mid 130.967202 -5.185992)
		(end 130.812794 -5.082794)
		(width 0.24384)
		(layer "B.Cu")
		(net "ENET10G_1_RDN")
	)
	(arc
		(start 130.13944 -6.492494)
		(mid 130.07823 -6.801137)
		(end 129.903728 -7.062978)
		(width 0.24384)
		(layer "B.Cu")
		(net "ENET10G_1_RDN")
	)
	(arc
		(start 130.724148 -4.994148)
		(mid 130.611122 -4.918563)
		(end 130.477768 -4.89204)
		(width 0.24384)
		(layer "B.Cu")
		(net "ENET10G_1_RDN")
	)
	(arc
		(start 130.2385 -4.9911)
		(mid 130.165203 -5.100891)
		(end 130.13944 -5.230368)
		(width 0.24384)
		(layer "B.Cu")
		(net "ENET10G_1_RDN")
	)
	(arc
		(start 132.731764 -5.040884)
		(mid 132.566996 -4.930726)
		(end 132.372608 -4.89204)
		(width 0.24384)
		(layer "B.Cu")
		(net "ENET10G_1_RDN")
	)
	(arc
		(start 131.705604 -5.073396)
		(mid 131.540836 -5.183554)
		(end 131.346448 -5.22224)
		(width 0.24384)
		(layer "B.Cu")
		(net "ENET10G_1_RDN")
	)
	(arc
		(start 129.903728 -7.062978)
		(mid 129.641549 -7.238257)
		(end 129.332228 -7.299706)
		(width 0.24384)
		(layer "B.Cu")
		(net "ENET10G_1_RDN")
	)
	(arc
		(start 130.477768 -4.89204)
		(mid 130.348281 -4.917779)
		(end 130.2385 -4.9911)
		(width 0.24384)
		(layer "B.Cu")
		(net "ENET10G_1_RDN")
	)
	(segment
		(start 349.930466 -28.672282)
		(end 349.758 -28.844494)
		(width 0.1524)
		(layer "In5.Cu")
		(net "ENET1G_3_MDI0N")
	)
	(segment
		(start 349.758 -28.844494)
		(end 349.758 -29.301694)
		(width 0.1524)
		(layer "In5.Cu")
		(net "ENET1G_3_MDI0N")
	)
	(segment
		(start 349.758 -28.04287)
		(end 349.930466 -28.215082)
		(width 0.1524)
		(layer "In5.Cu")
		(net "ENET1G_3_MDI0N")
	)
	(segment
		(start 349.758 -29.301694)
		(end 349.930466 -29.473906)
		(width 0.1524)
		(layer "In5.Cu")
		(net "ENET1G_3_MDI0N")
	)
	(segment
		(start 349.930466 -26.956258)
		(end 349.930466 -27.413458)
		(width 0.1524)
		(layer "In5.Cu")
		(net "ENET1G_3_MDI0N")
	)
	(segment
		(start 349.930466 -22.031198)
		(end 349.930466 -26.154634)
		(width 0.1524)
		(layer "In5.Cu")
		(net "ENET1G_3_MDI0N")
	)
	(segment
		(start 349.758 -26.784046)
		(end 349.930466 -26.956258)
		(width 0.1524)
		(layer "In5.Cu")
		(net "ENET1G_3_MDI0N")
	)
	(segment
		(start 348.390464 -36.998656)
		(end 348.185994 -36.930838)
		(width 0.1524)
		(layer "In5.Cu")
		(net "ENET1G_3_MDI0N")
	)
	(segment
		(start 349.530162 -3.50012)
		(end 350.026986 -3.003296)
		(width 0.1524)
		(layer "In5.Cu")
		(net "ENET1G_3_MDI0N")
	)
	(segment
		(start 348.185994 -36.930838)
		(end 347.710252 -35.9791)
		(width 0.1524)
		(layer "In5.Cu")
		(net "ENET1G_3_MDI0N")
	)
	(segment
		(start 348.467934 -36.960048)
		(end 348.390464 -36.998656)
		(width 0.1524)
		(layer "In5.Cu")
		(net "ENET1G_3_MDI0N")
	)
	(segment
		(start 349.930466 -35.49777)
		(end 348.467934 -36.960048)
		(width 0.1524)
		(layer "In5.Cu")
		(net "ENET1G_3_MDI0N")
	)
	(segment
		(start 351.835466 -3.7846)
		(end 351.835466 -20.126198)
		(width 0.1524)
		(layer "In5.Cu")
		(net "ENET1G_3_MDI0N")
	)
	(segment
		(start 349.930466 -26.154634)
		(end 349.758 -26.326846)
		(width 0.1524)
		(layer "In5.Cu")
		(net "ENET1G_3_MDI0N")
	)
	(segment
		(start 349.930466 -27.413458)
		(end 349.758 -27.58567)
		(width 0.1524)
		(layer "In5.Cu")
		(net "ENET1G_3_MDI0N")
	)
	(segment
		(start 349.930466 -28.215082)
		(end 349.930466 -28.672282)
		(width 0.1524)
		(layer "In5.Cu")
		(net "ENET1G_3_MDI0N")
	)
	(segment
		(start 351.835466 -20.126198)
		(end 349.930466 -22.031198)
		(width 0.1524)
		(layer "In5.Cu")
		(net "ENET1G_3_MDI0N")
	)
	(segment
		(start 349.930466 -29.473906)
		(end 349.930466 -35.49777)
		(width 0.1524)
		(layer "In5.Cu")
		(net "ENET1G_3_MDI0N")
	)
	(segment
		(start 349.758 -27.58567)
		(end 349.758 -28.04287)
		(width 0.1524)
		(layer "In5.Cu")
		(net "ENET1G_3_MDI0N")
	)
	(segment
		(start 349.758 -26.326846)
		(end 349.758 -26.784046)
		(width 0.1524)
		(layer "In5.Cu")
		(net "ENET1G_3_MDI0N")
	)
	(segment
		(start 351.054162 -3.003296)
		(end 351.835466 -3.7846)
		(width 0.1524)
		(layer "In5.Cu")
		(net "ENET1G_3_MDI0N")
	)
	(segment
		(start 350.026986 -3.003296)
		(end 351.054162 -3.003296)
		(width 0.1524)
		(layer "In5.Cu")
		(net "ENET1G_3_MDI0N")
	)
	(segment
		(start 140.589762 -8.852662)
		(end 140.690092 -8.952992)
		(width 0.24384)
		(layer "F.Cu")
		(net "ENET10G_1_RDP")
	)
	(segment
		(start 140.690092 -8.952992)
		(end 140.690092 -10.290048)
		(width 0.24384)
		(layer "F.Cu")
		(net "ENET10G_1_RDP")
	)
	(segment
		(start 132.9182 -3.95732)
		(end 133.25348 -4.2926)
		(width 0.24384)
		(layer "F.Cu")
		(net "ENET10G_1_RDP")
	)
	(segment
		(start 133.25348 -4.2926)
		(end 139.667488 -4.2926)
		(width 0.24384)
		(layer "F.Cu")
		(net "ENET10G_1_RDP")
	)
	(segment
		(start 140.026644 -4.441444)
		(end 140.440918 -4.855718)
		(width 0.24384)
		(layer "F.Cu")
		(net "ENET10G_1_RDP")
	)
	(segment
		(start 140.589762 -5.214874)
		(end 140.589762 -8.852662)
		(width 0.24384)
		(layer "F.Cu")
		(net "ENET10G_1_RDP")
	)
	(via
		(at 132.9182 -3.95732)
		(size 0.508)
		(drill 0.254)
		(layers "F.Cu" "B.Cu")
		(net "ENET10G_1_RDP")
	)
	(arc
		(start 140.440918 -4.855718)
		(mid 140.551076 -5.020486)
		(end 140.589762 -5.214874)
		(width 0.24384)
		(layer "F.Cu")
		(net "ENET10G_1_RDP")
	)
	(arc
		(start 139.667488 -4.2926)
		(mid 139.861877 -4.331284)
		(end 140.026644 -4.441444)
		(width 0.24384)
		(layer "F.Cu")
		(net "ENET10G_1_RDP")
	)
	(segment
		(start 129.54 -5.230368)
		(end 129.54 -6.492494)
		(width 0.24384)
		(layer "B.Cu")
		(net "ENET10G_1_RDP")
	)
	(segment
		(start 132.9182 -3.95732)
		(end 132.58292 -4.2926)
		(width 0.24384)
		(layer "B.Cu")
		(net "ENET10G_1_RDP")
	)
	(segment
		(start 128.9304 -6.700266)
		(end 128.530096 -6.299962)
		(width 0.24384)
		(layer "B.Cu")
		(net "ENET10G_1_RDP")
	)
	(segment
		(start 129.332228 -6.700266)
		(end 128.9304 -6.700266)
		(width 0.24384)
		(layer "B.Cu")
		(net "ENET10G_1_RDP")
	)
	(segment
		(start 132.58292 -4.2926)
		(end 130.477768 -4.2926)
		(width 0.24384)
		(layer "B.Cu")
		(net "ENET10G_1_RDP")
	)
	(arc
		(start 129.479294 -6.639306)
		(mid 129.411834 -6.684445)
		(end 129.332228 -6.700266)
		(width 0.24384)
		(layer "B.Cu")
		(net "ENET10G_1_RDP")
	)
	(arc
		(start 129.814574 -4.567174)
		(mid 129.611371 -4.871478)
		(end 129.54 -5.230368)
		(width 0.24384)
		(layer "B.Cu")
		(net "ENET10G_1_RDP")
	)
	(arc
		(start 129.54 -6.492494)
		(mid 129.524219 -6.571922)
		(end 129.479294 -6.639306)
		(width 0.24384)
		(layer "B.Cu")
		(net "ENET10G_1_RDP")
	)
	(arc
		(start 130.477768 -4.2926)
		(mid 130.118871 -4.363953)
		(end 129.814574 -4.567174)
		(width 0.24384)
		(layer "B.Cu")
		(net "ENET10G_1_RDP")
	)
	(segment
		(start 341.802466 -30.7848)
		(end 341.040466 -30.0228)
		(width 0.1524)
		(layer "In2.Cu")
		(net "ENET1G_4_MDI1N")
	)
	(segment
		(start 341.530178 -3.167888)
		(end 341.530178 -3.50012)
		(width 0.1524)
		(layer "In2.Cu")
		(net "ENET1G_4_MDI1N")
	)
	(segment
		(start 342.07196 -3.003296)
		(end 341.69477 -3.003296)
		(width 0.1524)
		(layer "In2.Cu")
		(net "ENET1G_4_MDI1N")
	)
	(segment
		(start 345.305888 -30.7848)
		(end 341.802466 -30.7848)
		(width 0.1524)
		(layer "In2.Cu")
		(net "ENET1G_4_MDI1N")
	)
	(segment
		(start 343.428066 -26.5684)
		(end 343.428066 -19.9644)
		(width 0.1524)
		(layer "In2.Cu")
		(net "ENET1G_4_MDI1N")
	)
	(segment
		(start 341.040466 -30.0228)
		(end 341.040466 -28.956)
		(width 0.1524)
		(layer "In2.Cu")
		(net "ENET1G_4_MDI1N")
	)
	(segment
		(start 343.428066 -19.9644)
		(end 342.259666 -18.796)
		(width 0.1524)
		(layer "In2.Cu")
		(net "ENET1G_4_MDI1N")
	)
	(segment
		(start 341.69477 -3.003296)
		(end 341.530178 -3.167888)
		(width 0.1524)
		(layer "In2.Cu")
		(net "ENET1G_4_MDI1N")
	)
	(segment
		(start 346.440252 -31.919164)
		(end 345.305888 -30.7848)
		(width 0.1524)
		(layer "In2.Cu")
		(net "ENET1G_4_MDI1N")
	)
	(segment
		(start 342.259666 -18.796)
		(end 342.259666 -3.191002)
		(width 0.1524)
		(layer "In2.Cu")
		(net "ENET1G_4_MDI1N")
	)
	(segment
		(start 341.040466 -28.956)
		(end 343.428066 -26.5684)
		(width 0.1524)
		(layer "In2.Cu")
		(net "ENET1G_4_MDI1N")
	)
	(segment
		(start 342.259666 -3.191002)
		(end 342.07196 -3.003296)
		(width 0.1524)
		(layer "In2.Cu")
		(net "ENET1G_4_MDI1N")
	)
	(segment
		(start 346.6084 -35.2806)
		(end 347.4974 -34.3916)
		(width 0.14732)
		(layer "B.Cu")
		(net "ENET1G_3_MDI2N")
	)
	(segment
		(start 350.6216 -25.77846)
		(end 350.6216 -25.3365)
		(width 0.14732)
		(layer "B.Cu")
		(net "ENET1G_3_MDI2N")
	)
	(segment
		(start 347.381068 -4.252468)
		(end 347.530166 -4.401566)
		(width 0.14732)
		(layer "B.Cu")
		(net "ENET1G_3_MDI2N")
	)
	(segment
		(start 350.463866 -25.93594)
		(end 350.6216 -25.77846)
		(width 0.14732)
		(layer "B.Cu")
		(net "ENET1G_3_MDI2N")
	)
	(segment
		(start 344.401394 -37.516816)
		(end 344.599006 -37.451284)
		(width 0.14732)
		(layer "B.Cu")
		(net "ENET1G_3_MDI2N")
	)
	(segment
		(start 346.835222 -4.252468)
		(end 347.381068 -4.252468)
		(width 0.14732)
		(layer "B.Cu")
		(net "ENET1G_3_MDI2N")
	)
	(segment
		(start 350.463866 -22.78126)
		(end 350.463866 -22.3393)
		(width 0.14732)
		(layer "B.Cu")
		(net "ENET1G_3_MDI2N")
	)
	(segment
		(start 350.6216 -25.3365)
		(end 350.463866 -25.17902)
		(width 0.14732)
		(layer "B.Cu")
		(net "ENET1G_3_MDI2N")
	)
	(segment
		(start 350.463866 -18.460466)
		(end 346.687902 -14.684502)
		(width 0.14732)
		(layer "B.Cu")
		(net "ENET1G_3_MDI2N")
	)
	(segment
		(start 347.4974 -34.3916)
		(end 348.583758 -34.3916)
		(width 0.14732)
		(layer "B.Cu")
		(net "ENET1G_3_MDI2N")
	)
	(segment
		(start 350.463866 -23.53818)
		(end 350.6216 -23.3807)
		(width 0.14732)
		(layer "B.Cu")
		(net "ENET1G_3_MDI2N")
	)
	(segment
		(start 344.820494 -37.606732)
		(end 345.806268 -37.606732)
		(width 0.14732)
		(layer "B.Cu")
		(net "ENET1G_3_MDI2N")
	)
	(segment
		(start 345.806268 -37.606732)
		(end 346.6084 -36.8046)
		(width 0.14732)
		(layer "B.Cu")
		(net "ENET1G_3_MDI2N")
	)
	(segment
		(start 350.6216 -22.18182)
		(end 350.6216 -21.73986)
		(width 0.14732)
		(layer "B.Cu")
		(net "ENET1G_3_MDI2N")
	)
	(segment
		(start 347.530166 -4.401566)
		(end 347.530166 -4.800092)
		(width 0.14732)
		(layer "B.Cu")
		(net "ENET1G_3_MDI2N")
	)
	(segment
		(start 350.463866 -32.511492)
		(end 350.463866 -25.93594)
		(width 0.14732)
		(layer "B.Cu")
		(net "ENET1G_3_MDI2N")
	)
	(segment
		(start 343.900252 -38.5191)
		(end 344.401394 -37.516816)
		(width 0.14732)
		(layer "B.Cu")
		(net "ENET1G_3_MDI2N")
	)
	(segment
		(start 350.463866 -22.3393)
		(end 350.6216 -22.18182)
		(width 0.14732)
		(layer "B.Cu")
		(net "ENET1G_3_MDI2N")
	)
	(segment
		(start 344.599006 -37.451284)
		(end 344.730832 -37.51707)
		(width 0.14732)
		(layer "B.Cu")
		(net "ENET1G_3_MDI2N")
	)
	(segment
		(start 350.6216 -24.57958)
		(end 350.6216 -24.13762)
		(width 0.14732)
		(layer "B.Cu")
		(net "ENET1G_3_MDI2N")
	)
	(segment
		(start 346.687902 -4.399788)
		(end 346.835222 -4.252468)
		(width 0.14732)
		(layer "B.Cu")
		(net "ENET1G_3_MDI2N")
	)
	(segment
		(start 350.463866 -24.73706)
		(end 350.6216 -24.57958)
		(width 0.14732)
		(layer "B.Cu")
		(net "ENET1G_3_MDI2N")
	)
	(segment
		(start 346.687902 -14.684502)
		(end 346.687902 -4.399788)
		(width 0.14732)
		(layer "B.Cu")
		(net "ENET1G_3_MDI2N")
	)
	(segment
		(start 348.583758 -34.3916)
		(end 350.463866 -32.511492)
		(width 0.14732)
		(layer "B.Cu")
		(net "ENET1G_3_MDI2N")
	)
	(segment
		(start 350.6216 -23.3807)
		(end 350.6216 -22.93874)
		(width 0.14732)
		(layer "B.Cu")
		(net "ENET1G_3_MDI2N")
	)
	(segment
		(start 350.463866 -25.17902)
		(end 350.463866 -24.73706)
		(width 0.14732)
		(layer "B.Cu")
		(net "ENET1G_3_MDI2N")
	)
	(segment
		(start 350.463866 -23.98014)
		(end 350.463866 -23.53818)
		(width 0.14732)
		(layer "B.Cu")
		(net "ENET1G_3_MDI2N")
	)
	(segment
		(start 350.6216 -21.73986)
		(end 350.463866 -21.58238)
		(width 0.14732)
		(layer "B.Cu")
		(net "ENET1G_3_MDI2N")
	)
	(segment
		(start 350.6216 -24.13762)
		(end 350.463866 -23.98014)
		(width 0.14732)
		(layer "B.Cu")
		(net "ENET1G_3_MDI2N")
	)
	(segment
		(start 344.730832 -37.51707)
		(end 344.820494 -37.606732)
		(width 0.14732)
		(layer "B.Cu")
		(net "ENET1G_3_MDI2N")
	)
	(segment
		(start 350.463866 -21.58238)
		(end 350.463866 -18.460466)
		(width 0.14732)
		(layer "B.Cu")
		(net "ENET1G_3_MDI2N")
	)
	(segment
		(start 350.6216 -22.93874)
		(end 350.463866 -22.78126)
		(width 0.14732)
		(layer "B.Cu")
		(net "ENET1G_3_MDI2N")
	)
	(segment
		(start 346.6084 -36.8046)
		(end 346.6084 -35.2806)
		(width 0.14732)
		(layer "B.Cu")
		(net "ENET1G_3_MDI2N")
	)
	(segment
		(start 342.351614 -6.847586)
		(end 342.793066 -7.289038)
		(width 0.14732)
		(layer "B.Cu")
		(net "ENET1G_4_MDI2P")
	)
	(segment
		(start 346.4052 -27.0764)
		(end 346.4052 -30.4546)
		(width 0.14732)
		(layer "B.Cu")
		(net "ENET1G_4_MDI2P")
	)
	(segment
		(start 345.7956 -31.0642)
		(end 344.877898 -31.0642)
		(width 0.14732)
		(layer "B.Cu")
		(net "ENET1G_4_MDI2P")
	)
	(segment
		(start 344.877898 -31.0642)
		(end 344.730832 -30.917134)
		(width 0.14732)
		(layer "B.Cu")
		(net "ENET1G_4_MDI2P")
	)
	(segment
		(start 341.530178 -6.722364)
		(end 341.6554 -6.847586)
		(width 0.14732)
		(layer "B.Cu")
		(net "ENET1G_4_MDI2P")
	)
	(segment
		(start 341.6554 -6.847586)
		(end 342.351614 -6.847586)
		(width 0.14732)
		(layer "B.Cu")
		(net "ENET1G_4_MDI2P")
	)
	(segment
		(start 346.4052 -30.4546)
		(end 345.7956 -31.0642)
		(width 0.14732)
		(layer "B.Cu")
		(net "ENET1G_4_MDI2P")
	)
	(segment
		(start 344.401394 -30.91688)
		(end 343.900252 -31.919164)
		(width 0.14732)
		(layer "B.Cu")
		(net "ENET1G_4_MDI2P")
	)
	(segment
		(start 342.793066 -7.289038)
		(end 342.793066 -23.464266)
		(width 0.14732)
		(layer "B.Cu")
		(net "ENET1G_4_MDI2P")
	)
	(segment
		(start 344.730832 -30.917134)
		(end 344.599006 -30.851348)
		(width 0.14732)
		(layer "B.Cu")
		(net "ENET1G_4_MDI2P")
	)
	(segment
		(start 342.793066 -23.464266)
		(end 346.4052 -27.0764)
		(width 0.14732)
		(layer "B.Cu")
		(net "ENET1G_4_MDI2P")
	)
	(segment
		(start 344.599006 -30.851348)
		(end 344.401394 -30.91688)
		(width 0.14732)
		(layer "B.Cu")
		(net "ENET1G_4_MDI2P")
	)
	(segment
		(start 341.530178 -6.299962)
		(end 341.530178 -6.722364)
		(width 0.14732)
		(layer "B.Cu")
		(net "ENET1G_4_MDI2P")
	)
	(segment
		(start 122.6947 -35.9791)
		(end 123.7996 -34.8742)
		(width 0.1524)
		(layer "In5.Cu")
		(net "ENET1G_1_MDI1N")
	)
	(segment
		(start 126.4793 -31.296102)
		(end 125.349 -30.165802)
		(width 0.1524)
		(layer "In5.Cu")
		(net "ENET1G_1_MDI1N")
	)
	(segment
		(start 127.179324 -8.503158)
		(end 126.6698 -8.503158)
		(width 0.1524)
		(layer "In5.Cu")
		(net "ENET1G_1_MDI1N")
	)
	(segment
		(start 125.349 -30.165802)
		(end 125.349 -27.644598)
		(width 0.1524)
		(layer "In5.Cu")
		(net "ENET1G_1_MDI1N")
	)
	(segment
		(start 126.6698 -8.503158)
		(end 126.5301 -8.642858)
		(width 0.1524)
		(layer "In5.Cu")
		(net "ENET1G_1_MDI1N")
	)
	(segment
		(start 126.5301 -8.642858)
		(end 126.5301 -8.999982)
		(width 0.1524)
		(layer "In5.Cu")
		(net "ENET1G_1_MDI1N")
	)
	(segment
		(start 124.977398 -34.8742)
		(end 126.4793 -33.372298)
		(width 0.1524)
		(layer "In5.Cu")
		(net "ENET1G_1_MDI1N")
	)
	(segment
		(start 123.7996 -34.8742)
		(end 124.977398 -34.8742)
		(width 0.1524)
		(layer "In5.Cu")
		(net "ENET1G_1_MDI1N")
	)
	(segment
		(start 126.4793 -33.372298)
		(end 126.4793 -31.296102)
		(width 0.1524)
		(layer "In5.Cu")
		(net "ENET1G_1_MDI1N")
	)
	(segment
		(start 127 -21.802598)
		(end 127.4318 -21.370798)
		(width 0.1524)
		(layer "In5.Cu")
		(net "ENET1G_1_MDI1N")
	)
	(segment
		(start 125.349 -27.644598)
		(end 127 -25.993598)
		(width 0.1524)
		(layer "In5.Cu")
		(net "ENET1G_1_MDI1N")
	)
	(segment
		(start 127 -25.993598)
		(end 127 -21.802598)
		(width 0.1524)
		(layer "In5.Cu")
		(net "ENET1G_1_MDI1N")
	)
	(segment
		(start 127.4318 -8.755634)
		(end 127.179324 -8.503158)
		(width 0.1524)
		(layer "In5.Cu")
		(net "ENET1G_1_MDI1N")
	)
	(segment
		(start 127.4318 -21.370798)
		(end 127.4318 -8.755634)
		(width 0.1524)
		(layer "In5.Cu")
		(net "ENET1G_1_MDI1N")
	)
	(segment
		(start 121.630186 -35.9791)
		(end 122.6947 -35.9791)
		(width 0.1524)
		(layer "In5.Cu")
		(net "ENET1G_1_MDI1N")
	)
	(segment
		(start 397.284956 -29.50083)
		(end 397.284956 -28.4099)
		(width 0.1778)
		(layer "F.Cu")
		(net "SAS_BLAD2_RX5_P")
	)
	(segment
		(start 397.060166 -30.53588)
		(end 397.060166 -29.72562)
		(width 0.1778)
		(layer "F.Cu")
		(net "SAS_BLAD2_RX5_P")
	)
	(segment
		(start 397.519906 -30.99562)
		(end 397.060166 -30.53588)
		(width 0.1778)
		(layer "F.Cu")
		(net "SAS_BLAD2_RX5_P")
	)
	(segment
		(start 397.060166 -29.72562)
		(end 397.284956 -29.50083)
		(width 0.1778)
		(layer "F.Cu")
		(net "SAS_BLAD2_RX5_P")
	)
	(via
		(at 397.519906 -30.99562)
		(size 0.508)
		(drill 0.254)
		(layers "F.Cu" "B.Cu")
		(net "SAS_BLAD2_RX5_P")
	)
	(segment
		(start 389.430768 -12.296902)
		(end 389.703564 -12.296902)
		(width 0.1524)
		(layer "In5.Cu")
		(net "SAS_BLAD2_RX5_P")
	)
	(segment
		(start 396.939516 -32.11195)
		(end 396.76451 -32.286956)
		(width 0.1524)
		(layer "In5.Cu")
		(net "SAS_BLAD2_RX5_P")
	)
	(segment
		(start 394.757148 -23.354284)
		(end 391.575036 -20.172172)
		(width 0.1524)
		(layer "In5.Cu")
		(net "SAS_BLAD2_RX5_P")
	)
	(segment
		(start 394.673582 -25.497028)
		(end 394.757148 -25.413716)
		(width 0.1524)
		(layer "In5.Cu")
		(net "SAS_BLAD2_RX5_P")
	)
	(segment
		(start 397.08836 -31.427166)
		(end 397.08836 -31.752794)
		(width 0.1524)
		(layer "In5.Cu")
		(net "SAS_BLAD2_RX5_P")
	)
	(segment
		(start 388.87146 -12.52855)
		(end 388.871968 -12.528042)
		(width 0.1524)
		(layer "In5.Cu")
		(net "SAS_BLAD2_RX5_P")
	)
	(segment
		(start 397.519906 -30.99562)
		(end 397.08836 -31.427166)
		(width 0.1524)
		(layer "In5.Cu")
		(net "SAS_BLAD2_RX5_P")
	)
	(segment
		(start 388.640066 -14.623288)
		(end 388.640066 -13.088112)
		(width 0.1524)
		(layer "In5.Cu")
		(net "SAS_BLAD2_RX5_P")
	)
	(segment
		(start 389.89 -12.110466)
		(end 389.89 -11.800078)
		(width 0.1524)
		(layer "In5.Cu")
		(net "SAS_BLAD2_RX5_P")
	)
	(segment
		(start 396.405354 -32.4358)
		(end 396.089378 -32.4358)
		(width 0.1524)
		(layer "In5.Cu")
		(net "SAS_BLAD2_RX5_P")
	)
	(segment
		(start 391.307066 -19.525488)
		(end 391.307066 -17.710912)
		(width 0.1524)
		(layer "In5.Cu")
		(net "SAS_BLAD2_RX5_P")
	)
	(segment
		(start 395.729968 -32.286956)
		(end 395.15161 -31.708598)
		(width 0.1524)
		(layer "In5.Cu")
		(net "SAS_BLAD2_RX5_P")
	)
	(segment
		(start 394.786866 -25.342088)
		(end 394.786866 -23.425912)
		(width 0.1524)
		(layer "In5.Cu")
		(net "SAS_BLAD2_RX5_P")
	)
	(segment
		(start 395.15161 -31.708598)
		(end 394.564108 -31.120334)
		(width 0.1524)
		(layer "In5.Cu")
		(net "SAS_BLAD2_RX5_P")
	)
	(segment
		(start 394.405866 -30.752034)
		(end 394.405866 -26.143712)
		(width 0.1524)
		(layer "In5.Cu")
		(net "SAS_BLAD2_RX5_P")
	)
	(segment
		(start 389.703564 -12.296902)
		(end 389.89 -12.110466)
		(width 0.1524)
		(layer "In5.Cu")
		(net "SAS_BLAD2_RX5_P")
	)
	(segment
		(start 391.277348 -17.639284)
		(end 388.908036 -15.269972)
		(width 0.1524)
		(layer "In5.Cu")
		(net "SAS_BLAD2_RX5_P")
	)
	(arc
		(start 394.405866 -26.143712)
		(mid 394.475403 -25.793747)
		(end 394.673582 -25.497028)
		(width 0.1524)
		(layer "In5.Cu")
		(net "SAS_BLAD2_RX5_P")
	)
	(arc
		(start 397.08836 -31.752794)
		(mid 397.049676 -31.947183)
		(end 396.939516 -32.11195)
		(width 0.1524)
		(layer "In5.Cu")
		(net "SAS_BLAD2_RX5_P")
	)
	(arc
		(start 388.640066 -13.088112)
		(mid 388.700108 -12.785319)
		(end 388.87146 -12.52855)
		(width 0.1524)
		(layer "In5.Cu")
		(net "SAS_BLAD2_RX5_P")
	)
	(arc
		(start 394.757148 -25.413716)
		(mid 394.77916 -25.380867)
		(end 394.786866 -25.342088)
		(width 0.1524)
		(layer "In5.Cu")
		(net "SAS_BLAD2_RX5_P")
	)
	(arc
		(start 391.307066 -17.710912)
		(mid 391.299336 -17.672143)
		(end 391.277348 -17.639284)
		(width 0.1524)
		(layer "In5.Cu")
		(net "SAS_BLAD2_RX5_P")
	)
	(arc
		(start 396.089378 -32.4358)
		(mid 395.894838 -32.397179)
		(end 395.729968 -32.286956)
		(width 0.1524)
		(layer "In5.Cu")
		(net "SAS_BLAD2_RX5_P")
	)
	(arc
		(start 388.908036 -15.269972)
		(mid 388.709733 -14.973285)
		(end 388.640066 -14.623288)
		(width 0.1524)
		(layer "In5.Cu")
		(net "SAS_BLAD2_RX5_P")
	)
	(arc
		(start 388.871968 -12.528042)
		(mid 389.128404 -12.356949)
		(end 389.430768 -12.296902)
		(width 0.1524)
		(layer "In5.Cu")
		(net "SAS_BLAD2_RX5_P")
	)
	(arc
		(start 394.564108 -31.120334)
		(mid 394.447107 -30.95246)
		(end 394.405866 -30.752034)
		(width 0.1524)
		(layer "In5.Cu")
		(net "SAS_BLAD2_RX5_P")
	)
	(arc
		(start 391.575036 -20.172172)
		(mid 391.376733 -19.875485)
		(end 391.307066 -19.525488)
		(width 0.1524)
		(layer "In5.Cu")
		(net "SAS_BLAD2_RX5_P")
	)
	(arc
		(start 396.76451 -32.286956)
		(mid 396.599742 -32.397114)
		(end 396.405354 -32.4358)
		(width 0.1524)
		(layer "In5.Cu")
		(net "SAS_BLAD2_RX5_P")
	)
	(arc
		(start 394.786866 -23.425912)
		(mid 394.779136 -23.387143)
		(end 394.757148 -23.354284)
		(width 0.1524)
		(layer "In5.Cu")
		(net "SAS_BLAD2_RX5_P")
	)
	(segment
		(start 127.4064 -26.162)
		(end 127.4064 -21.971)
		(width 0.1524)
		(layer "In5.Cu")
		(net "ENET1G_1_MDI1P")
	)
	(segment
		(start 125.7554 -27.813)
		(end 127.4064 -26.162)
		(width 0.1524)
		(layer "In5.Cu")
		(net "ENET1G_1_MDI1P")
	)
	(segment
		(start 125.440186 -34.986214)
		(end 126.8857 -33.5407)
		(width 0.1524)
		(layer "In5.Cu")
		(net "ENET1G_1_MDI1P")
	)
	(segment
		(start 127.347726 -8.096758)
		(end 126.6698 -8.096758)
		(width 0.1524)
		(layer "In5.Cu")
		(net "ENET1G_1_MDI1P")
	)
	(segment
		(start 127.8382 -21.5392)
		(end 127.8382 -8.587232)
		(width 0.1524)
		(layer "In5.Cu")
		(net "ENET1G_1_MDI1P")
	)
	(segment
		(start 125.7554 -29.9974)
		(end 125.7554 -27.813)
		(width 0.1524)
		(layer "In5.Cu")
		(net "ENET1G_1_MDI1P")
	)
	(segment
		(start 127.8382 -8.587232)
		(end 127.347726 -8.096758)
		(width 0.1524)
		(layer "In5.Cu")
		(net "ENET1G_1_MDI1P")
	)
	(segment
		(start 126.8857 -33.5407)
		(end 126.8857 -31.1277)
		(width 0.1524)
		(layer "In5.Cu")
		(net "ENET1G_1_MDI1P")
	)
	(segment
		(start 125.440186 -38.5191)
		(end 125.440186 -34.986214)
		(width 0.1524)
		(layer "In5.Cu")
		(net "ENET1G_1_MDI1P")
	)
	(segment
		(start 126.5301 -7.957058)
		(end 126.5301 -7.600188)
		(width 0.1524)
		(layer "In5.Cu")
		(net "ENET1G_1_MDI1P")
	)
	(segment
		(start 126.8857 -31.1277)
		(end 125.7554 -29.9974)
		(width 0.1524)
		(layer "In5.Cu")
		(net "ENET1G_1_MDI1P")
	)
	(segment
		(start 127.4064 -21.971)
		(end 127.8382 -21.5392)
		(width 0.1524)
		(layer "In5.Cu")
		(net "ENET1G_1_MDI1P")
	)
	(segment
		(start 126.6698 -8.096758)
		(end 126.5301 -7.957058)
		(width 0.1524)
		(layer "In5.Cu")
		(net "ENET1G_1_MDI1P")
	)
	(segment
		(start 391.909554 -29.72562)
		(end 391.909554 -31.52648)
		(width 0.1778)
		(layer "F.Cu")
		(net "SAS_BLAD2_RX7_N")
	)
	(segment
		(start 391.909554 -31.52648)
		(end 391.449814 -31.98622)
		(width 0.1778)
		(layer "F.Cu")
		(net "SAS_BLAD2_RX7_N")
	)
	(segment
		(start 391.684764 -29.50083)
		(end 391.909554 -29.72562)
		(width 0.1778)
		(layer "F.Cu")
		(net "SAS_BLAD2_RX7_N")
	)
	(segment
		(start 391.684764 -28.4099)
		(end 391.684764 -29.50083)
		(width 0.1778)
		(layer "F.Cu")
		(net "SAS_BLAD2_RX7_N")
	)
	(via
		(at 391.449814 -31.98622)
		(size 0.508)
		(drill 0.254)
		(layers "F.Cu" "B.Cu")
		(net "SAS_BLAD2_RX7_N")
	)
	(segment
		(start 385.220464 -16.875506)
		(end 384.957574 -16.875506)
		(width 0.1524)
		(layer "In5.Cu")
		(net "SAS_BLAD2_RX7_N")
	)
	(segment
		(start 385.54406 -17.199102)
		(end 385.220464 -16.875506)
		(width 0.1524)
		(layer "In5.Cu")
		(net "SAS_BLAD2_RX7_N")
	)
	(segment
		(start 385.867402 -17.785334)
		(end 385.543552 -17.461484)
		(width 0.1524)
		(layer "In5.Cu")
		(net "SAS_BLAD2_RX7_N")
	)
	(segment
		(start 389.044942 -20.699984)
		(end 388.721092 -20.376134)
		(width 0.1524)
		(layer "In5.Cu")
		(net "SAS_BLAD2_RX7_N")
	)
	(segment
		(start 386.453888 -18.10893)
		(end 386.130292 -17.785334)
		(width 0.1524)
		(layer "In5.Cu")
		(net "SAS_BLAD2_RX7_N")
	)
	(segment
		(start 389.36803 -21.285962)
		(end 389.044434 -20.962366)
		(width 0.1524)
		(layer "In5.Cu")
		(net "SAS_BLAD2_RX7_N")
	)
	(segment
		(start 389.954262 -21.872194)
		(end 389.954262 -21.74113)
		(width 0.1524)
		(layer "In5.Cu")
		(net "SAS_BLAD2_RX7_N")
	)
	(segment
		(start 389.044434 -20.962366)
		(end 389.044434 -20.831302)
		(width 0.1524)
		(layer "In5.Cu")
		(net "SAS_BLAD2_RX7_N")
	)
	(segment
		(start 391.85215 -32.839914)
		(end 391.727182 -32.964882)
		(width 0.1524)
		(layer "In5.Cu")
		(net "SAS_BLAD2_RX7_N")
	)
	(segment
		(start 384.942842 -12.703302)
		(end 385.696968 -12.703302)
		(width 0.1524)
		(layer "In5.Cu")
		(net "SAS_BLAD2_RX7_N")
	)
	(segment
		(start 389.24357 -27.036522)
		(end 389.24357 -26.803096)
		(width 0.1524)
		(layer "In5.Cu")
		(net "SAS_BLAD2_RX7_N")
	)
	(segment
		(start 390.443466 -25.392888)
		(end 390.443466 -22.740112)
		(width 0.1524)
		(layer "In5.Cu")
		(net "SAS_BLAD2_RX7_N")
	)
	(segment
		(start 387.64591 -28.400756)
		(end 388.686802 -27.359864)
		(width 0.1524)
		(layer "In5.Cu")
		(net "SAS_BLAD2_RX7_N")
	)
	(segment
		(start 389.044434 -20.831302)
		(end 389.044942 -20.699984)
		(width 0.1524)
		(layer "In5.Cu")
		(net "SAS_BLAD2_RX7_N")
	)
	(segment
		(start 389.95477 -21.609812)
		(end 389.63092 -21.285962)
		(width 0.1524)
		(layer "In5.Cu")
		(net "SAS_BLAD2_RX7_N")
	)
	(segment
		(start 391.655554 -32.9946)
		(end 390.247378 -32.9946)
		(width 0.1524)
		(layer "In5.Cu")
		(net "SAS_BLAD2_RX7_N")
	)
	(segment
		(start 388.458202 -20.376134)
		(end 386.45338 -18.371312)
		(width 0.1524)
		(layer "In5.Cu")
		(net "SAS_BLAD2_RX7_N")
	)
	(segment
		(start 387.497066 -30.244288)
		(end 387.497066 -28.759912)
		(width 0.1524)
		(layer "In5.Cu")
		(net "SAS_BLAD2_RX7_N")
	)
	(segment
		(start 386.130292 -17.785334)
		(end 385.867402 -17.785334)
		(width 0.1524)
		(layer "In5.Cu")
		(net "SAS_BLAD2_RX7_N")
	)
	(segment
		(start 385.890008 -12.896342)
		(end 385.890008 -13.200126)
		(width 0.1524)
		(layer "In5.Cu")
		(net "SAS_BLAD2_RX7_N")
	)
	(segment
		(start 389.63092 -21.285962)
		(end 389.36803 -21.285962)
		(width 0.1524)
		(layer "In5.Cu")
		(net "SAS_BLAD2_RX7_N")
	)
	(segment
		(start 389.888222 -32.845756)
		(end 387.64591 -30.603444)
		(width 0.1524)
		(layer "In5.Cu")
		(net "SAS_BLAD2_RX7_N")
	)
	(segment
		(start 385.543552 -17.461484)
		(end 385.54406 -17.330166)
		(width 0.1524)
		(layer "In5.Cu")
		(net "SAS_BLAD2_RX7_N")
	)
	(segment
		(start 388.721092 -20.376134)
		(end 388.458202 -20.376134)
		(width 0.1524)
		(layer "In5.Cu")
		(net "SAS_BLAD2_RX7_N")
	)
	(segment
		(start 388.91972 -27.360372)
		(end 389.24357 -27.036522)
		(width 0.1524)
		(layer "In5.Cu")
		(net "SAS_BLAD2_RX7_N")
	)
	(segment
		(start 386.453888 -18.239994)
		(end 386.453888 -18.10893)
		(width 0.1524)
		(layer "In5.Cu")
		(net "SAS_BLAD2_RX7_N")
	)
	(segment
		(start 391.881868 -32.418274)
		(end 391.881868 -32.768286)
		(width 0.1524)
		(layer "In5.Cu")
		(net "SAS_BLAD2_RX7_N")
	)
	(segment
		(start 388.803134 -27.359864)
		(end 388.91972 -27.360372)
		(width 0.1524)
		(layer "In5.Cu")
		(net "SAS_BLAD2_RX7_N")
	)
	(segment
		(start 389.24357 -26.803096)
		(end 390.294622 -25.752044)
		(width 0.1524)
		(layer "In5.Cu")
		(net "SAS_BLAD2_RX7_N")
	)
	(segment
		(start 384.957574 -16.875506)
		(end 384.75031 -16.668242)
		(width 0.1524)
		(layer "In5.Cu")
		(net "SAS_BLAD2_RX7_N")
	)
	(segment
		(start 385.696968 -12.703302)
		(end 385.890008 -12.896342)
		(width 0.1524)
		(layer "In5.Cu")
		(net "SAS_BLAD2_RX7_N")
	)
	(segment
		(start 388.686802 -27.359864)
		(end 388.803134 -27.359864)
		(width 0.1524)
		(layer "In5.Cu")
		(net "SAS_BLAD2_RX7_N")
	)
	(segment
		(start 386.45338 -18.371312)
		(end 386.453888 -18.239994)
		(width 0.1524)
		(layer "In5.Cu")
		(net "SAS_BLAD2_RX7_N")
	)
	(segment
		(start 384.601466 -16.309086)
		(end 384.601466 -13.044424)
		(width 0.1524)
		(layer "In5.Cu")
		(net "SAS_BLAD2_RX7_N")
	)
	(segment
		(start 391.449814 -31.98622)
		(end 391.881868 -32.418274)
		(width 0.1524)
		(layer "In5.Cu")
		(net "SAS_BLAD2_RX7_N")
	)
	(segment
		(start 390.175496 -22.093428)
		(end 389.954262 -21.872194)
		(width 0.1524)
		(layer "In5.Cu")
		(net "SAS_BLAD2_RX7_N")
	)
	(segment
		(start 389.954262 -21.74113)
		(end 389.95477 -21.609812)
		(width 0.1524)
		(layer "In5.Cu")
		(net "SAS_BLAD2_RX7_N")
	)
	(segment
		(start 385.54406 -17.330166)
		(end 385.54406 -17.199102)
		(width 0.1524)
		(layer "In5.Cu")
		(net "SAS_BLAD2_RX7_N")
	)
	(arc
		(start 387.64591 -30.603444)
		(mid 387.535752 -30.438676)
		(end 387.497066 -30.244288)
		(width 0.1524)
		(layer "In5.Cu")
		(net "SAS_BLAD2_RX7_N")
	)
	(arc
		(start 387.497066 -28.759912)
		(mid 387.53575 -28.565523)
		(end 387.64591 -28.400756)
		(width 0.1524)
		(layer "In5.Cu")
		(net "SAS_BLAD2_RX7_N")
	)
	(arc
		(start 384.701288 -12.803378)
		(mid 384.812114 -12.729326)
		(end 384.942842 -12.703302)
		(width 0.1524)
		(layer "In5.Cu")
		(net "SAS_BLAD2_RX7_N")
	)
	(arc
		(start 384.75031 -16.668242)
		(mid 384.640152 -16.503474)
		(end 384.601466 -16.309086)
		(width 0.1524)
		(layer "In5.Cu")
		(net "SAS_BLAD2_RX7_N")
	)
	(arc
		(start 390.294622 -25.752044)
		(mid 390.40478 -25.587276)
		(end 390.443466 -25.392888)
		(width 0.1524)
		(layer "In5.Cu")
		(net "SAS_BLAD2_RX7_N")
	)
	(arc
		(start 391.727182 -32.964882)
		(mid 391.694333 -32.986894)
		(end 391.655554 -32.9946)
		(width 0.1524)
		(layer "In5.Cu")
		(net "SAS_BLAD2_RX7_N")
	)
	(arc
		(start 390.247378 -32.9946)
		(mid 390.052989 -32.955916)
		(end 389.888222 -32.845756)
		(width 0.1524)
		(layer "In5.Cu")
		(net "SAS_BLAD2_RX7_N")
	)
	(arc
		(start 384.601466 -13.044424)
		(mid 384.627413 -12.913979)
		(end 384.701288 -12.803378)
		(width 0.1524)
		(layer "In5.Cu")
		(net "SAS_BLAD2_RX7_N")
	)
	(arc
		(start 391.881868 -32.768286)
		(mid 391.874138 -32.807055)
		(end 391.85215 -32.839914)
		(width 0.1524)
		(layer "In5.Cu")
		(net "SAS_BLAD2_RX7_N")
	)
	(arc
		(start 390.443466 -22.740112)
		(mid 390.373827 -22.390103)
		(end 390.175496 -22.093428)
		(width 0.1524)
		(layer "In5.Cu")
		(net "SAS_BLAD2_RX7_N")
	)
	(segment
		(start 344.7288 -14.3256)
		(end 344.7288 -3.302)
		(width 0.1524)
		(layer "In2.Cu")
		(net "ENET1G_3_MDI3N")
	)
	(segment
		(start 350.667066 -33.7058)
		(end 350.667066 -29.620464)
		(width 0.1524)
		(layer "In2.Cu")
		(net "ENET1G_3_MDI3N")
	)
	(segment
		(start 340.565994 -36.930838)
		(end 340.497668 -37.135308)
		(width 0.1524)
		(layer "In2.Cu")
		(net "ENET1G_3_MDI3N")
	)
	(segment
		(start 340.090252 -35.9791)
		(end 340.565994 -36.930838)
		(width 0.1524)
		(layer "In2.Cu")
		(net "ENET1G_3_MDI3N")
	)
	(segment
		(start 340.497668 -37.135308)
		(end 340.496906 -37.135816)
		(width 0.1524)
		(layer "In2.Cu")
		(net "ENET1G_3_MDI3N")
	)
	(segment
		(start 340.447376 -37.160454)
		(end 340.318344 -37.160454)
		(width 0.1524)
		(layer "In2.Cu")
		(net "ENET1G_3_MDI3N")
	)
	(segment
		(start 345.53017 -3.16357)
		(end 345.53017 -3.50012)
		(width 0.1524)
		(layer "In2.Cu")
		(net "ENET1G_3_MDI3N")
	)
	(segment
		(start 345.027504 -3.003296)
		(end 345.369896 -3.003296)
		(width 0.1524)
		(layer "In2.Cu")
		(net "ENET1G_3_MDI3N")
	)
	(segment
		(start 340.7918 -40.1828)
		(end 349.651066 -40.1828)
		(width 0.1524)
		(layer "In2.Cu")
		(net "ENET1G_3_MDI3N")
	)
	(segment
		(start 345.369896 -3.003296)
		(end 345.53017 -3.16357)
		(width 0.1524)
		(layer "In2.Cu")
		(net "ENET1G_3_MDI3N")
	)
	(segment
		(start 350.667066 -29.620464)
		(end 346.71 -25.663398)
		(width 0.1524)
		(layer "In2.Cu")
		(net "ENET1G_3_MDI3N")
	)
	(segment
		(start 340.496906 -37.135816)
		(end 340.447376 -37.160454)
		(width 0.1524)
		(layer "In2.Cu")
		(net "ENET1G_3_MDI3N")
	)
	(segment
		(start 339.7758 -39.1668)
		(end 340.7918 -40.1828)
		(width 0.1524)
		(layer "In2.Cu")
		(net "ENET1G_3_MDI3N")
	)
	(segment
		(start 339.7758 -37.702998)
		(end 339.7758 -39.1668)
		(width 0.1524)
		(layer "In2.Cu")
		(net "ENET1G_3_MDI3N")
	)
	(segment
		(start 350.413066 -39.4208)
		(end 350.413066 -33.9598)
		(width 0.1524)
		(layer "In2.Cu")
		(net "ENET1G_3_MDI3N")
	)
	(segment
		(start 346.71 -16.3068)
		(end 344.7288 -14.3256)
		(width 0.1524)
		(layer "In2.Cu")
		(net "ENET1G_3_MDI3N")
	)
	(segment
		(start 340.318344 -37.160454)
		(end 339.7758 -37.702998)
		(width 0.1524)
		(layer "In2.Cu")
		(net "ENET1G_3_MDI3N")
	)
	(segment
		(start 346.71 -25.663398)
		(end 346.71 -16.3068)
		(width 0.1524)
		(layer "In2.Cu")
		(net "ENET1G_3_MDI3N")
	)
	(segment
		(start 344.7288 -3.302)
		(end 345.027504 -3.003296)
		(width 0.1524)
		(layer "In2.Cu")
		(net "ENET1G_3_MDI3N")
	)
	(segment
		(start 350.413066 -33.9598)
		(end 350.667066 -33.7058)
		(width 0.1524)
		(layer "In2.Cu")
		(net "ENET1G_3_MDI3N")
	)
	(segment
		(start 349.651066 -40.1828)
		(end 350.413066 -39.4208)
		(width 0.1524)
		(layer "In2.Cu")
		(net "ENET1G_3_MDI3N")
	)
	(segment
		(start 347.479366 -31.296102)
		(end 347.479366 -33.372298)
		(width 0.1524)
		(layer "In5.Cu")
		(net "ENET1G_3_MDI1N")
	)
	(segment
		(start 347.669866 -8.503158)
		(end 348.17939 -8.503158)
		(width 0.1524)
		(layer "In5.Cu")
		(net "ENET1G_3_MDI1N")
	)
	(segment
		(start 348.17939 -8.503158)
		(end 348.431866 -8.755634)
		(width 0.1524)
		(layer "In5.Cu")
		(net "ENET1G_3_MDI1N")
	)
	(segment
		(start 346.399866 -28.228798)
		(end 346.399866 -30.216602)
		(width 0.1524)
		(layer "In5.Cu")
		(net "ENET1G_3_MDI1N")
	)
	(segment
		(start 346.933266 -21.345398)
		(end 346.933266 -27.695398)
		(width 0.1524)
		(layer "In5.Cu")
		(net "ENET1G_3_MDI1N")
	)
	(segment
		(start 345.977464 -34.8742)
		(end 344.799666 -34.8742)
		(width 0.1524)
		(layer "In5.Cu")
		(net "ENET1G_3_MDI1N")
	)
	(segment
		(start 348.431866 -8.755634)
		(end 348.431866 -19.846798)
		(width 0.1524)
		(layer "In5.Cu")
		(net "ENET1G_3_MDI1N")
	)
	(segment
		(start 346.933266 -27.695398)
		(end 346.399866 -28.228798)
		(width 0.1524)
		(layer "In5.Cu")
		(net "ENET1G_3_MDI1N")
	)
	(segment
		(start 348.431866 -19.846798)
		(end 346.933266 -21.345398)
		(width 0.1524)
		(layer "In5.Cu")
		(net "ENET1G_3_MDI1N")
	)
	(segment
		(start 347.530166 -8.999982)
		(end 347.530166 -8.642858)
		(width 0.1524)
		(layer "In5.Cu")
		(net "ENET1G_3_MDI1N")
	)
	(segment
		(start 346.399866 -30.216602)
		(end 347.479366 -31.296102)
		(width 0.1524)
		(layer "In5.Cu")
		(net "ENET1G_3_MDI1N")
	)
	(segment
		(start 343.694766 -35.9791)
		(end 342.630252 -35.9791)
		(width 0.1524)
		(layer "In5.Cu")
		(net "ENET1G_3_MDI1N")
	)
	(segment
		(start 347.479366 -33.372298)
		(end 345.977464 -34.8742)
		(width 0.1524)
		(layer "In5.Cu")
		(net "ENET1G_3_MDI1N")
	)
	(segment
		(start 347.530166 -8.642858)
		(end 347.669866 -8.503158)
		(width 0.1524)
		(layer "In5.Cu")
		(net "ENET1G_3_MDI1N")
	)
	(segment
		(start 344.799666 -34.8742)
		(end 343.694766 -35.9791)
		(width 0.1524)
		(layer "In5.Cu")
		(net "ENET1G_3_MDI1N")
	)
	(segment
		(start 144.690084 -8.952992)
		(end 144.690084 -10.290048)
		(width 0.24384)
		(layer "F.Cu")
		(net "ENET10G_1_TDP")
	)
	(segment
		(start 144.790414 -6.05028)
		(end 144.790414 -8.852662)
		(width 0.24384)
		(layer "F.Cu")
		(net "ENET10G_1_TDP")
	)
	(segment
		(start 144.455134 -5.715)
		(end 144.790414 -6.05028)
		(width 0.24384)
		(layer "F.Cu")
		(net "ENET10G_1_TDP")
	)
	(segment
		(start 144.790414 -8.852662)
		(end 144.690084 -8.952992)
		(width 0.24384)
		(layer "F.Cu")
		(net "ENET10G_1_TDP")
	)
	(via
		(at 144.455134 -5.715)
		(size 0.508)
		(drill 0.254)
		(layers "F.Cu" "B.Cu")
		(net "ENET10G_1_TDP")
	)
	(segment
		(start 130.144012 -10.90041)
		(end 128.9304 -10.90041)
		(width 0.24384)
		(layer "B.Cu")
		(net "ENET10G_1_TDP")
	)
	(segment
		(start 131.23672 -9.586214)
		(end 130.991864 -9.83107)
		(width 0.24384)
		(layer "B.Cu")
		(net "ENET10G_1_TDP")
	)
	(segment
		(start 134.590028 -6.454394)
		(end 134.553452 -6.454394)
		(width 0.24384)
		(layer "B.Cu")
		(net "ENET10G_1_TDP")
	)
	(segment
		(start 141.34211 -5.715)
		(end 140.95349 -5.715)
		(width 0.24384)
		(layer "B.Cu")
		(net "ENET10G_1_TDP")
	)
	(segment
		(start 144.71904 -6.756908)
		(end 144.653762 -6.822186)
		(width 0.24384)
		(layer "B.Cu")
		(net "ENET10G_1_TDP")
	)
	(segment
		(start 128.9304 -10.90041)
		(end 128.530096 -10.500106)
		(width 0.24384)
		(layer "B.Cu")
		(net "ENET10G_1_TDP")
	)
	(segment
		(start 134.194296 -6.603238)
		(end 133.97484 -6.822694)
		(width 0.24384)
		(layer "B.Cu")
		(net "ENET10G_1_TDP")
	)
	(segment
		(start 139.23391 -5.715)
		(end 138.84529 -5.715)
		(width 0.24384)
		(layer "B.Cu")
		(net "ENET10G_1_TDP")
	)
	(segment
		(start 133.09854 -7.945882)
		(end 133.036564 -7.945882)
		(width 0.24384)
		(layer "B.Cu")
		(net "ENET10G_1_TDP")
	)
	(segment
		(start 142.401036 -5.97916)
		(end 141.97965 -5.97916)
		(width 0.24384)
		(layer "B.Cu")
		(net "ENET10G_1_TDP")
	)
	(segment
		(start 132.185664 -9.06907)
		(end 131.966208 -9.288526)
		(width 0.24384)
		(layer "B.Cu")
		(net "ENET10G_1_TDP")
	)
	(segment
		(start 136.46277 -5.853176)
		(end 136.4488 -5.865622)
		(width 0.24384)
		(layer "B.Cu")
		(net "ENET10G_1_TDP")
	)
	(segment
		(start 130.84302 -10.190226)
		(end 130.84302 -10.201402)
		(width 0.24384)
		(layer "B.Cu")
		(net "ENET10G_1_TDP")
	)
	(segment
		(start 135.12673 -6.128004)
		(end 134.949184 -6.30555)
		(width 0.24384)
		(layer "B.Cu")
		(net "ENET10G_1_TDP")
	)
	(segment
		(start 140.31595 -5.97916)
		(end 139.87145 -5.97916)
		(width 0.24384)
		(layer "B.Cu")
		(net "ENET10G_1_TDP")
	)
	(segment
		(start 131.607052 -9.43737)
		(end 131.595876 -9.43737)
		(width 0.24384)
		(layer "B.Cu")
		(net "ENET10G_1_TDP")
	)
	(segment
		(start 132.677408 -8.094726)
		(end 132.483352 -8.288782)
		(width 0.24384)
		(layer "B.Cu")
		(net "ENET10G_1_TDP")
	)
	(segment
		(start 144.481296 -6.89356)
		(end 143.984472 -6.89356)
		(width 0.24384)
		(layer "B.Cu")
		(net "ENET10G_1_TDP")
	)
	(segment
		(start 138.20775 -5.97916)
		(end 137.78865 -5.97916)
		(width 0.24384)
		(layer "B.Cu")
		(net "ENET10G_1_TDP")
	)
	(segment
		(start 133.677152 -7.577582)
		(end 133.457696 -7.797038)
		(width 0.24384)
		(layer "B.Cu")
		(net "ENET10G_1_TDP")
	)
	(segment
		(start 133.825996 -7.18185)
		(end 133.825996 -7.218426)
		(width 0.24384)
		(layer "B.Cu")
		(net "ENET10G_1_TDP")
	)
	(segment
		(start 143.625316 -6.744716)
		(end 143.184118 -6.303518)
		(width 0.24384)
		(layer "B.Cu")
		(net "ENET10G_1_TDP")
	)
	(segment
		(start 132.334508 -8.647938)
		(end 132.334508 -8.709914)
		(width 0.24384)
		(layer "B.Cu")
		(net "ENET10G_1_TDP")
	)
	(segment
		(start 136.15035 -5.97916)
		(end 135.485886 -5.97916)
		(width 0.24384)
		(layer "B.Cu")
		(net "ENET10G_1_TDP")
	)
	(segment
		(start 144.790414 -6.05028)
		(end 144.790414 -6.584442)
		(width 0.24384)
		(layer "B.Cu")
		(net "ENET10G_1_TDP")
	)
	(segment
		(start 144.455134 -5.715)
		(end 144.790414 -6.05028)
		(width 0.24384)
		(layer "B.Cu")
		(net "ENET10G_1_TDP")
	)
	(segment
		(start 137.15111 -5.715)
		(end 136.78789 -5.715)
		(width 0.24384)
		(layer "B.Cu")
		(net "ENET10G_1_TDP")
	)
	(segment
		(start 130.694176 -10.560558)
		(end 130.503168 -10.751566)
		(width 0.24384)
		(layer "B.Cu")
		(net "ENET10G_1_TDP")
	)
	(arc
		(start 133.97484 -6.822694)
		(mid 133.864682 -6.987462)
		(end 133.825996 -7.18185)
		(width 0.24384)
		(layer "B.Cu")
		(net "ENET10G_1_TDP")
	)
	(arc
		(start 133.457696 -7.797038)
		(mid 133.292928 -7.907196)
		(end 133.09854 -7.945882)
		(width 0.24384)
		(layer "B.Cu")
		(net "ENET10G_1_TDP")
	)
	(arc
		(start 136.4488 -5.865622)
		(mid 136.309965 -5.949687)
		(end 136.15035 -5.97916)
		(width 0.24384)
		(layer "B.Cu")
		(net "ENET10G_1_TDP")
	)
	(arc
		(start 134.949184 -6.30555)
		(mid 134.784416 -6.415708)
		(end 134.590028 -6.454394)
		(width 0.24384)
		(layer "B.Cu")
		(net "ENET10G_1_TDP")
	)
	(arc
		(start 130.84302 -10.201402)
		(mid 130.804336 -10.395791)
		(end 130.694176 -10.560558)
		(width 0.24384)
		(layer "B.Cu")
		(net "ENET10G_1_TDP")
	)
	(arc
		(start 130.503168 -10.751566)
		(mid 130.3384 -10.861724)
		(end 130.144012 -10.90041)
		(width 0.24384)
		(layer "B.Cu")
		(net "ENET10G_1_TDP")
	)
	(arc
		(start 138.84529 -5.715)
		(mid 138.672771 -5.749334)
		(end 138.52652 -5.84708)
		(width 0.24384)
		(layer "B.Cu")
		(net "ENET10G_1_TDP")
	)
	(arc
		(start 141.680692 -5.865876)
		(mid 141.670644 -5.856628)
		(end 141.66088 -5.84708)
		(width 0.24384)
		(layer "B.Cu")
		(net "ENET10G_1_TDP")
	)
	(arc
		(start 140.614908 -5.865876)
		(mid 140.475799 -5.94986)
		(end 140.31595 -5.97916)
		(width 0.24384)
		(layer "B.Cu")
		(net "ENET10G_1_TDP")
	)
	(arc
		(start 140.95349 -5.715)
		(mid 140.780971 -5.749334)
		(end 140.63472 -5.84708)
		(width 0.24384)
		(layer "B.Cu")
		(net "ENET10G_1_TDP")
	)
	(arc
		(start 137.78865 -5.97916)
		(mid 137.628765 -5.949954)
		(end 137.489692 -5.865876)
		(width 0.24384)
		(layer "B.Cu")
		(net "ENET10G_1_TDP")
	)
	(arc
		(start 139.55268 -5.84708)
		(mid 139.406441 -5.749303)
		(end 139.23391 -5.715)
		(width 0.24384)
		(layer "B.Cu")
		(net "ENET10G_1_TDP")
	)
	(arc
		(start 143.184118 -6.303518)
		(mid 142.824837 -6.063454)
		(end 142.401036 -5.97916)
		(width 0.24384)
		(layer "B.Cu")
		(net "ENET10G_1_TDP")
	)
	(arc
		(start 131.966208 -9.288526)
		(mid 131.80144 -9.398684)
		(end 131.607052 -9.43737)
		(width 0.24384)
		(layer "B.Cu")
		(net "ENET10G_1_TDP")
	)
	(arc
		(start 144.653762 -6.822186)
		(mid 144.57462 -6.875004)
		(end 144.481296 -6.89356)
		(width 0.24384)
		(layer "B.Cu")
		(net "ENET10G_1_TDP")
	)
	(arc
		(start 137.489692 -5.865876)
		(mid 137.479644 -5.856628)
		(end 137.46988 -5.84708)
		(width 0.24384)
		(layer "B.Cu")
		(net "ENET10G_1_TDP")
	)
	(arc
		(start 130.991864 -9.83107)
		(mid 130.881706 -9.995838)
		(end 130.84302 -10.190226)
		(width 0.24384)
		(layer "B.Cu")
		(net "ENET10G_1_TDP")
	)
	(arc
		(start 138.52652 -5.84708)
		(mid 138.516756 -5.856628)
		(end 138.506708 -5.865876)
		(width 0.24384)
		(layer "B.Cu")
		(net "ENET10G_1_TDP")
	)
	(arc
		(start 144.790414 -6.584442)
		(mid 144.771868 -6.67777)
		(end 144.71904 -6.756908)
		(width 0.24384)
		(layer "B.Cu")
		(net "ENET10G_1_TDP")
	)
	(arc
		(start 133.036564 -7.945882)
		(mid 132.842175 -7.984566)
		(end 132.677408 -8.094726)
		(width 0.24384)
		(layer "B.Cu")
		(net "ENET10G_1_TDP")
	)
	(arc
		(start 131.595876 -9.43737)
		(mid 131.401487 -9.476054)
		(end 131.23672 -9.586214)
		(width 0.24384)
		(layer "B.Cu")
		(net "ENET10G_1_TDP")
	)
	(arc
		(start 134.553452 -6.454394)
		(mid 134.359063 -6.493078)
		(end 134.194296 -6.603238)
		(width 0.24384)
		(layer "B.Cu")
		(net "ENET10G_1_TDP")
	)
	(arc
		(start 138.506708 -5.865876)
		(mid 138.367599 -5.94986)
		(end 138.20775 -5.97916)
		(width 0.24384)
		(layer "B.Cu")
		(net "ENET10G_1_TDP")
	)
	(arc
		(start 132.334508 -8.709914)
		(mid 132.295824 -8.904303)
		(end 132.185664 -9.06907)
		(width 0.24384)
		(layer "B.Cu")
		(net "ENET10G_1_TDP")
	)
	(arc
		(start 139.87145 -5.97916)
		(mid 139.711565 -5.949954)
		(end 139.572492 -5.865876)
		(width 0.24384)
		(layer "B.Cu")
		(net "ENET10G_1_TDP")
	)
	(arc
		(start 132.483352 -8.288782)
		(mid 132.373194 -8.45355)
		(end 132.334508 -8.647938)
		(width 0.24384)
		(layer "B.Cu")
		(net "ENET10G_1_TDP")
	)
	(arc
		(start 139.572492 -5.865876)
		(mid 139.562444 -5.856628)
		(end 139.55268 -5.84708)
		(width 0.24384)
		(layer "B.Cu")
		(net "ENET10G_1_TDP")
	)
	(arc
		(start 136.78789 -5.715)
		(mid 136.615371 -5.749334)
		(end 136.46912 -5.84708)
		(width 0.24384)
		(layer "B.Cu")
		(net "ENET10G_1_TDP")
	)
	(arc
		(start 143.984472 -6.89356)
		(mid 143.790083 -6.854876)
		(end 143.625316 -6.744716)
		(width 0.24384)
		(layer "B.Cu")
		(net "ENET10G_1_TDP")
	)
	(arc
		(start 140.63472 -5.84708)
		(mid 140.624956 -5.856628)
		(end 140.614908 -5.865876)
		(width 0.24384)
		(layer "B.Cu")
		(net "ENET10G_1_TDP")
	)
	(arc
		(start 141.97965 -5.97916)
		(mid 141.819765 -5.949954)
		(end 141.680692 -5.865876)
		(width 0.24384)
		(layer "B.Cu")
		(net "ENET10G_1_TDP")
	)
	(arc
		(start 135.485886 -5.97916)
		(mid 135.291497 -6.017844)
		(end 135.12673 -6.128004)
		(width 0.24384)
		(layer "B.Cu")
		(net "ENET10G_1_TDP")
	)
	(arc
		(start 137.46988 -5.84708)
		(mid 137.323641 -5.749303)
		(end 137.15111 -5.715)
		(width 0.24384)
		(layer "B.Cu")
		(net "ENET10G_1_TDP")
	)
	(arc
		(start 133.825996 -7.218426)
		(mid 133.787312 -7.412815)
		(end 133.677152 -7.577582)
		(width 0.24384)
		(layer "B.Cu")
		(net "ENET10G_1_TDP")
	)
	(arc
		(start 141.66088 -5.84708)
		(mid 141.514641 -5.749303)
		(end 141.34211 -5.715)
		(width 0.24384)
		(layer "B.Cu")
		(net "ENET10G_1_TDP")
	)
	(arc
		(start 136.46912 -5.84708)
		(mid 136.46596 -5.850143)
		(end 136.46277 -5.853176)
		(width 0.24384)
		(layer "B.Cu")
		(net "ENET10G_1_TDP")
	)
	(segment
		(start 145.490184 -8.952992)
		(end 145.389854 -8.852662)
		(width 0.24384)
		(layer "F.Cu")
		(net "ENET10G_1_TDN")
	)
	(segment
		(start 145.490184 -10.290048)
		(end 145.490184 -8.952992)
		(width 0.24384)
		(layer "F.Cu")
		(net "ENET10G_1_TDN")
	)
	(segment
		(start 145.389854 -8.852662)
		(end 145.389854 -6.05028)
		(width 0.24384)
		(layer "F.Cu")
		(net "ENET10G_1_TDN")
	)
	(segment
		(start 145.389854 -6.05028)
		(end 145.725134 -5.715)
		(width 0.24384)
		(layer "F.Cu")
		(net "ENET10G_1_TDN")
	)
	(via
		(at 145.725134 -5.715)
		(size 0.508)
		(drill 0.254)
		(layers "F.Cu" "B.Cu")
		(net "ENET10G_1_TDN")
	)
	(segment
		(start 135.452612 -6.649974)
		(end 130.927094 -11.175492)
		(width 0.24384)
		(layer "B.Cu")
		(net "ENET10G_1_TDN")
	)
	(segment
		(start 144.620488 -7.493)
		(end 143.984472 -7.493)
		(width 0.24384)
		(layer "B.Cu")
		(net "ENET10G_1_TDN")
	)
	(segment
		(start 145.24101 -7.08279)
		(end 144.979644 -7.344156)
		(width 0.24384)
		(layer "B.Cu")
		(net "ENET10G_1_TDN")
	)
	(segment
		(start 145.389854 -6.05028)
		(end 145.389854 -6.723634)
		(width 0.24384)
		(layer "B.Cu")
		(net "ENET10G_1_TDN")
	)
	(segment
		(start 145.725134 -5.715)
		(end 145.389854 -6.05028)
		(width 0.24384)
		(layer "B.Cu")
		(net "ENET10G_1_TDN")
	)
	(segment
		(start 143.20139 -7.168642)
		(end 142.760192 -6.727444)
		(width 0.24384)
		(layer "B.Cu")
		(net "ENET10G_1_TDN")
	)
	(segment
		(start 128.9304 -11.49985)
		(end 128.530096 -11.900154)
		(width 0.24384)
		(layer "B.Cu")
		(net "ENET10G_1_TDN")
	)
	(segment
		(start 142.401036 -6.5786)
		(end 135.625078 -6.5786)
		(width 0.24384)
		(layer "B.Cu")
		(net "ENET10G_1_TDN")
	)
	(segment
		(start 130.144012 -11.49985)
		(end 128.9304 -11.49985)
		(width 0.24384)
		(layer "B.Cu")
		(net "ENET10G_1_TDN")
	)
	(arc
		(start 142.760192 -6.727444)
		(mid 142.595424 -6.617286)
		(end 142.401036 -6.5786)
		(width 0.24384)
		(layer "B.Cu")
		(net "ENET10G_1_TDN")
	)
	(arc
		(start 135.625078 -6.5786)
		(mid 135.53175 -6.597146)
		(end 135.452612 -6.649974)
		(width 0.24384)
		(layer "B.Cu")
		(net "ENET10G_1_TDN")
	)
	(arc
		(start 143.984472 -7.493)
		(mid 143.560673 -7.408701)
		(end 143.20139 -7.168642)
		(width 0.24384)
		(layer "B.Cu")
		(net "ENET10G_1_TDN")
	)
	(arc
		(start 145.389854 -6.723634)
		(mid 145.35117 -6.918023)
		(end 145.24101 -7.08279)
		(width 0.24384)
		(layer "B.Cu")
		(net "ENET10G_1_TDN")
	)
	(arc
		(start 130.927094 -11.175492)
		(mid 130.567813 -11.415556)
		(end 130.144012 -11.49985)
		(width 0.24384)
		(layer "B.Cu")
		(net "ENET10G_1_TDN")
	)
	(arc
		(start 144.979644 -7.344156)
		(mid 144.814876 -7.454314)
		(end 144.620488 -7.493)
		(width 0.24384)
		(layer "B.Cu")
		(net "ENET10G_1_TDN")
	)
	(segment
		(start 407.494994 -28.4099)
		(end 406.915112 -28.4099)
		(width 0.28956)
		(layer "F.Cu")
		(net "GND")
	)
	(segment
		(start 329.370182 -8.923782)
		(end 329.3364 -8.89)
		(width 0.28956)
		(layer "F.Cu")
		(net "GND")
	)
	(segment
		(start 146.290284 -10.290048)
		(end 146.290284 -11.7094)
		(width 0.28956)
		(layer "F.Cu")
		(net "GND")
	)
	(segment
		(start 345.425268 -22.074632)
		(end 345.425268 -22.874732)
		(width 0.4572)
		(layer "F.Cu")
		(net "GND")
	)
	(segment
		(start 139.090146 -10.290048)
		(end 139.090146 -11.7094)
		(width 0.28956)
		(layer "F.Cu")
		(net "GND")
	)
	(segment
		(start 393.68476 -25.899872)
		(end 393.68476 -24.520652)
		(width 0.28956)
		(layer "F.Cu")
		(net "GND")
	)
	(segment
		(start 143.890238 -10.290048)
		(end 143.890238 -11.7094)
		(width 0.28956)
		(layer "F.Cu")
		(net "GND")
	)
	(segment
		(start 328.970132 -18.490184)
		(end 328.970132 -20.106132)
		(width 0.28956)
		(layer "F.Cu")
		(net "GND")
	)
	(segment
		(start 177.48504 -25.899872)
		(end 178.239928 -25.899872)
		(width 0.28956)
		(layer "F.Cu")
		(net "GND")
	)
	(segment
		(start 340.4616 -23.0632)
		(end 340.898734 -23.0632)
		(width 0.4572)
		(layer "F.Cu")
		(net "GND")
	)
	(segment
		(start 141.490192 -10.290048)
		(end 141.490192 -8.927592)
		(width 0.28956)
		(layer "F.Cu")
		(net "GND")
	)
	(segment
		(start 360.090212 -10.289794)
		(end 360.090212 -11.7094)
		(width 0.28956)
		(layer "F.Cu")
		(net "GND")
	)
	(segment
		(start 412.294832 -29.7942)
		(end 412.295086 -29.793946)
		(width 0.28956)
		(layer "F.Cu")
		(net "GND")
	)
	(segment
		(start 123.839732 -22.150832)
		(end 123.839732 -22.696932)
		(width 0.4572)
		(layer "F.Cu")
		(net "GND")
	)
	(segment
		(start 169.4688 -19.2278)
		(end 170.28795 -20.04695)
		(width 0.4572)
		(layer "F.Cu")
		(net "GND")
	)
	(segment
		(start 326.970136 -10.290048)
		(end 326.970136 -8.89)
		(width 0.28956)
		(layer "F.Cu")
		(net "GND")
	)
	(segment
		(start 108.370116 -10.289794)
		(end 108.370116 -8.929116)
		(width 0.28956)
		(layer "F.Cu")
		(net "GND")
	)
	(segment
		(start 412.694882 -24.434038)
		(end 412.694628 -24.433784)
		(width 0.28956)
		(layer "F.Cu")
		(net "GND")
	)
	(segment
		(start 362.490258 -10.289794)
		(end 362.490258 -11.7094)
		(width 0.28956)
		(layer "F.Cu")
		(net "GND")
	)
	(segment
		(start 393.827 -19.177)
		(end 393.688062 -19.315938)
		(width 0.4572)
		(layer "F.Cu")
		(net "GND")
	)
	(segment
		(start 329.370182 -10.290048)
		(end 329.370182 -8.923782)
		(width 0.28956)
		(layer "F.Cu")
		(net "GND")
	)
	(segment
		(start 390.884918 -28.4099)
		(end 390.884918 -29.885894)
		(width 0.28956)
		(layer "F.Cu")
		(net "GND")
	)
	(segment
		(start 191.694816 -25.899872)
		(end 191.694816 -24.433784)
		(width 0.28956)
		(layer "F.Cu")
		(net "GND")
	)
	(segment
		(start 194.4624 -18.9992)
		(end 194.4624 -19.5072)
		(width 0.4572)
		(layer "F.Cu")
		(net "GND")
	)
	(segment
		(start 341.771732 -22.190202)
		(end 341.778844 -22.18309)
		(width 0.4572)
		(layer "F.Cu")
		(net "GND")
	)
	(segment
		(start 360.090212 -10.289794)
		(end 360.090212 -8.89)
		(width 0.28956)
		(layer "F.Cu")
		(net "GND")
	)
	(segment
		(start 388.484872 -28.4099)
		(end 388.484872 -29.84246)
		(width 0.28956)
		(layer "F.Cu")
		(net "GND")
	)
	(segment
		(start 412.287466 -19.0754)
		(end 412.287466 -19.3548)
		(width 0.4572)
		(layer "F.Cu")
		(net "GND")
	)
	(segment
		(start 101.169978 -10.289794)
		(end 101.169978 -8.89)
		(width 0.28956)
		(layer "F.Cu")
		(net "GND")
	)
	(segment
		(start 172.285152 -28.4099)
		(end 172.285152 -31.1658)
		(width 0.28956)
		(layer "F.Cu")
		(net "GND")
	)
	(segment
		(start 324.57009 -8.92429)
		(end 324.5358 -8.89)
		(width 0.28956)
		(layer "F.Cu")
		(net "GND")
	)
	(segment
		(start 143.890238 -10.290048)
		(end 143.890238 -8.89)
		(width 0.28956)
		(layer "F.Cu")
		(net "GND")
	)
	(segment
		(start 412.295086 -29.793946)
		(end 412.295086 -28.4099)
		(width 0.28956)
		(layer "F.Cu")
		(net "GND")
	)
	(segment
		(start 191.697864 -19.765264)
		(end 191.697864 -20.964906)
		(width 0.4572)
		(layer "F.Cu")
		(net "GND")
	)
	(segment
		(start 194.094862 -25.899872)
		(end 194.094862 -24.422862)
		(width 0.28956)
		(layer "F.Cu")
		(net "GND")
	)
	(segment
		(start 412.69793 -19.765264)
		(end 412.69793 -20.964906)
		(width 0.4572)
		(layer "F.Cu")
		(net "GND")
	)
	(segment
		(start 25.841706 -15.306294)
		(end 25.841706 -15.954502)
		(width 0.3556)
		(layer "F.Cu")
		(net "GND")
	)
	(segment
		(start 194.4624 -19.5072)
		(end 194.09791 -19.87169)
		(width 0.4572)
		(layer "F.Cu")
		(net "GND")
	)
	(segment
		(start 128.229868 -22.692868)
		(end 128.4478 -22.9108)
		(width 0.4572)
		(layer "F.Cu")
		(net "GND")
	)
	(segment
		(start 174.684944 -28.4099)
		(end 174.684944 -30.1498)
		(width 0.28956)
		(layer "F.Cu")
		(net "GND")
	)
	(segment
		(start 145.890234 -18.490184)
		(end 145.890234 -19.9136)
		(width 0.28956)
		(layer "F.Cu")
		(net "GND")
	)
	(segment
		(start 324.57009 -10.290048)
		(end 324.57009 -11.7094)
		(width 0.28956)
		(layer "F.Cu")
		(net "GND")
	)
	(segment
		(start 322.170044 -10.290048)
		(end 322.170044 -11.7094)
		(width 0.28956)
		(layer "F.Cu")
		(net "GND")
	)
	(segment
		(start 390.468866 -19.2278)
		(end 391.288016 -20.04695)
		(width 0.4572)
		(layer "F.Cu")
		(net "GND")
	)
	(segment
		(start 186.894978 -25.899872)
		(end 186.894978 -24.534622)
		(width 0.28956)
		(layer "F.Cu")
		(net "GND")
	)
	(segment
		(start 415.097976 -19.87169)
		(end 415.097976 -20.964906)
		(width 0.4572)
		(layer "F.Cu")
		(net "GND")
	)
	(segment
		(start 128.229868 -22.150832)
		(end 128.229868 -22.692868)
		(width 0.4572)
		(layer "F.Cu")
		(net "GND")
	)
	(segment
		(start 367.29035 -10.289794)
		(end 367.29035 -11.7094)
		(width 0.28956)
		(layer "F.Cu")
		(net "GND")
	)
	(segment
		(start 26.0096 -15.1384)
		(end 25.841706 -15.306294)
		(width 0.3556)
		(layer "F.Cu")
		(net "GND")
	)
	(segment
		(start 167.48506 -28.4099)
		(end 167.48506 -29.84246)
		(width 0.28956)
		(layer "F.Cu")
		(net "GND")
	)
	(segment
		(start 324.57009 -10.290048)
		(end 324.57009 -8.92429)
		(width 0.28956)
		(layer "F.Cu")
		(net "GND")
	)
	(segment
		(start 407.895044 -24.534876)
		(end 407.89479 -24.534622)
		(width 0.28956)
		(layer "F.Cu")
		(net "GND")
	)
	(segment
		(start 186.494928 -28.4099)
		(end 185.9153 -28.4099)
		(width 0.28956)
		(layer "F.Cu")
		(net "GND")
	)
	(segment
		(start 105.97007 -10.289794)
		(end 105.97007 -8.89)
		(width 0.28956)
		(layer "F.Cu")
		(net "GND")
	)
	(segment
		(start 393.688062 -19.315938)
		(end 393.688062 -20.964906)
		(width 0.4572)
		(layer "F.Cu")
		(net "GND")
	)
	(segment
		(start 139.090146 -10.290048)
		(end 139.090146 -8.89)
		(width 0.28956)
		(layer "F.Cu")
		(net "GND")
	)
	(segment
		(start 364.890304 -10.289794)
		(end 364.890304 -11.7094)
		(width 0.28956)
		(layer "F.Cu")
		(net "GND")
	)
	(segment
		(start 175.189642 -22.7076)
		(end 175.088042 -22.606)
		(width 0.4572)
		(layer "F.Cu")
		(net "GND")
	)
	(segment
		(start 415.462466 -19.5072)
		(end 415.097976 -19.87169)
		(width 0.4572)
		(layer "F.Cu")
		(net "GND")
	)
	(segment
		(start 410.29509 -25.899872)
		(end 410.29509 -24.39543)
		(width 0.28956)
		(layer "F.Cu")
		(net "GND")
	)
	(segment
		(start 175.088042 -22.606)
		(end 175.088042 -20.964906)
		(width 0.4572)
		(layer "F.Cu")
		(net "GND")
	)
	(segment
		(start 345.425268 -22.074632)
		(end 345.442032 -22.057868)
		(width 0.4572)
		(layer "F.Cu")
		(net "GND")
	)
	(segment
		(start 103.570024 -8.929624)
		(end 103.5304 -8.89)
		(width 0.28956)
		(layer "F.Cu")
		(net "GND")
	)
	(segment
		(start 121.31802 -21.952712)
		(end 121.31802 -22.5806)
		(width 0.4572)
		(layer "F.Cu")
		(net "GND")
	)
	(segment
		(start 121.371868 -22.634448)
		(end 121.371868 -23.357332)
		(width 0.4572)
		(layer "F.Cu")
		(net "GND")
	)
	(segment
		(start 191.2874 -19.0754)
		(end 191.2874 -19.3548)
		(width 0.4572)
		(layer "F.Cu")
		(net "GND")
	)
	(segment
		(start 417.494974 -25.899872)
		(end 418.11194 -25.899872)
		(width 0.28956)
		(layer "F.Cu")
		(net "GND")
	)
	(segment
		(start 409.89504 -29.819346)
		(end 409.894786 -29.8196)
		(width 0.28956)
		(layer "F.Cu")
		(net "GND")
	)
	(segment
		(start 391.284968 -25.899872)
		(end 391.284968 -24.507444)
		(width 0.28956)
		(layer "F.Cu")
		(net "GND")
	)
	(segment
		(start 412.287466 -19.3548)
		(end 412.69793 -19.765264)
		(width 0.4572)
		(layer "F.Cu")
		(net "GND")
	)
	(segment
		(start 107.970066 -19.552666)
		(end 108.2548 -19.8374)
		(width 0.28956)
		(layer "F.Cu")
		(net "GND")
	)
	(segment
		(start 345.425268 -22.874732)
		(end 345.186 -23.114)
		(width 0.4572)
		(layer "F.Cu")
		(net "GND")
	)
	(segment
		(start 172.684948 -25.899872)
		(end 172.684948 -24.520652)
		(width 0.28956)
		(layer "F.Cu")
		(net "GND")
	)
	(segment
		(start 409.89504 -28.4099)
		(end 409.89504 -29.819346)
		(width 0.28956)
		(layer "F.Cu")
		(net "GND")
	)
	(segment
		(start 366.8903 -18.48993)
		(end 366.8903 -19.8882)
		(width 0.28956)
		(layer "F.Cu")
		(net "GND")
	)
	(segment
		(start 188.712094 -20.964906)
		(end 189.298072 -20.964906)
		(width 0.4572)
		(layer "F.Cu")
		(net "GND")
	)
	(segment
		(start 412.694882 -25.899872)
		(end 412.694882 -24.434038)
		(width 0.28956)
		(layer "F.Cu")
		(net "GND")
	)
	(segment
		(start 359.690162 -18.48993)
		(end 359.690162 -19.9136)
		(width 0.28956)
		(layer "F.Cu")
		(net "GND")
	)
	(segment
		(start 367.29035 -10.289794)
		(end 367.29035 -8.92175)
		(width 0.28956)
		(layer "F.Cu")
		(net "GND")
	)
	(segment
		(start 196.094858 -28.4099)
		(end 196.094858 -29.7942)
		(width 0.28956)
		(layer "F.Cu")
		(net "GND")
	)
	(segment
		(start 395.684756 -28.4099)
		(end 395.684756 -30.1498)
		(width 0.28956)
		(layer "F.Cu")
		(net "GND")
	)
	(segment
		(start 146.290284 -8.927084)
		(end 146.2532 -8.89)
		(width 0.28956)
		(layer "F.Cu")
		(net "GND")
	)
	(segment
		(start 414.694878 -29.793946)
		(end 414.694624 -29.7942)
		(width 0.28956)
		(layer "F.Cu")
		(net "GND")
	)
	(segment
		(start 123.839732 -22.696932)
		(end 123.952 -22.8092)
		(width 0.4572)
		(layer "F.Cu")
		(net "GND")
	)
	(segment
		(start 415.094928 -24.423116)
		(end 415.094674 -24.422862)
		(width 0.28956)
		(layer "F.Cu")
		(net "GND")
	)
	(segment
		(start 177.08499 -28.4099)
		(end 177.08499 -29.81579)
		(width 0.28956)
		(layer "F.Cu")
		(net "GND")
	)
	(segment
		(start 188.0362 -21.6408)
		(end 188.712094 -20.964906)
		(width 0.4572)
		(layer "F.Cu")
		(net "GND")
	)
	(segment
		(start 341.778844 -22.18309)
		(end 342.965278 -22.18309)
		(width 0.4572)
		(layer "F.Cu")
		(net "GND")
	)
	(segment
		(start 349.594932 -21.961602)
		(end 348.3864 -21.961602)
		(width 0.4572)
		(layer "F.Cu")
		(net "GND")
	)
	(segment
		(start 415.094928 -25.899872)
		(end 415.094928 -24.423116)
		(width 0.28956)
		(layer "F.Cu")
		(net "GND")
	)
	(segment
		(start 167.368728 -25.899872)
		(end 167.2336 -26.035)
		(width 0.28956)
		(layer "F.Cu")
		(net "GND")
	)
	(segment
		(start 121.31802 -22.5806)
		(end 121.371868 -22.634448)
		(width 0.4572)
		(layer "F.Cu")
		(net "GND")
	)
	(segment
		(start 191.2874 -19.3548)
		(end 191.697864 -19.765264)
		(width 0.4572)
		(layer "F.Cu")
		(net "GND")
	)
	(segment
		(start 170.28795 -20.04695)
		(end 170.28795 -20.964906)
		(width 0.4572)
		(layer "F.Cu")
		(net "GND")
	)
	(segment
		(start 326.970136 -10.290048)
		(end 326.970136 -11.7094)
		(width 0.28956)
		(layer "F.Cu")
		(net "GND")
	)
	(segment
		(start 340.898734 -23.0632)
		(end 341.771732 -22.190202)
		(width 0.4572)
		(layer "F.Cu")
		(net "GND")
	)
	(segment
		(start 138.690096 -18.490184)
		(end 138.690096 -20.1168)
		(width 0.28956)
		(layer "F.Cu")
		(net "GND")
	)
	(segment
		(start 105.97007 -10.289794)
		(end 105.97007 -11.7094)
		(width 0.28956)
		(layer "F.Cu")
		(net "GND")
	)
	(segment
		(start 362.490258 -8.922258)
		(end 362.458 -8.89)
		(width 0.28956)
		(layer "F.Cu")
		(net "GND")
	)
	(segment
		(start 172.7962 -19.2024)
		(end 172.687996 -19.310604)
		(width 0.4572)
		(layer "F.Cu")
		(net "GND")
	)
	(segment
		(start 107.970066 -18.48993)
		(end 107.970066 -19.552666)
		(width 0.28956)
		(layer "F.Cu")
		(net "GND")
	)
	(segment
		(start 194.09791 -19.87169)
		(end 194.09791 -20.964906)
		(width 0.4572)
		(layer "F.Cu")
		(net "GND")
	)
	(segment
		(start 193.694812 -28.4099)
		(end 193.694812 -29.7942)
		(width 0.28956)
		(layer "F.Cu")
		(net "GND")
	)
	(segment
		(start 364.890304 -10.289794)
		(end 364.890304 -8.89)
		(width 0.28956)
		(layer "F.Cu")
		(net "GND")
	)
	(segment
		(start 321.769994 -18.490184)
		(end 321.769994 -19.8882)
		(width 0.28956)
		(layer "F.Cu")
		(net "GND")
	)
	(segment
		(start 345.442032 -22.057868)
		(end 346.521532 -22.057868)
		(width 0.4572)
		(layer "F.Cu")
		(net "GND")
	)
	(segment
		(start 128.229868 -22.150832)
		(end 127.141732 -22.150832)
		(width 0.4572)
		(layer "F.Cu")
		(net "GND")
	)
	(segment
		(start 362.490258 -10.289794)
		(end 362.490258 -8.922258)
		(width 0.28956)
		(layer "F.Cu")
		(net "GND")
	)
	(segment
		(start 391.288016 -20.04695)
		(end 391.288016 -20.964906)
		(width 0.4572)
		(layer "F.Cu")
		(net "GND")
	)
	(segment
		(start 103.570024 -10.289794)
		(end 103.570024 -8.929624)
		(width 0.28956)
		(layer "F.Cu")
		(net "GND")
	)
	(segment
		(start 415.462466 -18.9992)
		(end 415.462466 -19.5072)
		(width 0.4572)
		(layer "F.Cu")
		(net "GND")
	)
	(segment
		(start 388.884922 -25.899872)
		(end 388.36854 -25.899872)
		(width 0.28956)
		(layer "F.Cu")
		(net "GND")
	)
	(segment
		(start 170.285156 -25.899872)
		(end 170.285156 -24.507444)
		(width 0.28956)
		(layer "F.Cu")
		(net "GND")
	)
	(segment
		(start 100.769928 -18.48993)
		(end 100.769928 -20.048728)
		(width 0.28956)
		(layer "F.Cu")
		(net "GND")
	)
	(segment
		(start 409.71216 -20.964906)
		(end 410.298138 -20.964906)
		(width 0.4572)
		(layer "F.Cu")
		(net "GND")
	)
	(segment
		(start 388.36854 -25.899872)
		(end 388.233412 -26.035)
		(width 0.28956)
		(layer "F.Cu")
		(net "GND")
	)
	(segment
		(start 367.29035 -8.92175)
		(end 367.2586 -8.89)
		(width 0.28956)
		(layer "F.Cu")
		(net "GND")
	)
	(segment
		(start 196.494908 -25.899872)
		(end 197.112128 -25.899872)
		(width 0.28956)
		(layer "F.Cu")
		(net "GND")
	)
	(segment
		(start 407.895044 -25.899872)
		(end 407.895044 -24.534876)
		(width 0.28956)
		(layer "F.Cu")
		(net "GND")
	)
	(segment
		(start 188.894974 -28.4099)
		(end 188.894974 -29.8196)
		(width 0.28956)
		(layer "F.Cu")
		(net "GND")
	)
	(segment
		(start 396.084806 -25.899872)
		(end 396.084806 -24.462994)
		(width 0.28956)
		(layer "F.Cu")
		(net "GND")
	)
	(segment
		(start 396.189708 -22.7076)
		(end 396.088108 -22.606)
		(width 0.4572)
		(layer "F.Cu")
		(net "GND")
	)
	(segment
		(start 409.036266 -22.1742)
		(end 409.036266 -21.6408)
		(width 0.4572)
		(layer "F.Cu")
		(net "GND")
	)
	(segment
		(start 188.0362 -22.1742)
		(end 188.0362 -21.6408)
		(width 0.4572)
		(layer "F.Cu")
		(net "GND")
	)
	(segment
		(start 398.484852 -25.899872)
		(end 399.23974 -25.899872)
		(width 0.28956)
		(layer "F.Cu")
		(net "GND")
	)
	(segment
		(start 101.169978 -10.289794)
		(end 101.169978 -11.7094)
		(width 0.28956)
		(layer "F.Cu")
		(net "GND")
	)
	(segment
		(start 103.570024 -10.289794)
		(end 103.570024 -11.7094)
		(width 0.28956)
		(layer "F.Cu")
		(net "GND")
	)
	(segment
		(start 417.094924 -28.4099)
		(end 417.094924 -29.793946)
		(width 0.28956)
		(layer "F.Cu")
		(net "GND")
	)
	(segment
		(start 417.094924 -29.793946)
		(end 417.09467 -29.7942)
		(width 0.28956)
		(layer "F.Cu")
		(net "GND")
	)
	(segment
		(start 141.490192 -10.290048)
		(end 141.490192 -11.7094)
		(width 0.28956)
		(layer "F.Cu")
		(net "GND")
	)
	(segment
		(start 396.088108 -22.606)
		(end 396.088108 -20.964906)
		(width 0.4572)
		(layer "F.Cu")
		(net "GND")
	)
	(segment
		(start 322.170044 -10.290048)
		(end 322.170044 -8.89)
		(width 0.28956)
		(layer "F.Cu")
		(net "GND")
	)
	(segment
		(start 141.490192 -8.927592)
		(end 141.4526 -8.89)
		(width 0.28956)
		(layer "F.Cu")
		(net "GND")
	)
	(segment
		(start 393.284964 -28.4099)
		(end 393.284964 -31.1658)
		(width 0.28956)
		(layer "F.Cu")
		(net "GND")
	)
	(segment
		(start 410.29509 -24.39543)
		(end 410.294836 -24.395176)
		(width 0.28956)
		(layer "F.Cu")
		(net "GND")
	)
	(segment
		(start 191.29502 -28.4099)
		(end 191.29502 -29.7942)
		(width 0.28956)
		(layer "F.Cu")
		(net "GND")
	)
	(segment
		(start 398.084802 -28.4099)
		(end 398.084802 -29.81579)
		(width 0.28956)
		(layer "F.Cu")
		(net "GND")
	)
	(segment
		(start 108.370116 -10.289794)
		(end 108.370116 -11.7094)
		(width 0.28956)
		(layer "F.Cu")
		(net "GND")
	)
	(segment
		(start 167.88511 -25.899872)
		(end 167.368728 -25.899872)
		(width 0.28956)
		(layer "F.Cu")
		(net "GND")
	)
	(segment
		(start 108.370116 -8.929116)
		(end 108.331 -8.89)
		(width 0.28956)
		(layer "F.Cu")
		(net "GND")
	)
	(segment
		(start 146.290284 -10.290048)
		(end 146.290284 -8.927084)
		(width 0.28956)
		(layer "F.Cu")
		(net "GND")
	)
	(segment
		(start 117.71249 -21.08581)
		(end 117.71249 -20.28571)
		(width 0.4572)
		(layer "F.Cu")
		(net "GND")
	)
	(segment
		(start 172.687996 -19.310604)
		(end 172.687996 -20.964906)
		(width 0.4572)
		(layer "F.Cu")
		(net "GND")
	)
	(segment
		(start 409.036266 -21.6408)
		(end 409.71216 -20.964906)
		(width 0.4572)
		(layer "F.Cu")
		(net "GND")
	)
	(segment
		(start 175.084994 -25.899872)
		(end 175.084994 -24.462994)
		(width 0.28956)
		(layer "F.Cu")
		(net "GND")
	)
	(segment
		(start 414.694878 -28.4099)
		(end 414.694878 -29.793946)
		(width 0.28956)
		(layer "F.Cu")
		(net "GND")
	)
	(segment
		(start 189.295024 -25.899872)
		(end 189.295024 -24.395176)
		(width 0.28956)
		(layer "F.Cu")
		(net "GND")
	)
	(segment
		(start 169.885106 -28.4099)
		(end 169.885106 -29.885894)
		(width 0.28956)
		(layer "F.Cu")
		(net "GND")
	)
	(segment
		(start 329.370182 -10.290048)
		(end 329.370182 -11.7094)
		(width 0.28956)
		(layer "F.Cu")
		(net "GND")
	)
	(via
		(at 87.7316 -27.3304)
		(size 0.508)
		(drill 0.254)
		(layers "F.Cu" "B.Cu")
		(net "GND")
	)
	(via
		(at 34.8234 -40.2844)
		(size 1.016)
		(drill 0.508)
		(layers "F.Cu" "B.Cu")
		(net "GND")
	)
	(via
		(at 191.694816 -24.433784)
		(size 0.508)
		(drill 0.254)
		(layers "F.Cu" "B.Cu")
		(net "GND")
	)
	(via
		(at 42.9768 -41.9608)
		(size 0.508)
		(drill 0.254)
		(layers "F.Cu" "B.Cu")
		(net "GND")
	)
	(via
		(at 189.295024 -24.395176)
		(size 0.508)
		(drill 0.254)
		(layers "F.Cu" "B.Cu")
		(net "GND")
	)
	(via
		(at 388.484872 -29.84246)
		(size 0.508)
		(drill 0.254)
		(layers "F.Cu" "B.Cu")
		(net "GND")
	)
	(via
		(at 365.252 -2.0574)
		(size 0.508)
		(drill 0.254)
		(layers "F.Cu" "B.Cu")
		(net "GND")
	)
	(via
		(at 278.6888 -28.2702)
		(size 1.016)
		(drill 0.508)
		(layers "F.Cu" "B.Cu")
		(net "GND")
	)
	(via
		(at 389.046466 -19.2786)
		(size 0.508)
		(drill 0.254)
		(layers "F.Cu" "B.Cu")
		(net "GND")
	)
	(via
		(at 63.1444 -36.2966)
		(size 1.016)
		(drill 0.508)
		(layers "F.Cu" "B.Cu")
		(net "GND")
	)
	(via
		(at 240.1316 -43.942)
		(size 1.016)
		(drill 0.508)
		(layers "F.Cu" "B.Cu")
		(net "GND")
	)
	(via
		(at 293.9796 -43.8404)
		(size 1.016)
		(drill 0.508)
		(layers "F.Cu" "B.Cu")
		(net "GND")
	)
	(via
		(at 266.3952 -6.6802)
		(size 1.016)
		(drill 0.508)
		(layers "F.Cu" "B.Cu")
		(net "GND")
	)
	(via
		(at 50.1142 -35.3314)
		(size 1.016)
		(drill 0.508)
		(layers "F.Cu" "B.Cu")
		(net "GND")
	)
	(via
		(at 326.970136 -8.89)
		(size 0.508)
		(drill 0.254)
		(layers "F.Cu" "B.Cu")
		(net "GND")
	)
	(via
		(at 120.523 -0.9906)
		(size 0.508)
		(drill 0.254)
		(layers "F.Cu" "B.Cu")
		(net "GND")
	)
	(via
		(at 367.2586 -8.89)
		(size 0.508)
		(drill 0.254)
		(layers "F.Cu" "B.Cu")
		(net "GND")
	)
	(via
		(at 172.684948 -24.520652)
		(size 0.508)
		(drill 0.254)
		(layers "F.Cu" "B.Cu")
		(net "GND")
	)
	(via
		(at 54.1782 -37.2872)
		(size 1.016)
		(drill 0.508)
		(layers "F.Cu" "B.Cu")
		(net "GND")
	)
	(via
		(at 39.5986 -43.18)
		(size 1.016)
		(drill 0.508)
		(layers "F.Cu" "B.Cu")
		(net "GND")
	)
	(via
		(at 213.5378 -16.5608)
		(size 1.016)
		(drill 0.508)
		(layers "F.Cu" "B.Cu")
		(net "GND")
	)
	(via
		(at 174.1424 -33.8328)
		(size 0.508)
		(drill 0.254)
		(layers "F.Cu" "B.Cu")
		(net "GND")
	)
	(via
		(at 251.6378 -16.5608)
		(size 1.016)
		(drill 0.508)
		(layers "F.Cu" "B.Cu")
		(net "GND")
	)
	(via
		(at 240.0808 -28.3718)
		(size 1.016)
		(drill 0.508)
		(layers "F.Cu" "B.Cu")
		(net "GND")
	)
	(via
		(at 393.68476 -24.520652)
		(size 0.508)
		(drill 0.254)
		(layers "F.Cu" "B.Cu")
		(net "GND")
	)
	(via
		(at 247.7516 -43.942)
		(size 1.016)
		(drill 0.508)
		(layers "F.Cu" "B.Cu")
		(net "GND")
	)
	(via
		(at 359.690162 -19.9136)
		(size 0.508)
		(drill 0.254)
		(layers "F.Cu" "B.Cu")
		(net "GND")
	)
	(via
		(at 409.036266 -22.1742)
		(size 0.508)
		(drill 0.254)
		(layers "F.Cu" "B.Cu")
		(net "GND")
	)
	(via
		(at 367.29035 -11.7094)
		(size 0.508)
		(drill 0.254)
		(layers "F.Cu" "B.Cu")
		(net "GND")
	)
	(via
		(at 158.9024 -24.2316)
		(size 0.508)
		(drill 0.254)
		(layers "F.Cu" "B.Cu")
		(net "GND")
	)
	(via
		(at 139.090146 -8.89)
		(size 0.508)
		(drill 0.254)
		(layers "F.Cu" "B.Cu")
		(net "GND")
	)
	(via
		(at 45.5422 -39.7256)
		(size 1.016)
		(drill 0.508)
		(layers "F.Cu" "B.Cu")
		(net "GND")
	)
	(via
		(at 82.3468 -24.4602)
		(size 1.016)
		(drill 0.508)
		(layers "F.Cu" "B.Cu")
		(net "GND")
	)
	(via
		(at 366.8903 -19.8882)
		(size 0.508)
		(drill 0.254)
		(layers "F.Cu" "B.Cu")
		(net "GND")
	)
	(via
		(at 87.9348 -26.035)
		(size 0.508)
		(drill 0.254)
		(layers "F.Cu" "B.Cu")
		(net "GND")
	)
	(via
		(at 61.6204 -35.5854)
		(size 1.016)
		(drill 0.508)
		(layers "F.Cu" "B.Cu")
		(net "GND")
	)
	(via
		(at 108.370116 -11.7094)
		(size 0.508)
		(drill 0.254)
		(layers "F.Cu" "B.Cu")
		(net "GND")
	)
	(via
		(at 173.1264 -14.097)
		(size 0.508)
		(drill 0.254)
		(layers "F.Cu" "B.Cu")
		(net "GND")
	)
	(via
		(at 67.3862 -43.18)
		(size 1.016)
		(drill 0.508)
		(layers "F.Cu" "B.Cu")
		(net "GND")
	)
	(via
		(at 64.1604 -48.768)
		(size 1.016)
		(drill 0.508)
		(layers "F.Cu" "B.Cu")
		(net "GND")
	)
	(via
		(at 390.468866 -19.2278)
		(size 0.508)
		(drill 0.254)
		(layers "F.Cu" "B.Cu")
		(net "GND")
	)
	(via
		(at 409.894786 -29.8196)
		(size 0.508)
		(drill 0.254)
		(layers "F.Cu" "B.Cu")
		(net "GND")
	)
	(via
		(at 92.075 -24.6634)
		(size 0.508)
		(drill 0.254)
		(layers "F.Cu" "B.Cu")
		(net "GND")
	)
	(via
		(at 46.736 -35.2552)
		(size 1.016)
		(drill 0.508)
		(layers "F.Cu" "B.Cu")
		(net "GND")
	)
	(via
		(at 415.081466 -31.5722)
		(size 0.508)
		(drill 0.254)
		(layers "F.Cu" "B.Cu")
		(net "GND")
	)
	(via
		(at 183.769 -30.2006)
		(size 0.508)
		(drill 0.254)
		(layers "F.Cu" "B.Cu")
		(net "GND")
	)
	(via
		(at 146.2532 -6.1722)
		(size 0.508)
		(drill 0.254)
		(layers "F.Cu" "B.Cu")
		(net "GND")
	)
	(via
		(at 85.9282 -41.3766)
		(size 1.016)
		(drill 0.508)
		(layers "F.Cu" "B.Cu")
		(net "GND")
	)
	(via
		(at 353.283266 -3.5052)
		(size 0.508)
		(drill 0.254)
		(layers "F.Cu" "B.Cu")
		(net "GND")
	)
	(via
		(at 389.9662 -14.1732)
		(size 0.508)
		(drill 0.254)
		(layers "F.Cu" "B.Cu")
		(net "GND")
	)
	(via
		(at 47.5234 -39.5732)
		(size 1.016)
		(drill 0.508)
		(layers "F.Cu" "B.Cu")
		(net "GND")
	)
	(via
		(at 37.7952 -21.59)
		(size 1.016)
		(drill 0.508)
		(layers "F.Cu" "B.Cu")
		(net "GND")
	)
	(via
		(at 165.3794 -23.1394)
		(size 0.508)
		(drill 0.254)
		(layers "F.Cu" "B.Cu")
		(net "GND")
	)
	(via
		(at 395.986 -1.0668)
		(size 0.508)
		(drill 0.254)
		(layers "F.Cu" "B.Cu")
		(net "GND")
	)
	(via
		(at 414.694624 -29.7942)
		(size 0.508)
		(drill 0.254)
		(layers "F.Cu" "B.Cu")
		(net "GND")
	)
	(via
		(at 60.071 -47.2186)
		(size 1.016)
		(drill 0.508)
		(layers "F.Cu" "B.Cu")
		(net "GND")
	)
	(via
		(at 101.169978 -11.7094)
		(size 0.508)
		(drill 0.254)
		(layers "F.Cu" "B.Cu")
		(net "GND")
	)
	(via
		(at 177.3936 -22.9362)
		(size 0.508)
		(drill 0.254)
		(layers "F.Cu" "B.Cu")
		(net "GND")
	)
	(via
		(at 396.084806 -24.462994)
		(size 0.508)
		(drill 0.254)
		(layers "F.Cu" "B.Cu")
		(net "GND")
	)
	(via
		(at 247.7008 -28.3718)
		(size 1.016)
		(drill 0.508)
		(layers "F.Cu" "B.Cu")
		(net "GND")
	)
	(via
		(at 78.7908 -34.5186)
		(size 1.016)
		(drill 0.508)
		(layers "F.Cu" "B.Cu")
		(net "GND")
	)
	(via
		(at 340.4616 -23.0632)
		(size 0.508)
		(drill 0.254)
		(layers "F.Cu" "B.Cu")
		(net "GND")
	)
	(via
		(at 88.0872 -28.829)
		(size 0.508)
		(drill 0.254)
		(layers "F.Cu" "B.Cu")
		(net "GND")
	)
	(via
		(at 44.45 -15.8242)
		(size 1.016)
		(drill 0.508)
		(layers "F.Cu" "B.Cu")
		(net "GND")
	)
	(via
		(at 145.890234 -19.9136)
		(size 0.508)
		(drill 0.254)
		(layers "F.Cu" "B.Cu")
		(net "GND")
	)
	(via
		(at 74.3712 -43.1292)
		(size 1.016)
		(drill 0.508)
		(layers "F.Cu" "B.Cu")
		(net "GND")
	)
	(via
		(at 41.7576 -35.1028)
		(size 1.016)
		(drill 0.508)
		(layers "F.Cu" "B.Cu")
		(net "GND")
	)
	(via
		(at 364.890304 -11.7094)
		(size 0.508)
		(drill 0.254)
		(layers "F.Cu" "B.Cu")
		(net "GND")
	)
	(via
		(at 37.7444 -43.2054)
		(size 1.016)
		(drill 0.508)
		(layers "F.Cu" "B.Cu")
		(net "GND")
	)
	(via
		(at 56.9976 -35.1028)
		(size 1.016)
		(drill 0.508)
		(layers "F.Cu" "B.Cu")
		(net "GND")
	)
	(via
		(at 412.5722 -30.861)
		(size 0.508)
		(drill 0.254)
		(layers "F.Cu" "B.Cu")
		(net "GND")
	)
	(via
		(at 204.9272 -6.7818)
		(size 1.016)
		(drill 0.508)
		(layers "F.Cu" "B.Cu")
		(net "GND")
	)
	(via
		(at 68.6562 -5.1308)
		(size 1.016)
		(drill 0.508)
		(layers "F.Cu" "B.Cu")
		(net "GND")
	)
	(via
		(at 415.094674 -24.422862)
		(size 0.508)
		(drill 0.254)
		(layers "F.Cu" "B.Cu")
		(net "GND")
	)
	(via
		(at 367.3602 -2.1082)
		(size 0.508)
		(drill 0.254)
		(layers "F.Cu" "B.Cu")
		(net "GND")
	)
	(via
		(at 48.3616 -43.1292)
		(size 1.016)
		(drill 0.508)
		(layers "F.Cu" "B.Cu")
		(net "GND")
	)
	(via
		(at 101.0412 -5.9944)
		(size 0.508)
		(drill 0.254)
		(layers "F.Cu" "B.Cu")
		(net "GND")
	)
	(via
		(at 60.6552 -40.005)
		(size 1.016)
		(drill 0.508)
		(layers "F.Cu" "B.Cu")
		(net "GND")
	)
	(via
		(at 334.258666 -8.6106)
		(size 0.508)
		(drill 0.254)
		(layers "F.Cu" "B.Cu")
		(net "GND")
	)
	(via
		(at 36.703 -10.16)
		(size 1.016)
		(drill 0.508)
		(layers "F.Cu" "B.Cu")
		(net "GND")
	)
	(via
		(at 188.0362 -22.1742)
		(size 0.508)
		(drill 0.254)
		(layers "F.Cu" "B.Cu")
		(net "GND")
	)
	(via
		(at 345.186 -23.114)
		(size 0.508)
		(drill 0.254)
		(layers "F.Cu" "B.Cu")
		(net "GND")
	)
	(via
		(at 386.379466 -23.1394)
		(size 0.508)
		(drill 0.254)
		(layers "F.Cu" "B.Cu")
		(net "GND")
	)
	(via
		(at 39.497 -41.8592)
		(size 0.508)
		(drill 0.254)
		(layers "F.Cu" "B.Cu")
		(net "GND")
	)
	(via
		(at 393.827 -19.177)
		(size 0.508)
		(drill 0.254)
		(layers "F.Cu" "B.Cu")
		(net "GND")
	)
	(via
		(at 172.7962 -19.2024)
		(size 0.508)
		(drill 0.254)
		(layers "F.Cu" "B.Cu")
		(net "GND")
	)
	(via
		(at 30.607 -15.0876)
		(size 0.508)
		(drill 0.254)
		(layers "F.Cu" "B.Cu")
		(net "GND")
	)
	(via
		(at 64.6176 -35.1028)
		(size 1.016)
		(drill 0.508)
		(layers "F.Cu" "B.Cu")
		(net "GND")
	)
	(via
		(at 62.2554 -41.9608)
		(size 1.016)
		(drill 0.508)
		(layers "F.Cu" "B.Cu")
		(net "GND")
	)
	(via
		(at 49.8348 -25.9842)
		(size 1.016)
		(drill 0.508)
		(layers "F.Cu" "B.Cu")
		(net "GND")
	)
	(via
		(at 393.948666 -33.8328)
		(size 0.508)
		(drill 0.254)
		(layers "F.Cu" "B.Cu")
		(net "GND")
	)
	(via
		(at 108.2548 -19.8374)
		(size 0.508)
		(drill 0.254)
		(layers "F.Cu" "B.Cu")
		(net "GND")
	)
	(via
		(at 144.0434 -5.207)
		(size 0.508)
		(drill 0.254)
		(layers "F.Cu" "B.Cu")
		(net "GND")
	)
	(via
		(at 45.7962 -5.1308)
		(size 1.016)
		(drill 0.508)
		(layers "F.Cu" "B.Cu")
		(net "GND")
	)
	(via
		(at 336.620866 -9.8044)
		(size 0.508)
		(drill 0.254)
		(layers "F.Cu" "B.Cu")
		(net "GND")
	)
	(via
		(at 415.462466 -18.9992)
		(size 0.508)
		(drill 0.254)
		(layers "F.Cu" "B.Cu")
		(net "GND")
	)
	(via
		(at 362.490258 -11.7094)
		(size 0.508)
		(drill 0.254)
		(layers "F.Cu" "B.Cu")
		(net "GND")
	)
	(via
		(at 390.545066 -32.0548)
		(size 0.508)
		(drill 0.254)
		(layers "F.Cu" "B.Cu")
		(net "GND")
	)
	(via
		(at 168.9354 -14.1986)
		(size 0.508)
		(drill 0.254)
		(layers "F.Cu" "B.Cu")
		(net "GND")
	)
	(via
		(at 417.09467 -29.7942)
		(size 0.508)
		(drill 0.254)
		(layers "F.Cu" "B.Cu")
		(net "GND")
	)
	(via
		(at 138.690096 -20.1168)
		(size 0.508)
		(drill 0.254)
		(layers "F.Cu" "B.Cu")
		(net "GND")
	)
	(via
		(at 412.294832 -29.7942)
		(size 0.508)
		(drill 0.254)
		(layers "F.Cu" "B.Cu")
		(net "GND")
	)
	(via
		(at 101.169978 -8.89)
		(size 0.508)
		(drill 0.254)
		(layers "F.Cu" "B.Cu")
		(net "GND")
	)
	(via
		(at 38.1762 -5.1308)
		(size 1.016)
		(drill 0.508)
		(layers "F.Cu" "B.Cu")
		(net "GND")
	)
	(via
		(at 61.7474 -12.5984)
		(size 1.016)
		(drill 0.508)
		(layers "F.Cu" "B.Cu")
		(net "GND")
	)
	(via
		(at 41.6052 -43.2054)
		(size 1.016)
		(drill 0.508)
		(layers "F.Cu" "B.Cu")
		(net "GND")
	)
	(via
		(at 49.4284 -39.3192)
		(size 1.016)
		(drill 0.508)
		(layers "F.Cu" "B.Cu")
		(net "GND")
	)
	(via
		(at 326.970136 -11.7094)
		(size 0.508)
		(drill 0.254)
		(layers "F.Cu" "B.Cu")
		(net "GND")
	)
	(via
		(at 172.285152 -31.1658)
		(size 0.508)
		(drill 0.254)
		(layers "F.Cu" "B.Cu")
		(net "GND")
	)
	(via
		(at 55.3974 -35.687)
		(size 1.016)
		(drill 0.508)
		(layers "F.Cu" "B.Cu")
		(net "GND")
	)
	(via
		(at 274.0152 -6.6802)
		(size 1.016)
		(drill 0.508)
		(layers "F.Cu" "B.Cu")
		(net "GND")
	)
	(via
		(at 205.9178 -16.5608)
		(size 1.016)
		(drill 0.508)
		(layers "F.Cu" "B.Cu")
		(net "GND")
	)
	(via
		(at 310.6928 -25.146)
		(size 0.508)
		(drill 0.254)
		(layers "F.Cu" "B.Cu")
		(net "GND")
	)
	(via
		(at 360.090212 -8.89)
		(size 0.508)
		(drill 0.254)
		(layers "F.Cu" "B.Cu")
		(net "GND")
	)
	(via
		(at 227.7872 -6.7818)
		(size 1.016)
		(drill 0.508)
		(layers "F.Cu" "B.Cu")
		(net "GND")
	)
	(via
		(at 108.331 -8.89)
		(size 0.508)
		(drill 0.254)
		(layers "F.Cu" "B.Cu")
		(net "GND")
	)
	(via
		(at 145.161 -1.905)
		(size 0.508)
		(drill 0.254)
		(layers "F.Cu" "B.Cu")
		(net "GND")
	)
	(via
		(at 36.6268 -24.4602)
		(size 1.016)
		(drill 0.508)
		(layers "F.Cu" "B.Cu")
		(net "GND")
	)
	(via
		(at 255.3208 -28.3718)
		(size 1.016)
		(drill 0.508)
		(layers "F.Cu" "B.Cu")
		(net "GND")
	)
	(via
		(at 63.0936 -38.0492)
		(size 1.016)
		(drill 0.508)
		(layers "F.Cu" "B.Cu")
		(net "GND")
	)
	(via
		(at 36.322 -26.8478)
		(size 1.016)
		(drill 0.508)
		(layers "F.Cu" "B.Cu")
		(net "GND")
	)
	(via
		(at 364.871 -5.2578)
		(size 0.508)
		(drill 0.254)
		(layers "F.Cu" "B.Cu")
		(net "GND")
	)
	(via
		(at 193.694812 -29.7942)
		(size 0.508)
		(drill 0.254)
		(layers "F.Cu" "B.Cu")
		(net "GND")
	)
	(via
		(at 250.6472 -6.7818)
		(size 1.016)
		(drill 0.508)
		(layers "F.Cu" "B.Cu")
		(net "GND")
	)
	(via
		(at 354.502466 -5.7404)
		(size 0.508)
		(drill 0.254)
		(layers "F.Cu" "B.Cu")
		(net "GND")
	)
	(via
		(at 43.1546 -37.2872)
		(size 1.016)
		(drill 0.508)
		(layers "F.Cu" "B.Cu")
		(net "GND")
	)
	(via
		(at 143.890238 -8.89)
		(size 0.508)
		(drill 0.254)
		(layers "F.Cu" "B.Cu")
		(net "GND")
	)
	(via
		(at 258.7752 -6.6802)
		(size 1.016)
		(drill 0.508)
		(layers "F.Cu" "B.Cu")
		(net "GND")
	)
	(via
		(at 33.8074 -18.1102)
		(size 1.016)
		(drill 0.508)
		(layers "F.Cu" "B.Cu")
		(net "GND")
	)
	(via
		(at 146.2532 -8.89)
		(size 0.508)
		(drill 0.254)
		(layers "F.Cu" "B.Cu")
		(net "GND")
	)
	(via
		(at 60.8584 -37.7698)
		(size 1.016)
		(drill 0.508)
		(layers "F.Cu" "B.Cu")
		(net "GND")
	)
	(via
		(at 367.2078 -6.1976)
		(size 0.508)
		(drill 0.254)
		(layers "F.Cu" "B.Cu")
		(net "GND")
	)
	(via
		(at 57.6834 -10.922)
		(size 1.016)
		(drill 0.508)
		(layers "F.Cu" "B.Cu")
		(net "GND")
	)
	(via
		(at 232.5116 -43.942)
		(size 1.016)
		(drill 0.508)
		(layers "F.Cu" "B.Cu")
		(net "GND")
	)
	(via
		(at 321.9958 -5.0038)
		(size 0.508)
		(drill 0.254)
		(layers "F.Cu" "B.Cu")
		(net "GND")
	)
	(via
		(at 36.3982 -6.9342)
		(size 1.016)
		(drill 0.508)
		(layers "F.Cu" "B.Cu")
		(net "GND")
	)
	(via
		(at 321.769994 -19.8882)
		(size 0.508)
		(drill 0.254)
		(layers "F.Cu" "B.Cu")
		(net "GND")
	)
	(via
		(at 309.0418 -29.0576)
		(size 0.508)
		(drill 0.254)
		(layers "F.Cu" "B.Cu")
		(net "GND")
	)
	(via
		(at 167.2336 -26.035)
		(size 0.508)
		(drill 0.254)
		(layers "F.Cu" "B.Cu")
		(net "GND")
	)
	(via
		(at 353.308666 -5.715)
		(size 0.508)
		(drill 0.254)
		(layers "F.Cu" "B.Cu")
		(net "GND")
	)
	(via
		(at 29.0576 -15.1638)
		(size 0.508)
		(drill 0.254)
		(layers "F.Cu" "B.Cu")
		(net "GND")
	)
	(via
		(at 398.393666 -22.9362)
		(size 0.508)
		(drill 0.254)
		(layers "F.Cu" "B.Cu")
		(net "GND")
	)
	(via
		(at 286.3088 -28.2702)
		(size 1.016)
		(drill 0.508)
		(layers "F.Cu" "B.Cu")
		(net "GND")
	)
	(via
		(at 41.4528 -38.5064)
		(size 1.016)
		(drill 0.508)
		(layers "F.Cu" "B.Cu")
		(net "GND")
	)
	(via
		(at 412.694628 -24.433784)
		(size 0.508)
		(drill 0.254)
		(layers "F.Cu" "B.Cu")
		(net "GND")
	)
	(via
		(at 37.592 -40.3352)
		(size 1.016)
		(drill 0.508)
		(layers "F.Cu" "B.Cu")
		(net "GND")
	)
	(via
		(at 324.57009 -11.7094)
		(size 0.508)
		(drill 0.254)
		(layers "F.Cu" "B.Cu")
		(net "GND")
	)
	(via
		(at 61.5442 -43.6372)
		(size 1.016)
		(drill 0.508)
		(layers "F.Cu" "B.Cu")
		(net "GND")
	)
	(via
		(at 73.0504 -38.1)
		(size 1.016)
		(drill 0.508)
		(layers "F.Cu" "B.Cu")
		(net "GND")
	)
	(via
		(at 115.6716 -8.636)
		(size 0.508)
		(drill 0.254)
		(layers "F.Cu" "B.Cu")
		(net "GND")
	)
	(via
		(at 379.603 -26.0858)
		(size 0.508)
		(drill 0.254)
		(layers "F.Cu" "B.Cu")
		(net "GND")
	)
	(via
		(at 345.5924 -1.016)
		(size 0.508)
		(drill 0.254)
		(layers "F.Cu" "B.Cu")
		(net "GND")
	)
	(via
		(at 164.6682 -14.1224)
		(size 0.508)
		(drill 0.254)
		(layers "F.Cu" "B.Cu")
		(net "GND")
	)
	(via
		(at 255.3716 -43.942)
		(size 1.016)
		(drill 0.508)
		(layers "F.Cu" "B.Cu")
		(net "GND")
	)
	(via
		(at 59.7916 -43.9166)
		(size 1.016)
		(drill 0.508)
		(layers "F.Cu" "B.Cu")
		(net "GND")
	)
	(via
		(at 39.751 -36.7792)
		(size 1.016)
		(drill 0.508)
		(layers "F.Cu" "B.Cu")
		(net "GND")
	)
	(via
		(at 169.4688 -19.2278)
		(size 0.508)
		(drill 0.254)
		(layers "F.Cu" "B.Cu")
		(net "GND")
	)
	(via
		(at 262.9916 -43.942)
		(size 1.016)
		(drill 0.508)
		(layers "F.Cu" "B.Cu")
		(net "GND")
	)
	(via
		(at 37.9222 -41.6814)
		(size 1.016)
		(drill 0.508)
		(layers "F.Cu" "B.Cu")
		(net "GND")
	)
	(via
		(at 271.0688 -28.2702)
		(size 1.016)
		(drill 0.508)
		(layers "F.Cu" "B.Cu")
		(net "GND")
	)
	(via
		(at 379.73 -23.5712)
		(size 0.508)
		(drill 0.254)
		(layers "F.Cu" "B.Cu")
		(net "GND")
	)
	(via
		(at 71.7804 -48.768)
		(size 1.016)
		(drill 0.508)
		(layers "F.Cu" "B.Cu")
		(net "GND")
	)
	(via
		(at 159.0294 -25.3746)
		(size 0.508)
		(drill 0.254)
		(layers "F.Cu" "B.Cu")
		(net "GND")
	)
	(via
		(at 43.5102 -43.18)
		(size 1.016)
		(drill 0.508)
		(layers "F.Cu" "B.Cu")
		(net "GND")
	)
	(via
		(at 46.5074 -12.5984)
		(size 1.016)
		(drill 0.508)
		(layers "F.Cu" "B.Cu")
		(net "GND")
	)
	(via
		(at 132.3086 -5.715)
		(size 0.508)
		(drill 0.254)
		(layers "F.Cu" "B.Cu")
		(net "GND")
	)
	(via
		(at 34.798 -43.2816)
		(size 1.016)
		(drill 0.508)
		(layers "F.Cu" "B.Cu")
		(net "GND")
	)
	(via
		(at 44.7802 -41.7576)
		(size 1.016)
		(drill 0.508)
		(layers "F.Cu" "B.Cu")
		(net "GND")
	)
	(via
		(at 144.018 -6.1976)
		(size 0.508)
		(drill 0.254)
		(layers "F.Cu" "B.Cu")
		(net "GND")
	)
	(via
		(at 32.766 -41.8592)
		(size 0.508)
		(drill 0.254)
		(layers "F.Cu" "B.Cu")
		(net "GND")
	)
	(via
		(at 407.89479 -24.534622)
		(size 0.508)
		(drill 0.254)
		(layers "F.Cu" "B.Cu")
		(net "GND")
	)
	(via
		(at 334.233266 -9.7028)
		(size 0.508)
		(drill 0.254)
		(layers "F.Cu" "B.Cu")
		(net "GND")
	)
	(via
		(at 72.2376 -35.1028)
		(size 1.016)
		(drill 0.508)
		(layers "F.Cu" "B.Cu")
		(net "GND")
	)
	(via
		(at 267.3858 -16.4592)
		(size 1.016)
		(drill 0.508)
		(layers "F.Cu" "B.Cu")
		(net "GND")
	)
	(via
		(at 34.2392 -41.656)
		(size 1.016)
		(drill 0.508)
		(layers "F.Cu" "B.Cu")
		(net "GND")
	)
	(via
		(at 322.170044 -11.7094)
		(size 0.508)
		(drill 0.254)
		(layers "F.Cu" "B.Cu")
		(net "GND")
	)
	(via
		(at 224.8408 -28.3718)
		(size 1.016)
		(drill 0.508)
		(layers "F.Cu" "B.Cu")
		(net "GND")
	)
	(via
		(at 186.894978 -24.534622)
		(size 0.508)
		(drill 0.254)
		(layers "F.Cu" "B.Cu")
		(net "GND")
	)
	(via
		(at 42.672 -40.9448)
		(size 1.016)
		(drill 0.508)
		(layers "F.Cu" "B.Cu")
		(net "GND")
	)
	(via
		(at 54.1274 -12.5984)
		(size 1.016)
		(drill 0.508)
		(layers "F.Cu" "B.Cu")
		(net "GND")
	)
	(via
		(at 170.285156 -24.507444)
		(size 0.508)
		(drill 0.254)
		(layers "F.Cu" "B.Cu")
		(net "GND")
	)
	(via
		(at 132.2832 -3.5052)
		(size 0.508)
		(drill 0.254)
		(layers "F.Cu" "B.Cu")
		(net "GND")
	)
	(via
		(at 263.4488 -28.2702)
		(size 1.016)
		(drill 0.508)
		(layers "F.Cu" "B.Cu")
		(net "GND")
	)
	(via
		(at 364.871 -6.0706)
		(size 0.508)
		(drill 0.254)
		(layers "F.Cu" "B.Cu")
		(net "GND")
	)
	(via
		(at 124.5108 -1.016)
		(size 0.508)
		(drill 0.254)
		(layers "F.Cu" "B.Cu")
		(net "GND")
	)
	(via
		(at 236.3978 -16.5608)
		(size 1.016)
		(drill 0.508)
		(layers "F.Cu" "B.Cu")
		(net "GND")
	)
	(via
		(at 188.894974 -29.8196)
		(size 0.508)
		(drill 0.254)
		(layers "F.Cu" "B.Cu")
		(net "GND")
	)
	(via
		(at 308.991 -27.5082)
		(size 0.508)
		(drill 0.254)
		(layers "F.Cu" "B.Cu")
		(net "GND")
	)
	(via
		(at 41.148 -40.4876)
		(size 1.016)
		(drill 0.508)
		(layers "F.Cu" "B.Cu")
		(net "GND")
	)
	(via
		(at 146.2786 -5.2832)
		(size 0.508)
		(drill 0.254)
		(layers "F.Cu" "B.Cu")
		(net "GND")
	)
	(via
		(at 39.5224 -40.1066)
		(size 1.016)
		(drill 0.508)
		(layers "F.Cu" "B.Cu")
		(net "GND")
	)
	(via
		(at 41.1734 -41.7322)
		(size 1.016)
		(drill 0.508)
		(layers "F.Cu" "B.Cu")
		(net "GND")
	)
	(via
		(at 42.291 -8.8138)
		(size 1.016)
		(drill 0.508)
		(layers "F.Cu" "B.Cu")
		(net "GND")
	)
	(via
		(at 45.1612 -43.2816)
		(size 1.016)
		(drill 0.508)
		(layers "F.Cu" "B.Cu")
		(net "GND")
	)
	(via
		(at 325.3486 -1.4986)
		(size 0.508)
		(drill 0.254)
		(layers "F.Cu" "B.Cu")
		(net "GND")
	)
	(via
		(at 50.0634 -40.8432)
		(size 1.016)
		(drill 0.508)
		(layers "F.Cu" "B.Cu")
		(net "GND")
	)
	(via
		(at 185.6486 -27.6606)
		(size 0.508)
		(drill 0.254)
		(layers "F.Cu" "B.Cu")
		(net "GND")
	)
	(via
		(at 168.0464 -19.2786)
		(size 0.508)
		(drill 0.254)
		(layers "F.Cu" "B.Cu")
		(net "GND")
	)
	(via
		(at 113.284 -8.6106)
		(size 0.508)
		(drill 0.254)
		(layers "F.Cu" "B.Cu")
		(net "GND")
	)
	(via
		(at 309.372 -25.1714)
		(size 0.508)
		(drill 0.254)
		(layers "F.Cu" "B.Cu")
		(net "GND")
	)
	(via
		(at 183.4896 -25.9842)
		(size 0.508)
		(drill 0.254)
		(layers "F.Cu" "B.Cu")
		(net "GND")
	)
	(via
		(at 341.5538 -1.0414)
		(size 0.508)
		(drill 0.254)
		(layers "F.Cu" "B.Cu")
		(net "GND")
	)
	(via
		(at 349.5802 -1.016)
		(size 0.508)
		(drill 0.254)
		(layers "F.Cu" "B.Cu")
		(net "GND")
	)
	(via
		(at 244.0178 -16.5608)
		(size 1.016)
		(drill 0.508)
		(layers "F.Cu" "B.Cu")
		(net "GND")
	)
	(via
		(at 324.2818 -1.4986)
		(size 0.508)
		(drill 0.254)
		(layers "F.Cu" "B.Cu")
		(net "GND")
	)
	(via
		(at 48.6918 -19.1516)
		(size 1.016)
		(drill 0.508)
		(layers "F.Cu" "B.Cu")
		(net "GND")
	)
	(via
		(at 32.3596 -43.2816)
		(size 1.016)
		(drill 0.508)
		(layers "F.Cu" "B.Cu")
		(net "GND")
	)
	(via
		(at 113.284 -9.7536)
		(size 0.508)
		(drill 0.254)
		(layers "F.Cu" "B.Cu")
		(net "GND")
	)
	(via
		(at 275.0058 -16.4592)
		(size 1.016)
		(drill 0.508)
		(layers "F.Cu" "B.Cu")
		(net "GND")
	)
	(via
		(at 390.884918 -29.885894)
		(size 0.508)
		(drill 0.254)
		(layers "F.Cu" "B.Cu")
		(net "GND")
	)
	(via
		(at 235.4072 -6.7818)
		(size 1.016)
		(drill 0.508)
		(layers "F.Cu" "B.Cu")
		(net "GND")
	)
	(via
		(at 61.7982 -47.1424)
		(size 1.016)
		(drill 0.508)
		(layers "F.Cu" "B.Cu")
		(net "GND")
	)
	(via
		(at 38.8874 -12.5984)
		(size 1.016)
		(drill 0.508)
		(layers "F.Cu" "B.Cu")
		(net "GND")
	)
	(via
		(at 167.48506 -29.84246)
		(size 0.508)
		(drill 0.254)
		(layers "F.Cu" "B.Cu")
		(net "GND")
	)
	(via
		(at 394.1572 -14.1478)
		(size 0.508)
		(drill 0.254)
		(layers "F.Cu" "B.Cu")
		(net "GND")
	)
	(via
		(at 324.5358 -8.89)
		(size 0.508)
		(drill 0.254)
		(layers "F.Cu" "B.Cu")
		(net "GND")
	)
	(via
		(at 133.5024 -5.7404)
		(size 0.508)
		(drill 0.254)
		(layers "F.Cu" "B.Cu")
		(net "GND")
	)
	(via
		(at 177.08499 -29.81579)
		(size 0.508)
		(drill 0.254)
		(layers "F.Cu" "B.Cu")
		(net "GND")
	)
	(via
		(at 51.8668 -35.3568)
		(size 1.016)
		(drill 0.508)
		(layers "F.Cu" "B.Cu")
		(net "GND")
	)
	(via
		(at 62.3824 -39.878)
		(size 1.016)
		(drill 0.508)
		(layers "F.Cu" "B.Cu")
		(net "GND")
	)
	(via
		(at 278.7396 -43.8404)
		(size 1.016)
		(drill 0.508)
		(layers "F.Cu" "B.Cu")
		(net "GND")
	)
	(via
		(at 61.0362 -5.1308)
		(size 1.016)
		(drill 0.508)
		(layers "F.Cu" "B.Cu")
		(net "GND")
	)
	(via
		(at 26.0096 -15.1384)
		(size 0.508)
		(drill 0.254)
		(layers "F.Cu" "B.Cu")
		(net "GND")
	)
	(via
		(at 209.6008 -28.3718)
		(size 1.016)
		(drill 0.508)
		(layers "F.Cu" "B.Cu")
		(net "GND")
	)
	(via
		(at 362.458 -8.89)
		(size 0.508)
		(drill 0.254)
		(layers "F.Cu" "B.Cu")
		(net "GND")
	)
	(via
		(at 288.3916 -10.414)
		(size 1.016)
		(drill 0.508)
		(layers "F.Cu" "B.Cu")
		(net "GND")
	)
	(via
		(at 103.570024 -11.7094)
		(size 0.508)
		(drill 0.254)
		(layers "F.Cu" "B.Cu")
		(net "GND")
	)
	(via
		(at 53.4162 -5.1308)
		(size 1.016)
		(drill 0.508)
		(layers "F.Cu" "B.Cu")
		(net "GND")
	)
	(via
		(at 38.1762 -36.7284)
		(size 1.016)
		(drill 0.508)
		(layers "F.Cu" "B.Cu")
		(net "GND")
	)
	(via
		(at 43.0276 -39.0144)
		(size 1.016)
		(drill 0.508)
		(layers "F.Cu" "B.Cu")
		(net "GND")
	)
	(via
		(at 243.0272 -6.7818)
		(size 1.016)
		(drill 0.508)
		(layers "F.Cu" "B.Cu")
		(net "GND")
	)
	(via
		(at 47.1932 -36.9316)
		(size 1.016)
		(drill 0.508)
		(layers "F.Cu" "B.Cu")
		(net "GND")
	)
	(via
		(at 396.189708 -22.7076)
		(size 0.508)
		(drill 0.254)
		(layers "F.Cu" "B.Cu")
		(net "GND")
	)
	(via
		(at 324.7898 -5.842)
		(size 0.508)
		(drill 0.254)
		(layers "F.Cu" "B.Cu")
		(net "GND")
	)
	(via
		(at 185.9153 -28.4099)
		(size 0.508)
		(drill 0.254)
		(layers "F.Cu" "B.Cu")
		(net "GND")
	)
	(via
		(at 418.11194 -25.899872)
		(size 0.508)
		(drill 0.254)
		(layers "F.Cu" "B.Cu")
		(net "GND")
	)
	(via
		(at 48.5648 -36.1696)
		(size 1.016)
		(drill 0.508)
		(layers "F.Cu" "B.Cu")
		(net "GND")
	)
	(via
		(at 364.1598 -2.032)
		(size 0.508)
		(drill 0.254)
		(layers "F.Cu" "B.Cu")
		(net "GND")
	)
	(via
		(at 41.529 -36.8046)
		(size 1.016)
		(drill 0.508)
		(layers "F.Cu" "B.Cu")
		(net "GND")
	)
	(via
		(at 391.284968 -24.507444)
		(size 0.508)
		(drill 0.254)
		(layers "F.Cu" "B.Cu")
		(net "GND")
	)
	(via
		(at 56.3372 -37.9476)
		(size 1.016)
		(drill 0.508)
		(layers "F.Cu" "B.Cu")
		(net "GND")
	)
	(via
		(at 328.970132 -20.106132)
		(size 0.508)
		(drill 0.254)
		(layers "F.Cu" "B.Cu")
		(net "GND")
	)
	(via
		(at 308.991 -30.353)
		(size 0.508)
		(drill 0.254)
		(layers "F.Cu" "B.Cu")
		(net "GND")
	)
	(via
		(at 79.9084 -26.4414)
		(size 1.016)
		(drill 0.508)
		(layers "F.Cu" "B.Cu")
		(net "GND")
	)
	(via
		(at 57.3024 -26.543)
		(size 1.016)
		(drill 0.508)
		(layers "F.Cu" "B.Cu")
		(net "GND")
	)
	(via
		(at 64.8716 -37.6936)
		(size 1.016)
		(drill 0.508)
		(layers "F.Cu" "B.Cu")
		(net "GND")
	)
	(via
		(at 191.2874 -19.0754)
		(size 0.508)
		(drill 0.254)
		(layers "F.Cu" "B.Cu")
		(net "GND")
	)
	(via
		(at 38.7604 -38.608)
		(size 1.016)
		(drill 0.508)
		(layers "F.Cu" "B.Cu")
		(net "GND")
	)
	(via
		(at 321.9958 -5.8166)
		(size 0.508)
		(drill 0.254)
		(layers "F.Cu" "B.Cu")
		(net "GND")
	)
	(via
		(at 339.1662 -14.1224)
		(size 0.508)
		(drill 0.254)
		(layers "F.Cu" "B.Cu")
		(net "GND")
	)
	(via
		(at 220.1672 -6.7818)
		(size 1.016)
		(drill 0.508)
		(layers "F.Cu" "B.Cu")
		(net "GND")
	)
	(via
		(at 46.5582 -41.8338)
		(size 0.508)
		(drill 0.254)
		(layers "F.Cu" "B.Cu")
		(net "GND")
	)
	(via
		(at 31.2674 -12.5984)
		(size 1.016)
		(drill 0.508)
		(layers "F.Cu" "B.Cu")
		(net "GND")
	)
	(via
		(at 348.3864 -21.961602)
		(size 0.508)
		(drill 0.254)
		(layers "F.Cu" "B.Cu")
		(net "GND")
	)
	(via
		(at 217.2208 -28.3718)
		(size 1.016)
		(drill 0.508)
		(layers "F.Cu" "B.Cu")
		(net "GND")
	)
	(via
		(at 44.2468 -24.4602)
		(size 1.016)
		(drill 0.508)
		(layers "F.Cu" "B.Cu")
		(net "GND")
	)
	(via
		(at 417.748466 -22.9362)
		(size 0.508)
		(drill 0.254)
		(layers "F.Cu" "B.Cu")
		(net "GND")
	)
	(via
		(at 410.294836 -24.395176)
		(size 0.508)
		(drill 0.254)
		(layers "F.Cu" "B.Cu")
		(net "GND")
	)
	(via
		(at 354.502466 -3.5306)
		(size 0.508)
		(drill 0.254)
		(layers "F.Cu" "B.Cu")
		(net "GND")
	)
	(via
		(at 194.4624 -18.9992)
		(size 0.508)
		(drill 0.254)
		(layers "F.Cu" "B.Cu")
		(net "GND")
	)
	(via
		(at 117.71249 -20.28571)
		(size 0.508)
		(drill 0.254)
		(layers "F.Cu" "B.Cu")
		(net "GND")
	)
	(via
		(at 169.885106 -29.885894)
		(size 0.508)
		(drill 0.254)
		(layers "F.Cu" "B.Cu")
		(net "GND")
	)
	(via
		(at 197.112128 -25.899872)
		(size 0.508)
		(drill 0.254)
		(layers "F.Cu" "B.Cu")
		(net "GND")
	)
	(via
		(at 58.5724 -37.1856)
		(size 1.016)
		(drill 0.508)
		(layers "F.Cu" "B.Cu")
		(net "GND")
	)
	(via
		(at 175.084994 -24.462994)
		(size 0.508)
		(drill 0.254)
		(layers "F.Cu" "B.Cu")
		(net "GND")
	)
	(via
		(at 54.229 -39.4716)
		(size 1.016)
		(drill 0.508)
		(layers "F.Cu" "B.Cu")
		(net "GND")
	)
	(via
		(at 66.7766 -26.6446)
		(size 1.016)
		(drill 0.508)
		(layers "F.Cu" "B.Cu")
		(net "GND")
	)
	(via
		(at 379.6538 -28.2448)
		(size 0.508)
		(drill 0.254)
		(layers "F.Cu" "B.Cu")
		(net "GND")
	)
	(via
		(at 35.9156 -41.8592)
		(size 0.508)
		(drill 0.254)
		(layers "F.Cu" "B.Cu")
		(net "GND")
	)
	(via
		(at 46.3804 -38.608)
		(size 1.016)
		(drill 0.508)
		(layers "F.Cu" "B.Cu")
		(net "GND")
	)
	(via
		(at 406.915112 -28.4099)
		(size 0.508)
		(drill 0.254)
		(layers "F.Cu" "B.Cu")
		(net "GND")
	)
	(via
		(at 393.284964 -31.1658)
		(size 0.508)
		(drill 0.254)
		(layers "F.Cu" "B.Cu")
		(net "GND")
	)
	(via
		(at 324.7898 -5.0292)
		(size 0.508)
		(drill 0.254)
		(layers "F.Cu" "B.Cu")
		(net "GND")
	)
	(via
		(at 48.3616 -34.6964)
		(size 1.016)
		(drill 0.508)
		(layers "F.Cu" "B.Cu")
		(net "GND")
	)
	(via
		(at 128.8288 -1.0668)
		(size 0.508)
		(drill 0.254)
		(layers "F.Cu" "B.Cu")
		(net "GND")
	)
	(via
		(at 48.7934 -41.529)
		(size 1.016)
		(drill 0.508)
		(layers "F.Cu" "B.Cu")
		(net "GND")
	)
	(via
		(at 404.5966 -25.8318)
		(size 0.508)
		(drill 0.254)
		(layers "F.Cu" "B.Cu")
		(net "GND")
	)
	(via
		(at 221.1578 -16.5608)
		(size 1.016)
		(drill 0.508)
		(layers "F.Cu" "B.Cu")
		(net "GND")
	)
	(via
		(at 121.31802 -22.5806)
		(size 0.508)
		(drill 0.254)
		(layers "F.Cu" "B.Cu")
		(net "GND")
	)
	(via
		(at 143.890238 -11.7094)
		(size 0.508)
		(drill 0.254)
		(layers "F.Cu" "B.Cu")
		(net "GND")
	)
	(via
		(at 103.6828 -5.0546)
		(size 0.508)
		(drill 0.254)
		(layers "F.Cu" "B.Cu")
		(net "GND")
	)
	(via
		(at 44.0944 -35.2298)
		(size 1.016)
		(drill 0.508)
		(layers "F.Cu" "B.Cu")
		(net "GND")
	)
	(via
		(at 123.952 -22.8092)
		(size 0.508)
		(drill 0.254)
		(layers "F.Cu" "B.Cu")
		(net "GND")
	)
	(via
		(at 399.23974 -25.899872)
		(size 0.508)
		(drill 0.254)
		(layers "F.Cu" "B.Cu")
		(net "GND")
	)
	(via
		(at 105.3846 -1.651)
		(size 0.508)
		(drill 0.254)
		(layers "F.Cu" "B.Cu")
		(net "GND")
	)
	(via
		(at 60.1472 -41.91)
		(size 1.016)
		(drill 0.508)
		(layers "F.Cu" "B.Cu")
		(net "GND")
	)
	(via
		(at 61.5696 -49.0982)
		(size 1.016)
		(drill 0.508)
		(layers "F.Cu" "B.Cu")
		(net "GND")
	)
	(via
		(at 59.563 -35.2298)
		(size 1.016)
		(drill 0.508)
		(layers "F.Cu" "B.Cu")
		(net "GND")
	)
	(via
		(at 175.189642 -22.7076)
		(size 0.508)
		(drill 0.254)
		(layers "F.Cu" "B.Cu")
		(net "GND")
	)
	(via
		(at 48.26 -38.0492)
		(size 1.016)
		(drill 0.508)
		(layers "F.Cu" "B.Cu")
		(net "GND")
	)
	(via
		(at 106.1466 -1.7018)
		(size 0.508)
		(drill 0.254)
		(layers "F.Cu" "B.Cu")
		(net "GND")
	)
	(via
		(at 141.4526 -8.89)
		(size 0.508)
		(drill 0.254)
		(layers "F.Cu" "B.Cu")
		(net "GND")
	)
	(via
		(at 146.290284 -11.7094)
		(size 0.508)
		(drill 0.254)
		(layers "F.Cu" "B.Cu")
		(net "GND")
	)
	(via
		(at 232.4608 -28.3718)
		(size 1.016)
		(drill 0.508)
		(layers "F.Cu" "B.Cu")
		(net "GND")
	)
	(via
		(at 53.1876 -15.4686)
		(size 1.016)
		(drill 0.508)
		(layers "F.Cu" "B.Cu")
		(net "GND")
	)
	(via
		(at 271.1196 -43.8404)
		(size 1.016)
		(drill 0.508)
		(layers "F.Cu" "B.Cu")
		(net "GND")
	)
	(via
		(at 387.9088 -0.9652)
		(size 0.508)
		(drill 0.254)
		(layers "F.Cu" "B.Cu")
		(net "GND")
	)
	(via
		(at 386.481066 -24.0538)
		(size 0.508)
		(drill 0.254)
		(layers "F.Cu" "B.Cu")
		(net "GND")
	)
	(via
		(at 286.3596 -43.8404)
		(size 1.016)
		(drill 0.508)
		(layers "F.Cu" "B.Cu")
		(net "GND")
	)
	(via
		(at 128.4478 -22.9108)
		(size 0.508)
		(drill 0.254)
		(layers "F.Cu" "B.Cu")
		(net "GND")
	)
	(via
		(at 85.9282 -46.6852)
		(size 1.016)
		(drill 0.508)
		(layers "F.Cu" "B.Cu")
		(net "GND")
	)
	(via
		(at 288.6964 -5.0038)
		(size 1.016)
		(drill 0.508)
		(layers "F.Cu" "B.Cu")
		(net "GND")
	)
	(via
		(at 144.145 -1.8542)
		(size 0.508)
		(drill 0.254)
		(layers "F.Cu" "B.Cu")
		(net "GND")
	)
	(via
		(at 329.3364 -8.89)
		(size 0.508)
		(drill 0.254)
		(layers "F.Cu" "B.Cu")
		(net "GND")
	)
	(via
		(at 366.3696 -2.0828)
		(size 0.508)
		(drill 0.254)
		(layers "F.Cu" "B.Cu")
		(net "GND")
	)
	(via
		(at 360.090212 -11.7094)
		(size 0.508)
		(drill 0.254)
		(layers "F.Cu" "B.Cu")
		(net "GND")
	)
	(via
		(at 406.6286 -27.6098)
		(size 0.508)
		(drill 0.254)
		(layers "F.Cu" "B.Cu")
		(net "GND")
	)
	(via
		(at 159.1564 -26.9494)
		(size 0.508)
		(drill 0.254)
		(layers "F.Cu" "B.Cu")
		(net "GND")
	)
	(via
		(at 103.5304 -8.89)
		(size 0.508)
		(drill 0.254)
		(layers "F.Cu" "B.Cu")
		(net "GND")
	)
	(via
		(at 194.094862 -24.422862)
		(size 0.508)
		(drill 0.254)
		(layers "F.Cu" "B.Cu")
		(net "GND")
	)
	(via
		(at 196.094858 -29.7942)
		(size 0.508)
		(drill 0.254)
		(layers "F.Cu" "B.Cu")
		(net "GND")
	)
	(via
		(at 412.287466 -19.0754)
		(size 0.508)
		(drill 0.254)
		(layers "F.Cu" "B.Cu")
		(net "GND")
	)
	(via
		(at 178.239928 -25.899872)
		(size 0.508)
		(drill 0.254)
		(layers "F.Cu" "B.Cu")
		(net "GND")
	)
	(via
		(at 51.8668 -24.4602)
		(size 1.016)
		(drill 0.508)
		(layers "F.Cu" "B.Cu")
		(net "GND")
	)
	(via
		(at 69.3674 -12.5984)
		(size 1.016)
		(drill 0.508)
		(layers "F.Cu" "B.Cu")
		(net "GND")
	)
	(via
		(at 141.490192 -11.7094)
		(size 0.508)
		(drill 0.254)
		(layers "F.Cu" "B.Cu")
		(net "GND")
	)
	(via
		(at 90.8304 -24.638)
		(size 0.508)
		(drill 0.254)
		(layers "F.Cu" "B.Cu")
		(net "GND")
	)
	(via
		(at 52.0954 -37.5158)
		(size 1.016)
		(drill 0.508)
		(layers "F.Cu" "B.Cu")
		(net "GND")
	)
	(via
		(at 172.9486 -33.8328)
		(size 0.508)
		(drill 0.254)
		(layers "F.Cu" "B.Cu")
		(net "GND")
	)
	(via
		(at 329.370182 -11.7094)
		(size 0.508)
		(drill 0.254)
		(layers "F.Cu" "B.Cu")
		(net "GND")
	)
	(via
		(at 228.7778 -16.5608)
		(size 1.016)
		(drill 0.508)
		(layers "F.Cu" "B.Cu")
		(net "GND")
	)
	(via
		(at 425.7294 -20.0406)
		(size 0.508)
		(drill 0.254)
		(layers "F.Cu" "B.Cu")
		(net "GND")
	)
	(via
		(at 196.7484 -22.9362)
		(size 0.508)
		(drill 0.254)
		(layers "F.Cu" "B.Cu")
		(net "GND")
	)
	(via
		(at 27.305 -15.113)
		(size 0.508)
		(drill 0.254)
		(layers "F.Cu" "B.Cu")
		(net "GND")
	)
	(via
		(at 53.6702 -35.2044)
		(size 1.016)
		(drill 0.508)
		(layers "F.Cu" "B.Cu")
		(net "GND")
	)
	(via
		(at 105.97007 -8.89)
		(size 0.508)
		(drill 0.254)
		(layers "F.Cu" "B.Cu")
		(net "GND")
	)
	(via
		(at 191.29502 -29.7942)
		(size 0.508)
		(drill 0.254)
		(layers "F.Cu" "B.Cu")
		(net "GND")
	)
	(via
		(at 91.2114 -46.8376)
		(size 1.016)
		(drill 0.508)
		(layers "F.Cu" "B.Cu")
		(net "GND")
	)
	(via
		(at 326.5932 -1.4986)
		(size 0.508)
		(drill 0.254)
		(layers "F.Cu" "B.Cu")
		(net "GND")
	)
	(via
		(at 166.4208 -1.0414)
		(size 0.508)
		(drill 0.254)
		(layers "F.Cu" "B.Cu")
		(net "GND")
	)
	(via
		(at 174.684944 -30.1498)
		(size 0.508)
		(drill 0.254)
		(layers "F.Cu" "B.Cu")
		(net "GND")
	)
	(via
		(at 146.2024 -1.9304)
		(size 0.508)
		(drill 0.254)
		(layers "F.Cu" "B.Cu")
		(net "GND")
	)
	(via
		(at 388.233412 -26.035)
		(size 0.508)
		(drill 0.254)
		(layers "F.Cu" "B.Cu")
		(net "GND")
	)
	(via
		(at 105.97007 -11.7094)
		(size 0.508)
		(drill 0.254)
		(layers "F.Cu" "B.Cu")
		(net "GND")
	)
	(via
		(at 165.481 -24.0538)
		(size 0.508)
		(drill 0.254)
		(layers "F.Cu" "B.Cu")
		(net "GND")
	)
	(via
		(at 224.8916 -43.942)
		(size 1.016)
		(drill 0.508)
		(layers "F.Cu" "B.Cu")
		(net "GND")
	)
	(via
		(at 336.620866 -8.5852)
		(size 0.508)
		(drill 0.254)
		(layers "F.Cu" "B.Cu")
		(net "GND")
	)
	(via
		(at 323.342 -1.5494)
		(size 0.508)
		(drill 0.254)
		(layers "F.Cu" "B.Cu")
		(net "GND")
	)
	(via
		(at 36.5252 -13.6144)
		(size 1.016)
		(drill 0.508)
		(layers "F.Cu" "B.Cu")
		(net "GND")
	)
	(via
		(at 91.2368 -41.8846)
		(size 1.016)
		(drill 0.508)
		(layers "F.Cu" "B.Cu")
		(net "GND")
	)
	(via
		(at 158.9278 -22.8854)
		(size 0.508)
		(drill 0.254)
		(layers "F.Cu" "B.Cu")
		(net "GND")
	)
	(via
		(at 36.7538 -37.8968)
		(size 1.016)
		(drill 0.508)
		(layers "F.Cu" "B.Cu")
		(net "GND")
	)
	(via
		(at 39.624 -35.1028)
		(size 1.016)
		(drill 0.508)
		(layers "F.Cu" "B.Cu")
		(net "GND")
	)
	(via
		(at 102.7176 -1.7272)
		(size 0.508)
		(drill 0.254)
		(layers "F.Cu" "B.Cu")
		(net "GND")
	)
	(via
		(at 58.8264 -39.3954)
		(size 1.016)
		(drill 0.508)
		(layers "F.Cu" "B.Cu")
		(net "GND")
	)
	(via
		(at 395.142466 -33.8328)
		(size 0.508)
		(drill 0.254)
		(layers "F.Cu" "B.Cu")
		(net "GND")
	)
	(via
		(at 139.090146 -11.7094)
		(size 0.508)
		(drill 0.254)
		(layers "F.Cu" "B.Cu")
		(net "GND")
	)
	(via
		(at 51.181 -39.2176)
		(size 1.016)
		(drill 0.508)
		(layers "F.Cu" "B.Cu")
		(net "GND")
	)
	(via
		(at 191.5922 -30.8356)
		(size 0.508)
		(drill 0.254)
		(layers "F.Cu" "B.Cu")
		(net "GND")
	)
	(via
		(at 379.5268 -24.8412)
		(size 0.508)
		(drill 0.254)
		(layers "F.Cu" "B.Cu")
		(net "GND")
	)
	(via
		(at 398.084802 -29.81579)
		(size 0.508)
		(drill 0.254)
		(layers "F.Cu" "B.Cu")
		(net "GND")
	)
	(via
		(at 103.6828 -5.969)
		(size 0.508)
		(drill 0.254)
		(layers "F.Cu" "B.Cu")
		(net "GND")
	)
	(via
		(at 312.3692 -24.4856)
		(size 0.508)
		(drill 0.254)
		(layers "F.Cu" "B.Cu")
		(net "GND")
	)
	(via
		(at 118.2624 -14.1986)
		(size 0.508)
		(drill 0.254)
		(layers "F.Cu" "B.Cu")
		(net "GND")
	)
	(via
		(at 169.545 -32.0548)
		(size 0.508)
		(drill 0.254)
		(layers "F.Cu" "B.Cu")
		(net "GND")
	)
	(via
		(at 60.9092 -45.3898)
		(size 1.016)
		(drill 0.508)
		(layers "F.Cu" "B.Cu")
		(net "GND")
	)
	(via
		(at 364.890304 -8.89)
		(size 0.508)
		(drill 0.254)
		(layers "F.Cu" "B.Cu")
		(net "GND")
	)
	(via
		(at 217.2716 -43.942)
		(size 1.016)
		(drill 0.508)
		(layers "F.Cu" "B.Cu")
		(net "GND")
	)
	(via
		(at 104.1908 -1.7018)
		(size 0.508)
		(drill 0.254)
		(layers "F.Cu" "B.Cu")
		(net "GND")
	)
	(via
		(at 101.0412 -4.953)
		(size 0.508)
		(drill 0.254)
		(layers "F.Cu" "B.Cu")
		(net "GND")
	)
	(via
		(at 259.7658 -16.4592)
		(size 1.016)
		(drill 0.508)
		(layers "F.Cu" "B.Cu")
		(net "GND")
	)
	(via
		(at 45.2374 -36.7284)
		(size 1.016)
		(drill 0.508)
		(layers "F.Cu" "B.Cu")
		(net "GND")
	)
	(via
		(at 194.056 -31.6738)
		(size 0.508)
		(drill 0.254)
		(layers "F.Cu" "B.Cu")
		(net "GND")
	)
	(via
		(at 133.5024 -3.5306)
		(size 0.508)
		(drill 0.254)
		(layers "F.Cu" "B.Cu")
		(net "GND")
	)
	(via
		(at 212.5472 -6.7818)
		(size 1.016)
		(drill 0.508)
		(layers "F.Cu" "B.Cu")
		(net "GND")
	)
	(via
		(at 74.7268 -24.4602)
		(size 1.016)
		(drill 0.508)
		(layers "F.Cu" "B.Cu")
		(net "GND")
	)
	(via
		(at 49.7586 -37.1602)
		(size 1.016)
		(drill 0.508)
		(layers "F.Cu" "B.Cu")
		(net "GND")
	)
	(via
		(at 36.0426 -39.2938)
		(size 1.016)
		(drill 0.508)
		(layers "F.Cu" "B.Cu")
		(net "GND")
	)
	(via
		(at 143.0274 -1.8288)
		(size 0.508)
		(drill 0.254)
		(layers "F.Cu" "B.Cu")
		(net "GND")
	)
	(via
		(at 322.170044 -8.89)
		(size 0.508)
		(drill 0.254)
		(layers "F.Cu" "B.Cu")
		(net "GND")
	)
	(via
		(at 174.9552 -1.0414)
		(size 0.508)
		(drill 0.254)
		(layers "F.Cu" "B.Cu")
		(net "GND")
	)
	(via
		(at 44.1198 -40.3098)
		(size 1.016)
		(drill 0.508)
		(layers "F.Cu" "B.Cu")
		(net "GND")
	)
	(via
		(at 308.9656 -26.0604)
		(size 0.508)
		(drill 0.254)
		(layers "F.Cu" "B.Cu")
		(net "GND")
	)
	(via
		(at 59.4868 -24.4602)
		(size 1.016)
		(drill 0.508)
		(layers "F.Cu" "B.Cu")
		(net "GND")
	)
	(via
		(at 385.6228 -14.1224)
		(size 0.508)
		(drill 0.254)
		(layers "F.Cu" "B.Cu")
		(net "GND")
	)
	(via
		(at 44.577 -38.4302)
		(size 1.016)
		(drill 0.508)
		(layers "F.Cu" "B.Cu")
		(net "GND")
	)
	(via
		(at 367.2586 -5.2832)
		(size 0.508)
		(drill 0.254)
		(layers "F.Cu" "B.Cu")
		(net "GND")
	)
	(via
		(at 395.684756 -30.1498)
		(size 0.508)
		(drill 0.254)
		(layers "F.Cu" "B.Cu")
		(net "GND")
	)
	(via
		(at 115.6716 -9.8044)
		(size 0.508)
		(drill 0.254)
		(layers "F.Cu" "B.Cu")
		(net "GND")
	)
	(via
		(at 67.1068 -24.4602)
		(size 1.016)
		(drill 0.508)
		(layers "F.Cu" "B.Cu")
		(net "GND")
	)
	(via
		(at 404.6982 -30.226)
		(size 0.508)
		(drill 0.254)
		(layers "F.Cu" "B.Cu")
		(net "GND")
	)
	(via
		(at 100.769928 -20.048728)
		(size 0.508)
		(drill 0.254)
		(layers "F.Cu" "B.Cu")
		(net "GND")
	)
	(segment
		(start 388.464552 -18.5166)
		(end 388.873492 -18.10766)
		(width 0.1778)
		(layer "F.Cu")
		(net "SAS_BLAD2_TX6_P")
	)
	(segment
		(start 395.28496 -24.808942)
		(end 395.28496 -25.899872)
		(width 0.1778)
		(layer "F.Cu")
		(net "SAS_BLAD2_TX6_P")
	)
	(segment
		(start 388.873492 -18.10766)
		(end 388.873492 -17.682972)
		(width 0.1778)
		(layer "F.Cu")
		(net "SAS_BLAD2_TX6_P")
	)
	(segment
		(start 392.685524 -17.400524)
		(end 392.687556 -17.402556)
		(width 0.1778)
		(layer "F.Cu")
		(net "SAS_BLAD2_TX6_P")
	)
	(segment
		(start 395.06017 -18.842482)
		(end 395.06017 -24.584152)
		(width 0.1778)
		(layer "F.Cu")
		(net "SAS_BLAD2_TX6_P")
	)
	(segment
		(start 388.873492 -17.682972)
		(end 389.304784 -17.25168)
		(width 0.1778)
		(layer "F.Cu")
		(net "SAS_BLAD2_TX6_P")
	)
	(segment
		(start 395.06017 -24.584152)
		(end 395.28496 -24.808942)
		(width 0.1778)
		(layer "F.Cu")
		(net "SAS_BLAD2_TX6_P")
	)
	(segment
		(start 393.046712 -17.5514)
		(end 393.769088 -17.5514)
		(width 0.1778)
		(layer "F.Cu")
		(net "SAS_BLAD2_TX6_P")
	)
	(segment
		(start 394.128244 -17.700244)
		(end 394.911326 -18.483326)
		(width 0.1778)
		(layer "F.Cu")
		(net "SAS_BLAD2_TX6_P")
	)
	(segment
		(start 389.304784 -17.25168)
		(end 392.326368 -17.25168)
		(width 0.1778)
		(layer "F.Cu")
		(net "SAS_BLAD2_TX6_P")
	)
	(via
		(at 388.464552 -18.5166)
		(size 0.508)
		(drill 0.254)
		(layers "F.Cu" "B.Cu")
		(net "SAS_BLAD2_TX6_P")
	)
	(arc
		(start 392.687556 -17.402556)
		(mid 392.852324 -17.512714)
		(end 393.046712 -17.5514)
		(width 0.1778)
		(layer "F.Cu")
		(net "SAS_BLAD2_TX6_P")
	)
	(arc
		(start 392.326368 -17.25168)
		(mid 392.520757 -17.290364)
		(end 392.685524 -17.400524)
		(width 0.1778)
		(layer "F.Cu")
		(net "SAS_BLAD2_TX6_P")
	)
	(arc
		(start 393.769088 -17.5514)
		(mid 393.963477 -17.590084)
		(end 394.128244 -17.700244)
		(width 0.1778)
		(layer "F.Cu")
		(net "SAS_BLAD2_TX6_P")
	)
	(arc
		(start 394.911326 -18.483326)
		(mid 395.021484 -18.648094)
		(end 395.06017 -18.842482)
		(width 0.1778)
		(layer "F.Cu")
		(net "SAS_BLAD2_TX6_P")
	)
	(segment
		(start 388.464552 -18.5166)
		(end 388.464806 -18.5166)
		(width 0.1524)
		(layer "In5.Cu")
		(net "SAS_BLAD2_TX6_P")
	)
	(segment
		(start 387.890004 -2.477262)
		(end 387.890004 -2.100072)
		(width 0.1524)
		(layer "In5.Cu")
		(net "SAS_BLAD2_TX6_P")
	)
	(segment
		(start 388.83463 -17.847564)
		(end 386.830824 -15.843758)
		(width 0.1524)
		(layer "In5.Cu")
		(net "SAS_BLAD2_TX6_P")
	)
	(segment
		(start 387.342126 -2.596896)
		(end 387.77037 -2.596896)
		(width 0.1524)
		(layer "In5.Cu")
		(net "SAS_BLAD2_TX6_P")
	)
	(segment
		(start 387.77037 -2.596896)
		(end 387.890004 -2.477262)
		(width 0.1524)
		(layer "In5.Cu")
		(net "SAS_BLAD2_TX6_P")
	)
	(segment
		(start 388.464806 -18.5166)
		(end 388.83463 -18.146776)
		(width 0.1524)
		(layer "In5.Cu")
		(net "SAS_BLAD2_TX6_P")
	)
	(segment
		(start 386.68198 -15.484602)
		(end 386.68198 -3.257042)
		(width 0.1524)
		(layer "In5.Cu")
		(net "SAS_BLAD2_TX6_P")
	)
	(arc
		(start 386.68198 -3.257042)
		(mid 386.732284 -3.004235)
		(end 386.875528 -2.789936)
		(width 0.1524)
		(layer "In5.Cu")
		(net "SAS_BLAD2_TX6_P")
	)
	(arc
		(start 386.830824 -15.843758)
		(mid 386.720666 -15.67899)
		(end 386.68198 -15.484602)
		(width 0.1524)
		(layer "In5.Cu")
		(net "SAS_BLAD2_TX6_P")
	)
	(arc
		(start 388.83463 -18.146776)
		(mid 388.880494 -18.078136)
		(end 388.896606 -17.99717)
		(width 0.1524)
		(layer "In5.Cu")
		(net "SAS_BLAD2_TX6_P")
	)
	(arc
		(start 386.875528 -2.789936)
		(mid 387.089648 -2.647055)
		(end 387.342126 -2.596896)
		(width 0.1524)
		(layer "In5.Cu")
		(net "SAS_BLAD2_TX6_P")
	)
	(arc
		(start 388.896606 -17.99717)
		(mid 388.8805 -17.916201)
		(end 388.83463 -17.847564)
		(width 0.1524)
		(layer "In5.Cu")
		(net "SAS_BLAD2_TX6_P")
	)
	(segment
		(start 392.884914 -24.808942)
		(end 392.685524 -24.609552)
		(width 0.1778)
		(layer "F.Cu")
		(net "SAS_BLAD2_TX7_P")
	)
	(segment
		(start 392.685524 -24.13)
		(end 393.119864 -23.69566)
		(width 0.1778)
		(layer "F.Cu")
		(net "SAS_BLAD2_TX7_P")
	)
	(segment
		(start 392.884914 -25.899872)
		(end 392.884914 -24.808942)
		(width 0.1778)
		(layer "F.Cu")
		(net "SAS_BLAD2_TX7_P")
	)
	(segment
		(start 392.685524 -24.609552)
		(end 392.685524 -24.13)
		(width 0.1778)
		(layer "F.Cu")
		(net "SAS_BLAD2_TX7_P")
	)
	(via
		(at 393.119864 -23.69566)
		(size 0.508)
		(drill 0.254)
		(layers "F.Cu" "B.Cu")
		(net "SAS_BLAD2_TX7_P")
	)
	(segment
		(start 392.660378 -24.8793)
		(end 392.492484 -25.230582)
		(width 0.1778)
		(layer "B.Cu")
		(net "SAS_BLAD2_TX7_P")
	)
	(segment
		(start 390.000998 -24.58974)
		(end 386.966206 -21.554948)
		(width 0.1778)
		(layer "B.Cu")
		(net "SAS_BLAD2_TX7_P")
	)
	(segment
		(start 391.731754 -25.781)
		(end 391.141458 -25.781)
		(width 0.1778)
		(layer "B.Cu")
		(net "SAS_BLAD2_TX7_P")
	)
	(segment
		(start 387.724396 -11.02487)
		(end 387.890004 -10.859262)
		(width 0.1778)
		(layer "B.Cu")
		(net "SAS_BLAD2_TX7_P")
	)
	(segment
		(start 392.492484 -25.230582)
		(end 392.091164 -25.631902)
		(width 0.1778)
		(layer "B.Cu")
		(net "SAS_BLAD2_TX7_P")
	)
	(segment
		(start 387.890004 -10.859262)
		(end 387.890004 -10.500106)
		(width 0.1778)
		(layer "B.Cu")
		(net "SAS_BLAD2_TX7_P")
	)
	(segment
		(start 392.660378 -24.155146)
		(end 392.660378 -24.8793)
		(width 0.1778)
		(layer "B.Cu")
		(net "SAS_BLAD2_TX7_P")
	)
	(segment
		(start 393.119864 -23.69566)
		(end 392.660378 -24.155146)
		(width 0.1778)
		(layer "B.Cu")
		(net "SAS_BLAD2_TX7_P")
	)
	(segment
		(start 386.714746 -20.947888)
		(end 386.714746 -11.555476)
		(width 0.1778)
		(layer "B.Cu")
		(net "SAS_BLAD2_TX7_P")
	)
	(segment
		(start 390.534398 -25.52954)
		(end 390.288526 -25.283668)
		(width 0.1778)
		(layer "B.Cu")
		(net "SAS_BLAD2_TX7_P")
	)
	(segment
		(start 387.245098 -11.02487)
		(end 387.724396 -11.02487)
		(width 0.1778)
		(layer "B.Cu")
		(net "SAS_BLAD2_TX7_P")
	)
	(arc
		(start 390.042146 -24.6888)
		(mid 390.031443 -24.635173)
		(end 390.000998 -24.58974)
		(width 0.1778)
		(layer "B.Cu")
		(net "SAS_BLAD2_TX7_P")
	)
	(arc
		(start 386.966206 -21.554948)
		(mid 386.780104 -21.276427)
		(end 386.714746 -20.947888)
		(width 0.1778)
		(layer "B.Cu")
		(net "SAS_BLAD2_TX7_P")
	)
	(arc
		(start 390.288526 -25.283668)
		(mid 390.106162 -25.01074)
		(end 390.042146 -24.6888)
		(width 0.1778)
		(layer "B.Cu")
		(net "SAS_BLAD2_TX7_P")
	)
	(arc
		(start 392.091164 -25.631902)
		(mid 391.926308 -25.742245)
		(end 391.731754 -25.781)
		(width 0.1778)
		(layer "B.Cu")
		(net "SAS_BLAD2_TX7_P")
	)
	(arc
		(start 391.141458 -25.781)
		(mid 390.812917 -25.715649)
		(end 390.534398 -25.52954)
		(width 0.1778)
		(layer "B.Cu")
		(net "SAS_BLAD2_TX7_P")
	)
	(arc
		(start 386.870194 -11.180064)
		(mid 387.042216 -11.065186)
		(end 387.245098 -11.02487)
		(width 0.1778)
		(layer "B.Cu")
		(net "SAS_BLAD2_TX7_P")
	)
	(arc
		(start 386.714746 -11.555476)
		(mid 386.75514 -11.35231)
		(end 386.870194 -11.180064)
		(width 0.1778)
		(layer "B.Cu")
		(net "SAS_BLAD2_TX7_P")
	)
	(segment
		(start 130.8354 -19.846798)
		(end 129.54 -21.142198)
		(width 0.1524)
		(layer "In5.Cu")
		(net "ENET1G_1_MDI0N")
	)
	(segment
		(start 128.530096 -3.143504)
		(end 128.670304 -3.003296)
		(width 0.1524)
		(layer "In5.Cu")
		(net "ENET1G_1_MDI0N")
	)
	(segment
		(start 129.54 -25.790398)
		(end 128.143 -27.187398)
		(width 0.1524)
		(layer "In5.Cu")
		(net "ENET1G_1_MDI0N")
	)
	(segment
		(start 128.670304 -3.003296)
		(end 130.054096 -3.003296)
		(width 0.1524)
		(layer "In5.Cu")
		(net "ENET1G_1_MDI0N")
	)
	(segment
		(start 130.8354 -15.907512)
		(end 130.6576 -16.085312)
		(width 0.1524)
		(layer "In5.Cu")
		(net "ENET1G_1_MDI0N")
	)
	(segment
		(start 130.6576 -18.625312)
		(end 130.6576 -19.082512)
		(width 0.1524)
		(layer "In5.Cu")
		(net "ENET1G_1_MDI0N")
	)
	(segment
		(start 130.6576 -17.812512)
		(end 130.8354 -17.990312)
		(width 0.1524)
		(layer "In5.Cu")
		(net "ENET1G_1_MDI0N")
	)
	(segment
		(start 128.143 -27.187398)
		(end 128.143 -29.861002)
		(width 0.1524)
		(layer "In5.Cu")
		(net "ENET1G_1_MDI0N")
	)
	(segment
		(start 130.8354 -3.7846)
		(end 130.8354 -15.907512)
		(width 0.1524)
		(layer "In5.Cu")
		(net "ENET1G_1_MDI0N")
	)
	(segment
		(start 128.530096 -3.50012)
		(end 128.530096 -3.143504)
		(width 0.1524)
		(layer "In5.Cu")
		(net "ENET1G_1_MDI0N")
	)
	(segment
		(start 127.185928 -36.930838)
		(end 126.710186 -35.9791)
		(width 0.1524)
		(layer "In5.Cu")
		(net "ENET1G_1_MDI0N")
	)
	(segment
		(start 130.8354 -17.177512)
		(end 130.6576 -17.355312)
		(width 0.1524)
		(layer "In5.Cu")
		(net "ENET1G_1_MDI0N")
	)
	(segment
		(start 130.6576 -16.085312)
		(end 130.6576 -16.542512)
		(width 0.1524)
		(layer "In5.Cu")
		(net "ENET1G_1_MDI0N")
	)
	(segment
		(start 130.6576 -16.542512)
		(end 130.8354 -16.720312)
		(width 0.1524)
		(layer "In5.Cu")
		(net "ENET1G_1_MDI0N")
	)
	(segment
		(start 130.6576 -19.082512)
		(end 130.8354 -19.260312)
		(width 0.1524)
		(layer "In5.Cu")
		(net "ENET1G_1_MDI0N")
	)
	(segment
		(start 130.8354 -16.720312)
		(end 130.8354 -17.177512)
		(width 0.1524)
		(layer "In5.Cu")
		(net "ENET1G_1_MDI0N")
	)
	(segment
		(start 130.8354 -17.990312)
		(end 130.8354 -18.447512)
		(width 0.1524)
		(layer "In5.Cu")
		(net "ENET1G_1_MDI0N")
	)
	(segment
		(start 128.143 -29.861002)
		(end 128.9304 -30.648402)
		(width 0.1524)
		(layer "In5.Cu")
		(net "ENET1G_1_MDI0N")
	)
	(segment
		(start 128.9304 -35.49777)
		(end 127.467868 -36.960048)
		(width 0.1524)
		(layer "In5.Cu")
		(net "ENET1G_1_MDI0N")
	)
	(segment
		(start 130.8354 -18.447512)
		(end 130.6576 -18.625312)
		(width 0.1524)
		(layer "In5.Cu")
		(net "ENET1G_1_MDI0N")
	)
	(segment
		(start 130.054096 -3.003296)
		(end 130.8354 -3.7846)
		(width 0.1524)
		(layer "In5.Cu")
		(net "ENET1G_1_MDI0N")
	)
	(segment
		(start 127.390398 -36.998656)
		(end 127.185928 -36.930838)
		(width 0.1524)
		(layer "In5.Cu")
		(net "ENET1G_1_MDI0N")
	)
	(segment
		(start 127.467868 -36.960048)
		(end 127.390398 -36.998656)
		(width 0.1524)
		(layer "In5.Cu")
		(net "ENET1G_1_MDI0N")
	)
	(segment
		(start 130.6576 -17.355312)
		(end 130.6576 -17.812512)
		(width 0.1524)
		(layer "In5.Cu")
		(net "ENET1G_1_MDI0N")
	)
	(segment
		(start 128.9304 -30.648402)
		(end 128.9304 -35.49777)
		(width 0.1524)
		(layer "In5.Cu")
		(net "ENET1G_1_MDI0N")
	)
	(segment
		(start 130.8354 -19.260312)
		(end 130.8354 -19.846798)
		(width 0.1524)
		(layer "In5.Cu")
		(net "ENET1G_1_MDI0N")
	)
	(segment
		(start 129.54 -21.142198)
		(end 129.54 -25.790398)
		(width 0.1524)
		(layer "In5.Cu")
		(net "ENET1G_1_MDI0N")
	)
	(segment
		(start 394.08481 -28.4099)
		(end 394.08481 -29.50083)
		(width 0.1778)
		(layer "F.Cu")
		(net "SAS_BLAD2_RX6_N")
	)
	(segment
		(start 394.3096 -32.48406)
		(end 393.87526 -32.9184)
		(width 0.1778)
		(layer "F.Cu")
		(net "SAS_BLAD2_RX6_N")
	)
	(segment
		(start 394.08481 -29.50083)
		(end 394.3096 -29.72562)
		(width 0.1778)
		(layer "F.Cu")
		(net "SAS_BLAD2_RX6_N")
	)
	(segment
		(start 394.3096 -29.72562)
		(end 394.3096 -32.48406)
		(width 0.1778)
		(layer "F.Cu")
		(net "SAS_BLAD2_RX6_N")
	)
	(via
		(at 393.87526 -32.9184)
		(size 0.508)
		(drill 0.254)
		(layers "F.Cu" "B.Cu")
		(net "SAS_BLAD2_RX6_N")
	)
	(segment
		(start 393.87526 -32.9184)
		(end 394.335254 -32.458406)
		(width 0.1778)
		(layer "B.Cu")
		(net "SAS_BLAD2_RX6_N")
	)
	(segment
		(start 388.998714 -15.173706)
		(end 388.828026 -14.458696)
		(width 0.1778)
		(layer "B.Cu")
		(net "SAS_BLAD2_RX6_N")
	)
	(segment
		(start 388.074154 -7.175246)
		(end 387.890004 -7.359396)
		(width 0.1778)
		(layer "B.Cu")
		(net "SAS_BLAD2_RX6_N")
	)
	(segment
		(start 388.663942 -7.232396)
		(end 388.659116 -7.22757)
		(width 0.1778)
		(layer "B.Cu")
		(net "SAS_BLAD2_RX6_N")
	)
	(segment
		(start 394.586714 -26.826464)
		(end 394.669518 -26.74366)
		(width 0.1778)
		(layer "B.Cu")
		(net "SAS_BLAD2_RX6_N")
	)
	(segment
		(start 394.404342 -21.627084)
		(end 389.75665 -16.979392)
		(width 0.1778)
		(layer "B.Cu")
		(net "SAS_BLAD2_RX6_N")
	)
	(segment
		(start 394.703808 -22.317964)
		(end 394.438378 -21.678138)
		(width 0.1778)
		(layer "B.Cu")
		(net "SAS_BLAD2_RX6_N")
	)
	(segment
		(start 394.713968 -22.374098)
		(end 394.70076 -22.322536)
		(width 0.1778)
		(layer "B.Cu")
		(net "SAS_BLAD2_RX6_N")
	)
	(segment
		(start 394.335254 -32.458406)
		(end 394.335254 -27.433524)
		(width 0.1778)
		(layer "B.Cu")
		(net "SAS_BLAD2_RX6_N")
	)
	(segment
		(start 394.715746 -26.632408)
		(end 394.715746 -22.495256)
		(width 0.1778)
		(layer "B.Cu")
		(net "SAS_BLAD2_RX6_N")
	)
	(segment
		(start 389.718042 -16.92148)
		(end 389.00735 -15.200376)
		(width 0.1778)
		(layer "B.Cu")
		(net "SAS_BLAD2_RX6_N")
	)
	(segment
		(start 394.70076 -22.322536)
		(end 394.703808 -22.317964)
		(width 0.1778)
		(layer "B.Cu")
		(net "SAS_BLAD2_RX6_N")
	)
	(segment
		(start 387.890004 -7.359396)
		(end 387.890004 -7.70001)
		(width 0.1778)
		(layer "B.Cu")
		(net "SAS_BLAD2_RX6_N")
	)
	(segment
		(start 394.715746 -22.495256)
		(end 394.713968 -22.374098)
		(width 0.1778)
		(layer "B.Cu")
		(net "SAS_BLAD2_RX6_N")
	)
	(segment
		(start 388.532878 -7.175246)
		(end 388.074154 -7.175246)
		(width 0.1778)
		(layer "B.Cu")
		(net "SAS_BLAD2_RX6_N")
	)
	(segment
		(start 388.730744 -14.05128)
		(end 388.721346 -13.97)
		(width 0.1778)
		(layer "B.Cu")
		(net "SAS_BLAD2_RX6_N")
	)
	(segment
		(start 388.828026 -14.458696)
		(end 388.730744 -14.05128)
		(width 0.1778)
		(layer "B.Cu")
		(net "SAS_BLAD2_RX6_N")
	)
	(segment
		(start 388.721346 -13.97)
		(end 388.721346 -7.370826)
		(width 0.1778)
		(layer "B.Cu")
		(net "SAS_BLAD2_RX6_N")
	)
	(arc
		(start 388.659116 -7.22757)
		(mid 388.601211 -7.188846)
		(end 388.532878 -7.175246)
		(width 0.1778)
		(layer "B.Cu")
		(net "SAS_BLAD2_RX6_N")
	)
	(arc
		(start 389.00735 -15.200376)
		(mid 389.002515 -15.187209)
		(end 388.998714 -15.173706)
		(width 0.1778)
		(layer "B.Cu")
		(net "SAS_BLAD2_RX6_N")
	)
	(arc
		(start 394.669518 -26.74366)
		(mid 394.703731 -26.692646)
		(end 394.715746 -26.632408)
		(width 0.1778)
		(layer "B.Cu")
		(net "SAS_BLAD2_RX6_N")
	)
	(arc
		(start 388.721346 -7.370826)
		(mid 388.706424 -7.295898)
		(end 388.663942 -7.232396)
		(width 0.1778)
		(layer "B.Cu")
		(net "SAS_BLAD2_RX6_N")
	)
	(arc
		(start 394.438378 -21.678138)
		(mid 394.423865 -21.650942)
		(end 394.404342 -21.627084)
		(width 0.1778)
		(layer "B.Cu")
		(net "SAS_BLAD2_RX6_N")
	)
	(arc
		(start 394.335254 -27.433524)
		(mid 394.400605 -27.104983)
		(end 394.586714 -26.826464)
		(width 0.1778)
		(layer "B.Cu")
		(net "SAS_BLAD2_RX6_N")
	)
	(arc
		(start 389.75665 -16.979392)
		(mid 389.734472 -16.95235)
		(end 389.718042 -16.92148)
		(width 0.1778)
		(layer "B.Cu")
		(net "SAS_BLAD2_RX6_N")
	)
	(via
		(at 41.0972 -22.0472)
		(size 1.016)
		(drill 0.508)
		(layers "F.Cu" "B.Cu")
		(net "P12V")
	)
	(via
		(at 217.678 -48.2092)
		(size 1.016)
		(drill 0.508)
		(layers "F.Cu" "B.Cu")
		(net "P12V")
	)
	(via
		(at 32.1564 -37.973)
		(size 1.016)
		(drill 0.508)
		(layers "F.Cu" "B.Cu")
		(net "P12V")
	)
	(via
		(at 232.918 -48.2092)
		(size 1.016)
		(drill 0.508)
		(layers "F.Cu" "B.Cu")
		(net "P12V")
	)
	(via
		(at 15.7988 -43.1546)
		(size 1.016)
		(drill 0.508)
		(layers "F.Cu" "B.Cu")
		(net "P12V")
	)
	(via
		(at 273.8882 -32.5374)
		(size 1.016)
		(drill 0.508)
		(layers "F.Cu" "B.Cu")
		(net "P12V")
	)
	(via
		(at 220.9038 -21.971)
		(size 1.016)
		(drill 0.508)
		(layers "F.Cu" "B.Cu")
		(net "P12V")
	)
	(via
		(at 236.1438 -21.971)
		(size 1.016)
		(drill 0.508)
		(layers "F.Cu" "B.Cu")
		(net "P12V")
	)
	(via
		(at 19.8628 -43.1546)
		(size 1.016)
		(drill 0.508)
		(layers "F.Cu" "B.Cu")
		(net "P12V")
	)
	(via
		(at 286.258 -48.2092)
		(size 1.016)
		(drill 0.508)
		(layers "F.Cu" "B.Cu")
		(net "P12V")
	)
	(via
		(at 213.2838 -21.971)
		(size 1.016)
		(drill 0.508)
		(layers "F.Cu" "B.Cu")
		(net "P12V")
	)
	(via
		(at 71.5772 -25.6286)
		(size 1.016)
		(drill 0.508)
		(layers "F.Cu" "B.Cu")
		(net "P12V")
	)
	(via
		(at 14.5288 -41.9862)
		(size 1.016)
		(drill 0.508)
		(layers "F.Cu" "B.Cu")
		(net "P12V")
	)
	(via
		(at 24.1046 -36.703)
		(size 1.016)
		(drill 0.508)
		(layers "F.Cu" "B.Cu")
		(net "P12V")
	)
	(via
		(at 205.6638 -21.971)
		(size 1.016)
		(drill 0.508)
		(layers "F.Cu" "B.Cu")
		(net "P12V")
	)
	(via
		(at 22.9108 -43.053)
		(size 1.016)
		(drill 0.508)
		(layers "F.Cu" "B.Cu")
		(net "P12V")
	)
	(via
		(at 65.4812 -13.0048)
		(size 1.016)
		(drill 0.508)
		(layers "F.Cu" "B.Cu")
		(net "P12V")
	)
	(via
		(at 13.1826 -41.2242)
		(size 1.016)
		(drill 0.508)
		(layers "F.Cu" "B.Cu")
		(net "P12V")
	)
	(via
		(at 28.488132 -20.914868)
		(size 0.508)
		(drill 0.254)
		(layers "F.Cu" "B.Cu")
		(net "P12V")
	)
	(via
		(at 57.3532 -4.9784)
		(size 1.016)
		(drill 0.508)
		(layers "F.Cu" "B.Cu")
		(net "P12V")
	)
	(via
		(at 46.7614 -9.2964)
		(size 1.016)
		(drill 0.508)
		(layers "F.Cu" "B.Cu")
		(net "P12V")
	)
	(via
		(at 270.1798 -3.8862)
		(size 1.016)
		(drill 0.508)
		(layers "F.Cu" "B.Cu")
		(net "P12V")
	)
	(via
		(at 263.398 -48.2092)
		(size 1.016)
		(drill 0.508)
		(layers "F.Cu" "B.Cu")
		(net "P12V")
	)
	(via
		(at 28.1686 -40.4368)
		(size 1.016)
		(drill 0.508)
		(layers "F.Cu" "B.Cu")
		(net "P12V")
	)
	(via
		(at 35.5092 -22.9108)
		(size 1.016)
		(drill 0.508)
		(layers "F.Cu" "B.Cu")
		(net "P12V")
	)
	(via
		(at 30.7848 -8.6106)
		(size 1.016)
		(drill 0.508)
		(layers "F.Cu" "B.Cu")
		(net "P12V")
	)
	(via
		(at 64.6176 -18.8722)
		(size 1.016)
		(drill 0.508)
		(layers "F.Cu" "B.Cu")
		(net "P12V")
	)
	(via
		(at 17.8816 -43.18)
		(size 1.016)
		(drill 0.508)
		(layers "F.Cu" "B.Cu")
		(net "P12V")
	)
	(via
		(at 29.9974 -41.1734)
		(size 1.016)
		(drill 0.508)
		(layers "F.Cu" "B.Cu")
		(net "P12V")
	)
	(via
		(at 27.167332 -20.864068)
		(size 0.508)
		(drill 0.254)
		(layers "F.Cu" "B.Cu")
		(net "P12V")
	)
	(via
		(at 25.5778 -41.5036)
		(size 1.016)
		(drill 0.508)
		(layers "F.Cu" "B.Cu")
		(net "P12V")
	)
	(via
		(at 262.9916 -38.7096)
		(size 1.016)
		(drill 0.508)
		(layers "F.Cu" "B.Cu")
		(net "P12V")
	)
	(via
		(at 22.352 -40.3606)
		(size 1.016)
		(drill 0.508)
		(layers "F.Cu" "B.Cu")
		(net "P12V")
	)
	(via
		(at 16.383 -41.9608)
		(size 0.508)
		(drill 0.254)
		(layers "F.Cu" "B.Cu")
		(net "P12V")
	)
	(via
		(at 24.892 -39.9034)
		(size 1.016)
		(drill 0.508)
		(layers "F.Cu" "B.Cu")
		(net "P12V")
	)
	(via
		(at 22.606 -38.1508)
		(size 1.016)
		(drill 0.508)
		(layers "F.Cu" "B.Cu")
		(net "P12V")
	)
	(via
		(at 50.2412 -7.8486)
		(size 1.016)
		(drill 0.508)
		(layers "F.Cu" "B.Cu")
		(net "P12V")
	)
	(via
		(at 40.1828 -26.0096)
		(size 1.016)
		(drill 0.508)
		(layers "F.Cu" "B.Cu")
		(net "P12V")
	)
	(via
		(at 29.758132 -20.965668)
		(size 0.508)
		(drill 0.254)
		(layers "F.Cu" "B.Cu")
		(net "P12V")
	)
	(via
		(at 52.5018 -18.4658)
		(size 1.016)
		(drill 0.508)
		(layers "F.Cu" "B.Cu")
		(net "P12V")
	)
	(via
		(at 63.9064 -25.4254)
		(size 1.016)
		(drill 0.508)
		(layers "F.Cu" "B.Cu")
		(net "P12V")
	)
	(via
		(at 243.4082 -32.5374)
		(size 1.016)
		(drill 0.508)
		(layers "F.Cu" "B.Cu")
		(net "P12V")
	)
	(via
		(at 232.5116 -38.7096)
		(size 1.016)
		(drill 0.508)
		(layers "F.Cu" "B.Cu")
		(net "P12V")
	)
	(via
		(at 30.607 -39.9288)
		(size 1.016)
		(drill 0.508)
		(layers "F.Cu" "B.Cu")
		(net "P12V")
	)
	(via
		(at 72.0344 -17.653)
		(size 1.016)
		(drill 0.508)
		(layers "F.Cu" "B.Cu")
		(net "P12V")
	)
	(via
		(at 269.7226 -21.3614)
		(size 1.016)
		(drill 0.508)
		(layers "F.Cu" "B.Cu")
		(net "P12V")
	)
	(via
		(at 293.4716 -38.7096)
		(size 1.016)
		(drill 0.508)
		(layers "F.Cu" "B.Cu")
		(net "P12V")
	)
	(via
		(at 28.4226 -41.8592)
		(size 1.016)
		(drill 0.508)
		(layers "F.Cu" "B.Cu")
		(net "P12V")
	)
	(via
		(at 33.3756 -23.1902)
		(size 1.016)
		(drill 0.508)
		(layers "F.Cu" "B.Cu")
		(net "P12V")
	)
	(via
		(at 32.8168 -25.7302)
		(size 1.016)
		(drill 0.508)
		(layers "F.Cu" "B.Cu")
		(net "P12V")
	)
	(via
		(at 40.5892 -16.5354)
		(size 1.016)
		(drill 0.508)
		(layers "F.Cu" "B.Cu")
		(net "P12V")
	)
	(via
		(at 248.158 -48.2092)
		(size 1.016)
		(drill 0.508)
		(layers "F.Cu" "B.Cu")
		(net "P12V")
	)
	(via
		(at 88.9508 -45.9994)
		(size 1.016)
		(drill 0.508)
		(layers "F.Cu" "B.Cu")
		(net "P12V")
	)
	(via
		(at 26.6446 -39.9796)
		(size 1.016)
		(drill 0.508)
		(layers "F.Cu" "B.Cu")
		(net "P12V")
	)
	(via
		(at 284.7086 -16.383)
		(size 1.016)
		(drill 0.508)
		(layers "F.Cu" "B.Cu")
		(net "P12V")
	)
	(via
		(at 49.3776 -5.1308)
		(size 1.016)
		(drill 0.508)
		(layers "F.Cu" "B.Cu")
		(net "P12V")
	)
	(via
		(at 78.1812 -25.6794)
		(size 1.016)
		(drill 0.508)
		(layers "F.Cu" "B.Cu")
		(net "P12V")
	)
	(via
		(at 76.2762 -35.56)
		(size 1.016)
		(drill 0.508)
		(layers "F.Cu" "B.Cu")
		(net "P12V")
	)
	(via
		(at 224.8916 -38.7096)
		(size 1.016)
		(drill 0.508)
		(layers "F.Cu" "B.Cu")
		(net "P12V")
	)
	(via
		(at 30.0736 -38.608)
		(size 1.016)
		(drill 0.508)
		(layers "F.Cu" "B.Cu")
		(net "P12V")
	)
	(via
		(at 206.6798 -11.1506)
		(size 1.016)
		(drill 0.508)
		(layers "F.Cu" "B.Cu")
		(net "P12V")
	)
	(via
		(at 26.8732 -42.0116)
		(size 0.508)
		(drill 0.254)
		(layers "F.Cu" "B.Cu")
		(net "P12V")
	)
	(via
		(at 281.5082 -32.5374)
		(size 1.016)
		(drill 0.508)
		(layers "F.Cu" "B.Cu")
		(net "P12V")
	)
	(via
		(at 271.018 -48.2092)
		(size 1.016)
		(drill 0.508)
		(layers "F.Cu" "B.Cu")
		(net "P12V")
	)
	(via
		(at 212.9282 -32.5374)
		(size 1.016)
		(drill 0.508)
		(layers "F.Cu" "B.Cu")
		(net "P12V")
	)
	(via
		(at 270.6116 -38.7096)
		(size 1.016)
		(drill 0.508)
		(layers "F.Cu" "B.Cu")
		(net "P12V")
	)
	(via
		(at 16.6624 -40.7416)
		(size 1.016)
		(drill 0.508)
		(layers "F.Cu" "B.Cu")
		(net "P12V")
	)
	(via
		(at 20.0152 -40.132)
		(size 1.016)
		(drill 0.508)
		(layers "F.Cu" "B.Cu")
		(net "P12V")
	)
	(via
		(at 21.209 -43.1038)
		(size 1.016)
		(drill 0.508)
		(layers "F.Cu" "B.Cu")
		(net "P12V")
	)
	(via
		(at 228.5238 -21.971)
		(size 1.016)
		(drill 0.508)
		(layers "F.Cu" "B.Cu")
		(net "P12V")
	)
	(via
		(at 21.2852 -39.243)
		(size 1.016)
		(drill 0.508)
		(layers "F.Cu" "B.Cu")
		(net "P12V")
	)
	(via
		(at 292.5826 -21.3614)
		(size 1.016)
		(drill 0.508)
		(layers "F.Cu" "B.Cu")
		(net "P12V")
	)
	(via
		(at 22.9108 -5.6896)
		(size 1.016)
		(drill 0.508)
		(layers "F.Cu" "B.Cu")
		(net "P12V")
	)
	(via
		(at 64.0588 -40.4876)
		(size 1.016)
		(drill 0.508)
		(layers "F.Cu" "B.Cu")
		(net "P12V")
	)
	(via
		(at 220.5482 -32.5374)
		(size 1.016)
		(drill 0.508)
		(layers "F.Cu" "B.Cu")
		(net "P12V")
	)
	(via
		(at 64.2112 -45.6946)
		(size 1.016)
		(drill 0.508)
		(layers "F.Cu" "B.Cu")
		(net "P12V")
	)
	(via
		(at 243.586 -4.572)
		(size 1.016)
		(drill 0.508)
		(layers "F.Cu" "B.Cu")
		(net "P12V")
	)
	(via
		(at 28.956 -36.8808)
		(size 1.016)
		(drill 0.508)
		(layers "F.Cu" "B.Cu")
		(net "P12V")
	)
	(via
		(at 240.1316 -38.7096)
		(size 1.016)
		(drill 0.508)
		(layers "F.Cu" "B.Cu")
		(net "P12V")
	)
	(via
		(at 69.4182 -24.1046)
		(size 1.016)
		(drill 0.508)
		(layers "F.Cu" "B.Cu")
		(net "P12V")
	)
	(via
		(at 50.2412 -12.192)
		(size 1.016)
		(drill 0.508)
		(layers "F.Cu" "B.Cu")
		(net "P12V")
	)
	(via
		(at 32.8168 -36.1696)
		(size 1.016)
		(drill 0.508)
		(layers "F.Cu" "B.Cu")
		(net "P12V")
	)
	(via
		(at 30.4546 -36.3728)
		(size 1.016)
		(drill 0.508)
		(layers "F.Cu" "B.Cu")
		(net "P12V")
	)
	(via
		(at 68.1482 -9.1948)
		(size 1.016)
		(drill 0.508)
		(layers "F.Cu" "B.Cu")
		(net "P12V")
	)
	(via
		(at 217.2716 -38.7096)
		(size 1.016)
		(drill 0.508)
		(layers "F.Cu" "B.Cu")
		(net "P12V")
	)
	(via
		(at 38.481 -9.0932)
		(size 1.016)
		(drill 0.508)
		(layers "F.Cu" "B.Cu")
		(net "P12V")
	)
	(via
		(at 225.298 -48.2092)
		(size 1.016)
		(drill 0.508)
		(layers "F.Cu" "B.Cu")
		(net "P12V")
	)
	(via
		(at 18.5928 -41.1734)
		(size 1.016)
		(drill 0.508)
		(layers "F.Cu" "B.Cu")
		(net "P12V")
	)
	(via
		(at 133.759448 -36.068)
		(size 0.508)
		(drill 0.254)
		(layers "F.Cu" "B.Cu")
		(net "P12V")
	)
	(via
		(at 19.5326 -5.1308)
		(size 1.016)
		(drill 0.508)
		(layers "F.Cu" "B.Cu")
		(net "P12V")
	)
	(via
		(at 247.7516 -38.7096)
		(size 1.016)
		(drill 0.508)
		(layers "F.Cu" "B.Cu")
		(net "P12V")
	)
	(via
		(at 278.2316 -38.7096)
		(size 1.016)
		(drill 0.508)
		(layers "F.Cu" "B.Cu")
		(net "P12V")
	)
	(via
		(at 258.6482 -32.5374)
		(size 1.016)
		(drill 0.508)
		(layers "F.Cu" "B.Cu")
		(net "P12V")
	)
	(via
		(at 31.180532 -20.940268)
		(size 0.508)
		(drill 0.254)
		(layers "F.Cu" "B.Cu")
		(net "P12V")
	)
	(via
		(at 235.7882 -32.5374)
		(size 1.016)
		(drill 0.508)
		(layers "F.Cu" "B.Cu")
		(net "P12V")
	)
	(via
		(at 54.9656 -25.527)
		(size 1.016)
		(drill 0.508)
		(layers "F.Cu" "B.Cu")
		(net "P12V")
	)
	(via
		(at 44.2722 -18.6182)
		(size 1.016)
		(drill 0.508)
		(layers "F.Cu" "B.Cu")
		(net "P12V")
	)
	(via
		(at 31.891732 -20.229068)
		(size 0.508)
		(drill 0.254)
		(layers "F.Cu" "B.Cu")
		(net "P12V")
	)
	(via
		(at 26.035 -7.4676)
		(size 1.016)
		(drill 0.508)
		(layers "F.Cu" "B.Cu")
		(net "P12V")
	)
	(via
		(at 31.4706 -10.414)
		(size 1.016)
		(drill 0.508)
		(layers "F.Cu" "B.Cu")
		(net "P12V")
	)
	(via
		(at 42.0624 -4.9276)
		(size 1.016)
		(drill 0.508)
		(layers "F.Cu" "B.Cu")
		(net "P12V")
	)
	(via
		(at 243.7638 -21.971)
		(size 1.016)
		(drill 0.508)
		(layers "F.Cu" "B.Cu")
		(net "P12V")
	)
	(via
		(at 255.778 -48.2092)
		(size 1.016)
		(drill 0.508)
		(layers "F.Cu" "B.Cu")
		(net "P12V")
	)
	(via
		(at 25.908 -36.0426)
		(size 1.016)
		(drill 0.508)
		(layers "F.Cu" "B.Cu")
		(net "P12V")
	)
	(via
		(at 278.638 -48.2092)
		(size 1.016)
		(drill 0.508)
		(layers "F.Cu" "B.Cu")
		(net "P12V")
	)
	(via
		(at 36.6014 -18.5166)
		(size 1.016)
		(drill 0.508)
		(layers "F.Cu" "B.Cu")
		(net "P12V")
	)
	(via
		(at 58.2168 -7.8486)
		(size 1.016)
		(drill 0.508)
		(layers "F.Cu" "B.Cu")
		(net "P12V")
	)
	(via
		(at 67.9958 -36.8808)
		(size 1.016)
		(drill 0.508)
		(layers "F.Cu" "B.Cu")
		(net "P12V")
	)
	(via
		(at 26.543 -38.1762)
		(size 1.016)
		(drill 0.508)
		(layers "F.Cu" "B.Cu")
		(net "P12V")
	)
	(via
		(at 264.922 -11.557)
		(size 1.016)
		(drill 0.508)
		(layers "F.Cu" "B.Cu")
		(net "P12V")
	)
	(via
		(at 13.5128 -43.053)
		(size 1.016)
		(drill 0.508)
		(layers "F.Cu" "B.Cu")
		(net "P12V")
	)
	(via
		(at 266.2682 -32.5374)
		(size 1.016)
		(drill 0.508)
		(layers "F.Cu" "B.Cu")
		(net "P12V")
	)
	(via
		(at 35.2298 -16.129)
		(size 1.016)
		(drill 0.508)
		(layers "F.Cu" "B.Cu")
		(net "P12V")
	)
	(via
		(at 24.6126 -43.053)
		(size 1.016)
		(drill 0.508)
		(layers "F.Cu" "B.Cu")
		(net "P12V")
	)
	(via
		(at 88.9 -41.0972)
		(size 1.016)
		(drill 0.508)
		(layers "F.Cu" "B.Cu")
		(net "P12V")
	)
	(via
		(at 272.542 -11.557)
		(size 1.016)
		(drill 0.508)
		(layers "F.Cu" "B.Cu")
		(net "P12V")
	)
	(via
		(at 23.5204 -39.3192)
		(size 1.016)
		(drill 0.508)
		(layers "F.Cu" "B.Cu")
		(net "P12V")
	)
	(via
		(at 49.6824 -16.2814)
		(size 1.016)
		(drill 0.508)
		(layers "F.Cu" "B.Cu")
		(net "P12V")
	)
	(via
		(at 285.8516 -38.7096)
		(size 1.016)
		(drill 0.508)
		(layers "F.Cu" "B.Cu")
		(net "P12V")
	)
	(via
		(at 277.3426 -21.3614)
		(size 1.016)
		(drill 0.508)
		(layers "F.Cu" "B.Cu")
		(net "P12V")
	)
	(via
		(at 42.6974 -12.2936)
		(size 1.016)
		(drill 0.508)
		(layers "F.Cu" "B.Cu")
		(net "P12V")
	)
	(via
		(at 54.5338 -9.0932)
		(size 1.016)
		(drill 0.508)
		(layers "F.Cu" "B.Cu")
		(net "P12V")
	)
	(via
		(at 71.374 -45.8978)
		(size 1.016)
		(drill 0.508)
		(layers "F.Cu" "B.Cu")
		(net "P12V")
	)
	(via
		(at 25.146 -37.8206)
		(size 1.016)
		(drill 0.508)
		(layers "F.Cu" "B.Cu")
		(net "P12V")
	)
	(via
		(at 20.7264 -41.3004)
		(size 1.016)
		(drill 0.508)
		(layers "F.Cu" "B.Cu")
		(net "P12V")
	)
	(via
		(at 255.3716 -38.7096)
		(size 1.016)
		(drill 0.508)
		(layers "F.Cu" "B.Cu")
		(net "P12V")
	)
	(via
		(at 251.3838 -21.971)
		(size 1.016)
		(drill 0.508)
		(layers "F.Cu" "B.Cu")
		(net "P12V")
	)
	(via
		(at 27.2288 -4.9022)
		(size 1.016)
		(drill 0.508)
		(layers "F.Cu" "B.Cu")
		(net "P12V")
	)
	(via
		(at 240.538 -48.2092)
		(size 1.016)
		(drill 0.508)
		(layers "F.Cu" "B.Cu")
		(net "P12V")
	)
	(via
		(at 293.878 -48.2092)
		(size 1.016)
		(drill 0.508)
		(layers "F.Cu" "B.Cu")
		(net "P12V")
	)
	(via
		(at 28.3972 -38.5572)
		(size 1.016)
		(drill 0.508)
		(layers "F.Cu" "B.Cu")
		(net "P12V")
	)
	(via
		(at 29.2862 -43.2308)
		(size 1.016)
		(drill 0.508)
		(layers "F.Cu" "B.Cu")
		(net "P12V")
	)
	(via
		(at 62.2046 -9.2964)
		(size 1.016)
		(drill 0.508)
		(layers "F.Cu" "B.Cu")
		(net "P12V")
	)
	(via
		(at 22.7076 -41.9862)
		(size 0.508)
		(drill 0.254)
		(layers "F.Cu" "B.Cu")
		(net "P12V")
	)
	(via
		(at 27.5844 -36.3474)
		(size 1.016)
		(drill 0.508)
		(layers "F.Cu" "B.Cu")
		(net "P12V")
	)
	(via
		(at 291.3634 -16.383)
		(size 1.016)
		(drill 0.508)
		(layers "F.Cu" "B.Cu")
		(net "P12V")
	)
	(via
		(at 228.1682 -32.5374)
		(size 1.016)
		(drill 0.508)
		(layers "F.Cu" "B.Cu")
		(net "P12V")
	)
	(via
		(at 251.0282 -32.5374)
		(size 1.016)
		(drill 0.508)
		(layers "F.Cu" "B.Cu")
		(net "P12V")
	)
	(via
		(at 71.12 -40.5892)
		(size 1.016)
		(drill 0.508)
		(layers "F.Cu" "B.Cu")
		(net "P12V")
	)
	(via
		(at 64.6176 -4.8768)
		(size 1.016)
		(drill 0.508)
		(layers "F.Cu" "B.Cu")
		(net "P12V")
	)
	(via
		(at 27.051 -43.2562)
		(size 1.016)
		(drill 0.508)
		(layers "F.Cu" "B.Cu")
		(net "P12V")
	)
	(via
		(at 284.9626 -21.3614)
		(size 1.016)
		(drill 0.508)
		(layers "F.Cu" "B.Cu")
		(net "P12V")
	)
	(via
		(at 262.1026 -21.3614)
		(size 1.016)
		(drill 0.508)
		(layers "F.Cu" "B.Cu")
		(net "P12V")
	)
	(via
		(at 46.0756 -21.5138)
		(size 1.016)
		(drill 0.508)
		(layers "F.Cu" "B.Cu")
		(net "P12V")
	)
	(via
		(at 23.8506 -41.3766)
		(size 1.016)
		(drill 0.508)
		(layers "F.Cu" "B.Cu")
		(net "P12V")
	)
	(segment
		(start 322.73494 -5.57784)
		(end 323.07022 -5.91312)
		(width 0.24384)
		(layer "F.Cu")
		(net "ENET10G_4_RDN")
	)
	(segment
		(start 322.970144 -8.952484)
		(end 322.970144 -10.290048)
		(width 0.24384)
		(layer "F.Cu")
		(net "ENET10G_4_RDN")
	)
	(segment
		(start 323.07022 -5.91312)
		(end 323.07022 -8.852408)
		(width 0.24384)
		(layer "F.Cu")
		(net "ENET10G_4_RDN")
	)
	(segment
		(start 323.07022 -8.852408)
		(end 322.970144 -8.952484)
		(width 0.24384)
		(layer "F.Cu")
		(net "ENET10G_4_RDN")
	)
	(via
		(at 322.73494 -5.57784)
		(size 0.508)
		(drill 0.254)
		(layers "F.Cu" "B.Cu")
		(net "ENET10G_4_RDN")
	)
	(segment
		(start 323.142864 -6.943598)
		(end 323.518022 -7.318756)
		(width 0.24384)
		(layer "B.Cu")
		(net "ENET10G_4_RDN")
	)
	(segment
		(start 339.129878 -8.599678)
		(end 339.530182 -8.999982)
		(width 0.24384)
		(layer "B.Cu")
		(net "ENET10G_4_RDN")
	)
	(segment
		(start 336.707988 -7.183374)
		(end 337.799934 -8.27532)
		(width 0.24384)
		(layer "B.Cu")
		(net "ENET10G_4_RDN")
	)
	(segment
		(start 322.73494 -5.57784)
		(end 322.99402 -5.83692)
		(width 0.24384)
		(layer "B.Cu")
		(net "ENET10G_4_RDN")
	)
	(segment
		(start 324.90791 -7.318756)
		(end 324.965822 -7.260844)
		(width 0.24384)
		(layer "B.Cu")
		(net "ENET10G_4_RDN")
	)
	(segment
		(start 323.877178 -7.4676)
		(end 324.548754 -7.4676)
		(width 0.24384)
		(layer "B.Cu")
		(net "ENET10G_4_RDN")
	)
	(segment
		(start 325.324978 -7.112)
		(end 336.535522 -7.112)
		(width 0.24384)
		(layer "B.Cu")
		(net "ENET10G_4_RDN")
	)
	(segment
		(start 338.583016 -8.599678)
		(end 339.129878 -8.599678)
		(width 0.24384)
		(layer "B.Cu")
		(net "ENET10G_4_RDN")
	)
	(segment
		(start 322.99402 -5.83692)
		(end 322.99402 -6.584442)
		(width 0.24384)
		(layer "B.Cu")
		(net "ENET10G_4_RDN")
	)
	(arc
		(start 324.548754 -7.4676)
		(mid 324.743143 -7.428916)
		(end 324.90791 -7.318756)
		(width 0.24384)
		(layer "B.Cu")
		(net "ENET10G_4_RDN")
	)
	(arc
		(start 323.518022 -7.318756)
		(mid 323.68279 -7.428914)
		(end 323.877178 -7.4676)
		(width 0.24384)
		(layer "B.Cu")
		(net "ENET10G_4_RDN")
	)
	(arc
		(start 322.99402 -6.584442)
		(mid 323.032704 -6.778831)
		(end 323.142864 -6.943598)
		(width 0.24384)
		(layer "B.Cu")
		(net "ENET10G_4_RDN")
	)
	(arc
		(start 324.965822 -7.260844)
		(mid 325.13059 -7.150686)
		(end 325.324978 -7.112)
		(width 0.24384)
		(layer "B.Cu")
		(net "ENET10G_4_RDN")
	)
	(arc
		(start 336.535522 -7.112)
		(mid 336.62885 -7.130546)
		(end 336.707988 -7.183374)
		(width 0.24384)
		(layer "B.Cu")
		(net "ENET10G_4_RDN")
	)
	(arc
		(start 337.799934 -8.27532)
		(mid 338.159215 -8.515384)
		(end 338.583016 -8.599678)
		(width 0.24384)
		(layer "B.Cu")
		(net "ENET10G_4_RDN")
	)
	(segment
		(start 389.450072 -17.6022)
		(end 392.326368 -17.6022)
		(width 0.1778)
		(layer "F.Cu")
		(net "SAS_BLAD2_TX6_N")
	)
	(segment
		(start 393.88034 -17.948148)
		(end 394.663422 -18.73123)
		(width 0.1778)
		(layer "F.Cu")
		(net "SAS_BLAD2_TX6_N")
	)
	(segment
		(start 389.734552 -18.5166)
		(end 389.224012 -18.00606)
		(width 0.1778)
		(layer "F.Cu")
		(net "SAS_BLAD2_TX6_N")
	)
	(segment
		(start 393.046712 -17.90192)
		(end 393.769088 -17.90192)
		(width 0.1778)
		(layer "F.Cu")
		(net "SAS_BLAD2_TX6_N")
	)
	(segment
		(start 394.70965 -18.842482)
		(end 394.70965 -24.584152)
		(width 0.1778)
		(layer "F.Cu")
		(net "SAS_BLAD2_TX6_N")
	)
	(segment
		(start 392.43762 -17.648428)
		(end 392.439652 -17.65046)
		(width 0.1778)
		(layer "F.Cu")
		(net "SAS_BLAD2_TX6_N")
	)
	(segment
		(start 389.224012 -17.82826)
		(end 389.450072 -17.6022)
		(width 0.1778)
		(layer "F.Cu")
		(net "SAS_BLAD2_TX6_N")
	)
	(segment
		(start 394.48486 -24.808942)
		(end 394.48486 -25.899872)
		(width 0.1778)
		(layer "F.Cu")
		(net "SAS_BLAD2_TX6_N")
	)
	(segment
		(start 394.70965 -24.584152)
		(end 394.48486 -24.808942)
		(width 0.1778)
		(layer "F.Cu")
		(net "SAS_BLAD2_TX6_N")
	)
	(segment
		(start 389.224012 -18.00606)
		(end 389.224012 -17.82826)
		(width 0.1778)
		(layer "F.Cu")
		(net "SAS_BLAD2_TX6_N")
	)
	(via
		(at 389.734552 -18.5166)
		(size 0.508)
		(drill 0.254)
		(layers "F.Cu" "B.Cu")
		(net "SAS_BLAD2_TX6_N")
	)
	(arc
		(start 392.326368 -17.6022)
		(mid 392.386604 -17.614218)
		(end 392.43762 -17.648428)
		(width 0.1778)
		(layer "F.Cu")
		(net "SAS_BLAD2_TX6_N")
	)
	(arc
		(start 393.769088 -17.90192)
		(mid 393.829324 -17.913938)
		(end 393.88034 -17.948148)
		(width 0.1778)
		(layer "F.Cu")
		(net "SAS_BLAD2_TX6_N")
	)
	(arc
		(start 394.663422 -18.73123)
		(mid 394.697635 -18.782244)
		(end 394.70965 -18.842482)
		(width 0.1778)
		(layer "F.Cu")
		(net "SAS_BLAD2_TX6_N")
	)
	(arc
		(start 392.439652 -17.65046)
		(mid 392.718173 -17.836562)
		(end 393.046712 -17.90192)
		(width 0.1778)
		(layer "F.Cu")
		(net "SAS_BLAD2_TX6_N")
	)
	(segment
		(start 387.890004 -3.110738)
		(end 387.890004 -3.50012)
		(width 0.1524)
		(layer "In5.Cu")
		(net "SAS_BLAD2_TX6_N")
	)
	(segment
		(start 389.302752 -18.0848)
		(end 389.303006 -18.0848)
		(width 0.1524)
		(layer "In5.Cu")
		(net "SAS_BLAD2_TX6_N")
	)
	(segment
		(start 387.08838 -15.150846)
		(end 387.268466 -14.971014)
		(width 0.1524)
		(layer "In5.Cu")
		(net "SAS_BLAD2_TX6_N")
	)
	(segment
		(start 387.782562 -3.003296)
		(end 387.890004 -3.110738)
		(width 0.1524)
		(layer "In5.Cu")
		(net "SAS_BLAD2_TX6_N")
	)
	(segment
		(start 389.122158 -17.560036)
		(end 388.094474 -16.532352)
		(width 0.1524)
		(layer "In5.Cu")
		(net "SAS_BLAD2_TX6_N")
	)
	(segment
		(start 387.268466 -14.971014)
		(end 387.268466 -14.513814)
		(width 0.1524)
		(layer "In5.Cu")
		(net "SAS_BLAD2_TX6_N")
	)
	(segment
		(start 388.094474 -16.314928)
		(end 387.77164 -15.992094)
		(width 0.1524)
		(layer "In5.Cu")
		(net "SAS_BLAD2_TX6_N")
	)
	(segment
		(start 388.094474 -16.532352)
		(end 388.094474 -16.314928)
		(width 0.1524)
		(layer "In5.Cu")
		(net "SAS_BLAD2_TX6_N")
	)
	(segment
		(start 387.342126 -3.003296)
		(end 387.782562 -3.003296)
		(width 0.1524)
		(layer "In5.Cu")
		(net "SAS_BLAD2_TX6_N")
	)
	(segment
		(start 387.08838 -14.333982)
		(end 387.08838 -3.257042)
		(width 0.1524)
		(layer "In5.Cu")
		(net "SAS_BLAD2_TX6_N")
	)
	(segment
		(start 387.554216 -15.992094)
		(end 387.118098 -15.55623)
		(width 0.1524)
		(layer "In5.Cu")
		(net "SAS_BLAD2_TX6_N")
	)
	(segment
		(start 389.734552 -18.5166)
		(end 389.302752 -18.0848)
		(width 0.1524)
		(layer "In5.Cu")
		(net "SAS_BLAD2_TX6_N")
	)
	(segment
		(start 387.08838 -15.484602)
		(end 387.08838 -15.150846)
		(width 0.1524)
		(layer "In5.Cu")
		(net "SAS_BLAD2_TX6_N")
	)
	(segment
		(start 387.77164 -15.992094)
		(end 387.554216 -15.992094)
		(width 0.1524)
		(layer "In5.Cu")
		(net "SAS_BLAD2_TX6_N")
	)
	(segment
		(start 387.268466 -14.513814)
		(end 387.08838 -14.333982)
		(width 0.1524)
		(layer "In5.Cu")
		(net "SAS_BLAD2_TX6_N")
	)
	(arc
		(start 389.303006 -17.99717)
		(mid 389.256048 -17.760625)
		(end 389.122158 -17.560036)
		(width 0.1524)
		(layer "In5.Cu")
		(net "SAS_BLAD2_TX6_N")
	)
	(arc
		(start 387.08838 -3.257042)
		(mid 387.10773 -3.159855)
		(end 387.162802 -3.077464)
		(width 0.1524)
		(layer "In5.Cu")
		(net "SAS_BLAD2_TX6_N")
	)
	(arc
		(start 389.303006 -18.0848)
		(mid 389.304548 -18.040985)
		(end 389.303006 -17.99717)
		(width 0.1524)
		(layer "In5.Cu")
		(net "SAS_BLAD2_TX6_N")
	)
	(arc
		(start 387.118098 -15.55623)
		(mid 387.096086 -15.523381)
		(end 387.08838 -15.484602)
		(width 0.1524)
		(layer "In5.Cu")
		(net "SAS_BLAD2_TX6_N")
	)
	(arc
		(start 387.162802 -3.077464)
		(mid 387.245091 -3.022544)
		(end 387.342126 -3.003296)
		(width 0.1524)
		(layer "In5.Cu")
		(net "SAS_BLAD2_TX6_N")
	)
	(segment
		(start 127.503936 -37.566854)
		(end 127.980186 -38.5191)
		(width 0.1524)
		(layer "In5.Cu")
		(net "ENET1G_1_MDI0P")
	)
	(segment
		(start 129.9464 -25.9588)
		(end 128.5494 -27.3558)
		(width 0.1524)
		(layer "In5.Cu")
		(net "ENET1G_1_MDI0P")
	)
	(segment
		(start 131.2418 -3.616198)
		(end 131.2418 -20.0152)
		(width 0.1524)
		(layer "In5.Cu")
		(net "ENET1G_1_MDI0P")
	)
	(segment
		(start 128.5494 -29.6926)
		(end 129.3368 -30.48)
		(width 0.1524)
		(layer "In5.Cu")
		(net "ENET1G_1_MDI0P")
	)
	(segment
		(start 129.3368 -35.666172)
		(end 127.70866 -37.294312)
		(width 0.1524)
		(layer "In5.Cu")
		(net "ENET1G_1_MDI0P")
	)
	(segment
		(start 128.530096 -2.100072)
		(end 128.530096 -2.475992)
		(width 0.1524)
		(layer "In5.Cu")
		(net "ENET1G_1_MDI0P")
	)
	(segment
		(start 129.3368 -30.48)
		(end 129.3368 -35.666172)
		(width 0.1524)
		(layer "In5.Cu")
		(net "ENET1G_1_MDI0P")
	)
	(segment
		(start 128.530096 -2.475992)
		(end 128.651 -2.596896)
		(width 0.1524)
		(layer "In5.Cu")
		(net "ENET1G_1_MDI0P")
	)
	(segment
		(start 127.572262 -37.362384)
		(end 127.503936 -37.566854)
		(width 0.1524)
		(layer "In5.Cu")
		(net "ENET1G_1_MDI0P")
	)
	(segment
		(start 129.9464 -21.3106)
		(end 129.9464 -25.9588)
		(width 0.1524)
		(layer "In5.Cu")
		(net "ENET1G_1_MDI0P")
	)
	(segment
		(start 128.651 -2.596896)
		(end 130.222498 -2.596896)
		(width 0.1524)
		(layer "In5.Cu")
		(net "ENET1G_1_MDI0P")
	)
	(segment
		(start 131.2418 -20.0152)
		(end 129.9464 -21.3106)
		(width 0.1524)
		(layer "In5.Cu")
		(net "ENET1G_1_MDI0P")
	)
	(segment
		(start 130.222498 -2.596896)
		(end 131.2418 -3.616198)
		(width 0.1524)
		(layer "In5.Cu")
		(net "ENET1G_1_MDI0P")
	)
	(segment
		(start 127.70866 -37.294312)
		(end 127.572262 -37.362384)
		(width 0.1524)
		(layer "In5.Cu")
		(net "ENET1G_1_MDI0P")
	)
	(segment
		(start 128.5494 -27.3558)
		(end 128.5494 -29.6926)
		(width 0.1524)
		(layer "In5.Cu")
		(net "ENET1G_1_MDI0P")
	)
	(segment
		(start 392.084814 -24.859742)
		(end 392.084814 -25.899872)
		(width 0.1778)
		(layer "F.Cu")
		(net "SAS_BLAD2_TX7_N")
	)
	(segment
		(start 392.335004 -24.609552)
		(end 392.084814 -24.859742)
		(width 0.1778)
		(layer "F.Cu")
		(net "SAS_BLAD2_TX7_N")
	)
	(segment
		(start 392.335004 -24.1808)
		(end 392.335004 -24.609552)
		(width 0.1778)
		(layer "F.Cu")
		(net "SAS_BLAD2_TX7_N")
	)
	(segment
		(start 391.849864 -23.69566)
		(end 392.335004 -24.1808)
		(width 0.1778)
		(layer "F.Cu")
		(net "SAS_BLAD2_TX7_N")
	)
	(via
		(at 391.849864 -23.69566)
		(size 0.508)
		(drill 0.254)
		(layers "F.Cu" "B.Cu")
		(net "SAS_BLAD2_TX7_N")
	)
	(segment
		(start 392.202162 -25.025096)
		(end 392.309858 -24.799798)
		(width 0.1778)
		(layer "B.Cu")
		(net "SAS_BLAD2_TX7_N")
	)
	(segment
		(start 387.237986 -17.702276)
		(end 387.065266 -17.874996)
		(width 0.1778)
		(layer "B.Cu")
		(net "SAS_BLAD2_TX7_N")
	)
	(segment
		(start 387.890004 -11.900154)
		(end 387.890004 -11.492738)
		(width 0.1778)
		(layer "B.Cu")
		(net "SAS_BLAD2_TX7_N")
	)
	(segment
		(start 387.237986 -20.526756)
		(end 387.065266 -20.699476)
		(width 0.1778)
		(layer "B.Cu")
		(net "SAS_BLAD2_TX7_N")
	)
	(segment
		(start 387.065266 -17.874996)
		(end 387.065266 -18.408396)
		(width 0.1778)
		(layer "B.Cu")
		(net "SAS_BLAD2_TX7_N")
	)
	(segment
		(start 387.890004 -11.492738)
		(end 387.772656 -11.37539)
		(width 0.1778)
		(layer "B.Cu")
		(net "SAS_BLAD2_TX7_N")
	)
	(segment
		(start 387.065266 -16.996156)
		(end 387.237986 -17.168876)
		(width 0.1778)
		(layer "B.Cu")
		(net "SAS_BLAD2_TX7_N")
	)
	(segment
		(start 391.141458 -25.43048)
		(end 391.731754 -25.43048)
		(width 0.1778)
		(layer "B.Cu")
		(net "SAS_BLAD2_TX7_N")
	)
	(segment
		(start 391.843006 -25.384252)
		(end 392.202162 -25.025096)
		(width 0.1778)
		(layer "B.Cu")
		(net "SAS_BLAD2_TX7_N")
	)
	(segment
		(start 392.309858 -24.155654)
		(end 391.849864 -23.69566)
		(width 0.1778)
		(layer "B.Cu")
		(net "SAS_BLAD2_TX7_N")
	)
	(segment
		(start 390.53643 -25.035764)
		(end 390.782302 -25.281636)
		(width 0.1778)
		(layer "B.Cu")
		(net "SAS_BLAD2_TX7_N")
	)
	(segment
		(start 387.065266 -20.699476)
		(end 387.065266 -20.947888)
		(width 0.1778)
		(layer "B.Cu")
		(net "SAS_BLAD2_TX7_N")
	)
	(segment
		(start 387.21411 -21.307044)
		(end 390.248902 -24.341836)
		(width 0.1778)
		(layer "B.Cu")
		(net "SAS_BLAD2_TX7_N")
	)
	(segment
		(start 387.772656 -11.37539)
		(end 387.245098 -11.37539)
		(width 0.1778)
		(layer "B.Cu")
		(net "SAS_BLAD2_TX7_N")
	)
	(segment
		(start 387.065266 -18.408396)
		(end 387.237986 -18.581116)
		(width 0.1778)
		(layer "B.Cu")
		(net "SAS_BLAD2_TX7_N")
	)
	(segment
		(start 387.237986 -19.114516)
		(end 387.065266 -19.287236)
		(width 0.1778)
		(layer "B.Cu")
		(net "SAS_BLAD2_TX7_N")
	)
	(segment
		(start 392.309858 -24.799798)
		(end 392.309858 -24.155654)
		(width 0.1778)
		(layer "B.Cu")
		(net "SAS_BLAD2_TX7_N")
	)
	(segment
		(start 387.065266 -19.287236)
		(end 387.065266 -19.820636)
		(width 0.1778)
		(layer "B.Cu")
		(net "SAS_BLAD2_TX7_N")
	)
	(segment
		(start 387.065266 -19.820636)
		(end 387.237986 -19.993356)
		(width 0.1778)
		(layer "B.Cu")
		(net "SAS_BLAD2_TX7_N")
	)
	(segment
		(start 387.237986 -17.168876)
		(end 387.237986 -17.702276)
		(width 0.1778)
		(layer "B.Cu")
		(net "SAS_BLAD2_TX7_N")
	)
	(segment
		(start 387.065266 -11.555476)
		(end 387.065266 -16.996156)
		(width 0.1778)
		(layer "B.Cu")
		(net "SAS_BLAD2_TX7_N")
	)
	(segment
		(start 387.237986 -18.581116)
		(end 387.237986 -19.114516)
		(width 0.1778)
		(layer "B.Cu")
		(net "SAS_BLAD2_TX7_N")
	)
	(segment
		(start 387.237986 -19.993356)
		(end 387.237986 -20.526756)
		(width 0.1778)
		(layer "B.Cu")
		(net "SAS_BLAD2_TX7_N")
	)
	(arc
		(start 387.118098 -11.427968)
		(mid 387.079009 -11.486469)
		(end 387.065266 -11.555476)
		(width 0.1778)
		(layer "B.Cu")
		(net "SAS_BLAD2_TX7_N")
	)
	(arc
		(start 391.731754 -25.43048)
		(mid 391.79199 -25.418462)
		(end 391.843006 -25.384252)
		(width 0.1778)
		(layer "B.Cu")
		(net "SAS_BLAD2_TX7_N")
	)
	(arc
		(start 387.245098 -11.37539)
		(mid 387.176376 -11.38906)
		(end 387.118098 -11.427968)
		(width 0.1778)
		(layer "B.Cu")
		(net "SAS_BLAD2_TX7_N")
	)
	(arc
		(start 390.782302 -25.281636)
		(mid 390.94707 -25.391794)
		(end 391.141458 -25.43048)
		(width 0.1778)
		(layer "B.Cu")
		(net "SAS_BLAD2_TX7_N")
	)
	(arc
		(start 387.065266 -20.947888)
		(mid 387.10395 -21.142277)
		(end 387.21411 -21.307044)
		(width 0.1778)
		(layer "B.Cu")
		(net "SAS_BLAD2_TX7_N")
	)
	(arc
		(start 390.248902 -24.341836)
		(mid 390.355322 -24.50101)
		(end 390.392666 -24.6888)
		(width 0.1778)
		(layer "B.Cu")
		(net "SAS_BLAD2_TX7_N")
	)
	(arc
		(start 390.392666 -24.6888)
		(mid 390.430035 -24.876579)
		(end 390.53643 -25.035764)
		(width 0.1778)
		(layer "B.Cu")
		(net "SAS_BLAD2_TX7_N")
	)
	(segment
		(start 411.895036 -25.899872)
		(end 411.895036 -24.809196)
		(width 0.1778)
		(layer "F.Cu")
		(net "SAS_BLAD2_TX3_P")
	)
	(segment
		(start 411.669992 -24.584152)
		(end 411.669992 -24.03856)
		(width 0.1778)
		(layer "F.Cu")
		(net "SAS_BLAD2_TX3_P")
	)
	(segment
		(start 411.895036 -24.809196)
		(end 411.669992 -24.584152)
		(width 0.1778)
		(layer "F.Cu")
		(net "SAS_BLAD2_TX3_P")
	)
	(segment
		(start 411.669992 -24.03856)
		(end 412.129732 -23.57882)
		(width 0.1778)
		(layer "F.Cu")
		(net "SAS_BLAD2_TX3_P")
	)
	(via
		(at 412.129732 -23.57882)
		(size 0.508)
		(drill 0.254)
		(layers "F.Cu" "B.Cu")
		(net "SAS_BLAD2_TX3_P")
	)
	(segment
		(start 402.13026 -13.8176)
		(end 402.58746 -13.8176)
		(width 0.1524)
		(layer "In5.Cu")
		(net "SAS_BLAD2_TX3_P")
	)
	(segment
		(start 400.91106 -13.8176)
		(end 401.36826 -13.8176)
		(width 0.1524)
		(layer "In5.Cu")
		(net "SAS_BLAD2_TX3_P")
	)
	(segment
		(start 395.24686 -13.642594)
		(end 395.425422 -13.821156)
		(width 0.1524)
		(layer "In5.Cu")
		(net "SAS_BLAD2_TX3_P")
	)
	(segment
		(start 395.098016 -8.697468)
		(end 395.098016 -13.283438)
		(width 0.1524)
		(layer "In5.Cu")
		(net "SAS_BLAD2_TX3_P")
	)
	(segment
		(start 399.08226 -13.97)
		(end 399.53946 -13.97)
		(width 0.1524)
		(layer "In5.Cu")
		(net "SAS_BLAD2_TX3_P")
	)
	(segment
		(start 401.36826 -13.8176)
		(end 401.52066 -13.97)
		(width 0.1524)
		(layer "In5.Cu")
		(net "SAS_BLAD2_TX3_P")
	)
	(segment
		(start 398.47266 -13.8176)
		(end 398.92986 -13.8176)
		(width 0.1524)
		(layer "In5.Cu")
		(net "SAS_BLAD2_TX3_P")
	)
	(segment
		(start 397.71066 -13.8176)
		(end 397.86306 -13.97)
		(width 0.1524)
		(layer "In5.Cu")
		(net "SAS_BLAD2_TX3_P")
	)
	(segment
		(start 411.698186 -22.531832)
		(end 411.698186 -23.147274)
		(width 0.1524)
		(layer "In5.Cu")
		(net "SAS_BLAD2_TX3_P")
	)
	(segment
		(start 393.889992 -7.600188)
		(end 393.889992 -7.892288)
		(width 0.1524)
		(layer "In5.Cu")
		(net "SAS_BLAD2_TX3_P")
	)
	(segment
		(start 401.97786 -13.97)
		(end 402.13026 -13.8176)
		(width 0.1524)
		(layer "In5.Cu")
		(net "SAS_BLAD2_TX3_P")
	)
	(segment
		(start 393.889992 -7.892288)
		(end 394.094462 -8.096758)
		(width 0.1524)
		(layer "In5.Cu")
		(net "SAS_BLAD2_TX3_P")
	)
	(segment
		(start 402.58746 -13.8176)
		(end 402.73986 -13.97)
		(width 0.1524)
		(layer "In5.Cu")
		(net "SAS_BLAD2_TX3_P")
	)
	(segment
		(start 411.698186 -23.147274)
		(end 412.129732 -23.57882)
		(width 0.1524)
		(layer "In5.Cu")
		(net "SAS_BLAD2_TX3_P")
	)
	(segment
		(start 401.52066 -13.97)
		(end 401.97786 -13.97)
		(width 0.1524)
		(layer "In5.Cu")
		(net "SAS_BLAD2_TX3_P")
	)
	(segment
		(start 400.14906 -13.8176)
		(end 400.30146 -13.97)
		(width 0.1524)
		(layer "In5.Cu")
		(net "SAS_BLAD2_TX3_P")
	)
	(segment
		(start 400.75866 -13.97)
		(end 400.91106 -13.8176)
		(width 0.1524)
		(layer "In5.Cu")
		(net "SAS_BLAD2_TX3_P")
	)
	(segment
		(start 402.73986 -13.97)
		(end 403.136354 -13.97)
		(width 0.1524)
		(layer "In5.Cu")
		(net "SAS_BLAD2_TX3_P")
	)
	(segment
		(start 397.25346 -13.8176)
		(end 397.71066 -13.8176)
		(width 0.1524)
		(layer "In5.Cu")
		(net "SAS_BLAD2_TX3_P")
	)
	(segment
		(start 403.783038 -14.23797)
		(end 411.43047 -21.885148)
		(width 0.1524)
		(layer "In5.Cu")
		(net "SAS_BLAD2_TX3_P")
	)
	(segment
		(start 397.10106 -13.97)
		(end 397.25346 -13.8176)
		(width 0.1524)
		(layer "In5.Cu")
		(net "SAS_BLAD2_TX3_P")
	)
	(segment
		(start 397.86306 -13.97)
		(end 398.32026 -13.97)
		(width 0.1524)
		(layer "In5.Cu")
		(net "SAS_BLAD2_TX3_P")
	)
	(segment
		(start 398.92986 -13.8176)
		(end 399.08226 -13.97)
		(width 0.1524)
		(layer "In5.Cu")
		(net "SAS_BLAD2_TX3_P")
	)
	(segment
		(start 398.32026 -13.97)
		(end 398.47266 -13.8176)
		(width 0.1524)
		(layer "In5.Cu")
		(net "SAS_BLAD2_TX3_P")
	)
	(segment
		(start 399.53946 -13.97)
		(end 399.69186 -13.8176)
		(width 0.1524)
		(layer "In5.Cu")
		(net "SAS_BLAD2_TX3_P")
	)
	(segment
		(start 400.30146 -13.97)
		(end 400.75866 -13.97)
		(width 0.1524)
		(layer "In5.Cu")
		(net "SAS_BLAD2_TX3_P")
	)
	(segment
		(start 399.69186 -13.8176)
		(end 400.14906 -13.8176)
		(width 0.1524)
		(layer "In5.Cu")
		(net "SAS_BLAD2_TX3_P")
	)
	(segment
		(start 395.784578 -13.97)
		(end 397.10106 -13.97)
		(width 0.1524)
		(layer "In5.Cu")
		(net "SAS_BLAD2_TX3_P")
	)
	(segment
		(start 394.094462 -8.096758)
		(end 394.497306 -8.096758)
		(width 0.1524)
		(layer "In5.Cu")
		(net "SAS_BLAD2_TX3_P")
	)
	(arc
		(start 403.136354 -13.97)
		(mid 403.486363 -14.039639)
		(end 403.783038 -14.23797)
		(width 0.1524)
		(layer "In5.Cu")
		(net "SAS_BLAD2_TX3_P")
	)
	(arc
		(start 395.425422 -13.821156)
		(mid 395.59019 -13.931314)
		(end 395.784578 -13.97)
		(width 0.1524)
		(layer "In5.Cu")
		(net "SAS_BLAD2_TX3_P")
	)
	(arc
		(start 411.43047 -21.885148)
		(mid 411.62869 -22.18185)
		(end 411.698186 -22.531832)
		(width 0.1524)
		(layer "In5.Cu")
		(net "SAS_BLAD2_TX3_P")
	)
	(arc
		(start 394.497306 -8.096758)
		(mid 394.727256 -8.142386)
		(end 394.922248 -8.272526)
		(width 0.1524)
		(layer "In5.Cu")
		(net "SAS_BLAD2_TX3_P")
	)
	(arc
		(start 394.922248 -8.272526)
		(mid 395.052383 -8.46752)
		(end 395.098016 -8.697468)
		(width 0.1524)
		(layer "In5.Cu")
		(net "SAS_BLAD2_TX3_P")
	)
	(arc
		(start 395.098016 -13.283438)
		(mid 395.1367 -13.477827)
		(end 395.24686 -13.642594)
		(width 0.1524)
		(layer "In5.Cu")
		(net "SAS_BLAD2_TX3_P")
	)
	(segment
		(start 413.895032 -29.500576)
		(end 413.895032 -28.4099)
		(width 0.1778)
		(layer "F.Cu")
		(net "SAS_BLAD2_RX2_P")
	)
	(segment
		(start 414.143952 -31.68142)
		(end 413.684212 -31.22168)
		(width 0.1778)
		(layer "F.Cu")
		(net "SAS_BLAD2_RX2_P")
	)
	(segment
		(start 413.684212 -29.711396)
		(end 413.895032 -29.500576)
		(width 0.1778)
		(layer "F.Cu")
		(net "SAS_BLAD2_RX2_P")
	)
	(segment
		(start 413.684212 -31.22168)
		(end 413.684212 -29.711396)
		(width 0.1778)
		(layer "F.Cu")
		(net "SAS_BLAD2_RX2_P")
	)
	(via
		(at 414.143952 -31.68142)
		(size 0.508)
		(drill 0.254)
		(layers "F.Cu" "B.Cu")
		(net "SAS_BLAD2_RX2_P")
	)
	(segment
		(start 408.422602 -29.943552)
		(end 408.341576 -29.747972)
		(width 0.1524)
		(layer "In5.Cu")
		(net "SAS_BLAD2_RX2_P")
	)
	(segment
		(start 393.410186 -12.296902)
		(end 393.691364 -12.296902)
		(width 0.1524)
		(layer "In5.Cu")
		(net "SAS_BLAD2_RX2_P")
	)
	(segment
		(start 393.889992 -12.098274)
		(end 393.889992 -11.800078)
		(width 0.1524)
		(layer "In5.Cu")
		(net "SAS_BLAD2_RX2_P")
	)
	(segment
		(start 410.317188 -32.03702)
		(end 409.7782 -31.671768)
		(width 0.1524)
		(layer "In5.Cu")
		(net "SAS_BLAD2_RX2_P")
	)
	(segment
		(start 392.640058 -13.885418)
		(end 392.640058 -13.06703)
		(width 0.1524)
		(layer "In5.Cu")
		(net "SAS_BLAD2_RX2_P")
	)
	(segment
		(start 408.299666 -29.536136)
		(end 408.299666 -29.442918)
		(width 0.1524)
		(layer "In5.Cu")
		(net "SAS_BLAD2_RX2_P")
	)
	(segment
		(start 413.118554 -32.9438)
		(end 412.639002 -32.9438)
		(width 0.1524)
		(layer "In5.Cu")
		(net "SAS_BLAD2_RX2_P")
	)
	(segment
		(start 414.143952 -31.68142)
		(end 413.712406 -32.112966)
		(width 0.1524)
		(layer "In5.Cu")
		(net "SAS_BLAD2_RX2_P")
	)
	(segment
		(start 408.291792 -29.404056)
		(end 407.017728 -26.329386)
		(width 0.1524)
		(layer "In5.Cu")
		(net "SAS_BLAD2_RX2_P")
	)
	(segment
		(start 409.101798 -30.993842)
		(end 408.506676 -30.100778)
		(width 0.1524)
		(layer "In5.Cu")
		(net "SAS_BLAD2_RX2_P")
	)
	(segment
		(start 398.901666 -18.6436)
		(end 396.844266 -16.8402)
		(width 0.1524)
		(layer "In5.Cu")
		(net "SAS_BLAD2_RX2_P")
	)
	(segment
		(start 413.712406 -32.112966)
		(end 413.712406 -32.349948)
		(width 0.1524)
		(layer "In5.Cu")
		(net "SAS_BLAD2_RX2_P")
	)
	(segment
		(start 406.99563 -26.296366)
		(end 401.446746 -20.747482)
		(width 0.1524)
		(layer "In5.Cu")
		(net "SAS_BLAD2_RX2_P")
	)
	(segment
		(start 398.901412 -18.6436)
		(end 398.901666 -18.6436)
		(width 0.1524)
		(layer "In5.Cu")
		(net "SAS_BLAD2_RX2_P")
	)
	(segment
		(start 412.288482 -32.874458)
		(end 410.480002 -32.12465)
		(width 0.1524)
		(layer "In5.Cu")
		(net "SAS_BLAD2_RX2_P")
	)
	(segment
		(start 393.691364 -12.296902)
		(end 393.889992 -12.098274)
		(width 0.1524)
		(layer "In5.Cu")
		(net "SAS_BLAD2_RX2_P")
	)
	(segment
		(start 398.904714 -18.646394)
		(end 398.901412 -18.6436)
		(width 0.1524)
		(layer "In5.Cu")
		(net "SAS_BLAD2_RX2_P")
	)
	(segment
		(start 392.73734 -14.120876)
		(end 392.640058 -13.885418)
		(width 0.1524)
		(layer "In5.Cu")
		(net "SAS_BLAD2_RX2_P")
	)
	(segment
		(start 394.292836 -15.676372)
		(end 392.73734 -14.120876)
		(width 0.1524)
		(layer "In5.Cu")
		(net "SAS_BLAD2_RX2_P")
	)
	(segment
		(start 401.436078 -20.73783)
		(end 398.908016 -18.649188)
		(width 0.1524)
		(layer "In5.Cu")
		(net "SAS_BLAD2_RX2_P")
	)
	(segment
		(start 409.644088 -31.561278)
		(end 409.216098 -31.133288)
		(width 0.1524)
		(layer "In5.Cu")
		(net "SAS_BLAD2_RX2_P")
	)
	(segment
		(start 396.844266 -16.8402)
		(end 394.292836 -15.676372)
		(width 0.1524)
		(layer "In5.Cu")
		(net "SAS_BLAD2_RX2_P")
	)
	(segment
		(start 413.563562 -32.709104)
		(end 413.47771 -32.794956)
		(width 0.1524)
		(layer "In5.Cu")
		(net "SAS_BLAD2_RX2_P")
	)
	(arc
		(start 398.908016 -18.649188)
		(mid 398.906356 -18.647802)
		(end 398.904714 -18.646394)
		(width 0.1524)
		(layer "In5.Cu")
		(net "SAS_BLAD2_RX2_P")
	)
	(arc
		(start 409.7782 -31.671768)
		(mid 409.708511 -31.619718)
		(end 409.644088 -31.561278)
		(width 0.1524)
		(layer "In5.Cu")
		(net "SAS_BLAD2_RX2_P")
	)
	(arc
		(start 412.639002 -32.9438)
		(mid 412.460318 -32.92643)
		(end 412.288482 -32.874458)
		(width 0.1524)
		(layer "In5.Cu")
		(net "SAS_BLAD2_RX2_P")
	)
	(arc
		(start 413.712406 -32.349948)
		(mid 413.673722 -32.544337)
		(end 413.563562 -32.709104)
		(width 0.1524)
		(layer "In5.Cu")
		(net "SAS_BLAD2_RX2_P")
	)
	(arc
		(start 413.47771 -32.794956)
		(mid 413.312942 -32.905114)
		(end 413.118554 -32.9438)
		(width 0.1524)
		(layer "In5.Cu")
		(net "SAS_BLAD2_RX2_P")
	)
	(arc
		(start 408.506676 -30.100778)
		(mid 408.460798 -30.024219)
		(end 408.422602 -29.943552)
		(width 0.1524)
		(layer "In5.Cu")
		(net "SAS_BLAD2_RX2_P")
	)
	(arc
		(start 401.446746 -20.747482)
		(mid 401.441528 -20.742528)
		(end 401.436078 -20.73783)
		(width 0.1524)
		(layer "In5.Cu")
		(net "SAS_BLAD2_RX2_P")
	)
	(arc
		(start 408.341576 -29.747972)
		(mid 408.310222 -29.644113)
		(end 408.299666 -29.536136)
		(width 0.1524)
		(layer "In5.Cu")
		(net "SAS_BLAD2_RX2_P")
	)
	(arc
		(start 408.299666 -29.442918)
		(mid 408.297663 -29.423093)
		(end 408.291792 -29.404056)
		(width 0.1524)
		(layer "In5.Cu")
		(net "SAS_BLAD2_RX2_P")
	)
	(arc
		(start 392.865864 -12.5222)
		(mid 393.11563 -12.355438)
		(end 393.410186 -12.296902)
		(width 0.1524)
		(layer "In5.Cu")
		(net "SAS_BLAD2_RX2_P")
	)
	(arc
		(start 392.640058 -13.06703)
		(mid 392.698749 -12.772149)
		(end 392.865864 -12.5222)
		(width 0.1524)
		(layer "In5.Cu")
		(net "SAS_BLAD2_RX2_P")
	)
	(arc
		(start 407.017728 -26.329386)
		(mid 407.008324 -26.311773)
		(end 406.99563 -26.296366)
		(width 0.1524)
		(layer "In5.Cu")
		(net "SAS_BLAD2_RX2_P")
	)
	(arc
		(start 410.480002 -32.12465)
		(mid 410.396377 -32.084957)
		(end 410.317188 -32.03702)
		(width 0.1524)
		(layer "In5.Cu")
		(net "SAS_BLAD2_RX2_P")
	)
	(arc
		(start 409.216098 -31.133288)
		(mid 409.1555 -31.066391)
		(end 409.101798 -30.993842)
		(width 0.1524)
		(layer "In5.Cu")
		(net "SAS_BLAD2_RX2_P")
	)
	(segment
		(start 416.295078 -29.49448)
		(end 416.051746 -29.737812)
		(width 0.1778)
		(layer "F.Cu")
		(net "SAS_BLAD2_RX1_P")
	)
	(segment
		(start 416.051746 -29.737812)
		(end 416.051746 -30.085792)
		(width 0.1778)
		(layer "F.Cu")
		(net "SAS_BLAD2_RX1_P")
	)
	(segment
		(start 416.051746 -30.085792)
		(end 416.529774 -30.56382)
		(width 0.1778)
		(layer "F.Cu")
		(net "SAS_BLAD2_RX1_P")
	)
	(segment
		(start 416.295078 -28.4099)
		(end 416.295078 -29.49448)
		(width 0.1778)
		(layer "F.Cu")
		(net "SAS_BLAD2_RX1_P")
	)
	(via
		(at 416.529774 -30.56382)
		(size 0.508)
		(drill 0.254)
		(layers "F.Cu" "B.Cu")
		(net "SAS_BLAD2_RX1_P")
	)
	(segment
		(start 406.374092 -14.431772)
		(end 405.986996 -14.04493)
		(width 0.1778)
		(layer "B.Cu")
		(net "SAS_BLAD2_RX1_P")
	)
	(segment
		(start 405.986996 -14.04493)
		(end 405.986996 -13.800836)
		(width 0.1778)
		(layer "B.Cu")
		(net "SAS_BLAD2_RX1_P")
	)
	(segment
		(start 405.986996 -13.800836)
		(end 405.609806 -13.423392)
		(width 0.1778)
		(layer "B.Cu")
		(net "SAS_BLAD2_RX1_P")
	)
	(segment
		(start 405.365458 -13.423392)
		(end 404.751794 -12.809728)
		(width 0.1778)
		(layer "B.Cu")
		(net "SAS_BLAD2_RX1_P")
	)
	(segment
		(start 404.130256 -12.18819)
		(end 398.915636 -6.97357)
		(width 0.1778)
		(layer "B.Cu")
		(net "SAS_BLAD2_RX1_P")
	)
	(segment
		(start 409.012136 -17.07007)
		(end 409.012136 -16.825722)
		(width 0.1778)
		(layer "B.Cu")
		(net "SAS_BLAD2_RX1_P")
	)
	(segment
		(start 406.618186 -14.431772)
		(end 406.374092 -14.431772)
		(width 0.1778)
		(layer "B.Cu")
		(net "SAS_BLAD2_RX1_P")
	)
	(segment
		(start 396.414752 -6.824726)
		(end 395.889988 -6.299962)
		(width 0.1778)
		(layer "B.Cu")
		(net "SAS_BLAD2_RX1_P")
	)
	(segment
		(start 408.634946 -16.448532)
		(end 408.390852 -16.448532)
		(width 0.1778)
		(layer "B.Cu")
		(net "SAS_BLAD2_RX1_P")
	)
	(segment
		(start 407.382218 -15.440152)
		(end 406.995376 -15.05331)
		(width 0.1778)
		(layer "B.Cu")
		(net "SAS_BLAD2_RX1_P")
	)
	(segment
		(start 416.529774 -30.56382)
		(end 416.070288 -30.104334)
		(width 0.1778)
		(layer "B.Cu")
		(net "SAS_BLAD2_RX1_P")
	)
	(segment
		(start 408.390852 -16.448532)
		(end 408.003756 -16.06169)
		(width 0.1778)
		(layer "B.Cu")
		(net "SAS_BLAD2_RX1_P")
	)
	(segment
		(start 404.751794 -12.56538)
		(end 404.374604 -12.18819)
		(width 0.1778)
		(layer "B.Cu")
		(net "SAS_BLAD2_RX1_P")
	)
	(segment
		(start 398.55648 -6.824726)
		(end 396.414752 -6.824726)
		(width 0.1778)
		(layer "B.Cu")
		(net "SAS_BLAD2_RX1_P")
	)
	(segment
		(start 405.609806 -13.423392)
		(end 405.365458 -13.423392)
		(width 0.1778)
		(layer "B.Cu")
		(net "SAS_BLAD2_RX1_P")
	)
	(segment
		(start 409.643326 -17.456912)
		(end 409.398978 -17.456912)
		(width 0.1778)
		(layer "B.Cu")
		(net "SAS_BLAD2_RX1_P")
	)
	(segment
		(start 406.995376 -14.808962)
		(end 406.618186 -14.431772)
		(width 0.1778)
		(layer "B.Cu")
		(net "SAS_BLAD2_RX1_P")
	)
	(segment
		(start 404.374604 -12.18819)
		(end 404.130256 -12.18819)
		(width 0.1778)
		(layer "B.Cu")
		(net "SAS_BLAD2_RX1_P")
	)
	(segment
		(start 404.751794 -12.809728)
		(end 404.751794 -12.56538)
		(width 0.1778)
		(layer "B.Cu")
		(net "SAS_BLAD2_RX1_P")
	)
	(segment
		(start 406.995376 -15.05331)
		(end 406.995376 -14.808962)
		(width 0.1778)
		(layer "B.Cu")
		(net "SAS_BLAD2_RX1_P")
	)
	(segment
		(start 415.921444 -26.544778)
		(end 414.13811 -24.761444)
		(width 0.1778)
		(layer "B.Cu")
		(net "SAS_BLAD2_RX1_P")
	)
	(segment
		(start 407.626566 -15.440152)
		(end 407.382218 -15.440152)
		(width 0.1778)
		(layer "B.Cu")
		(net "SAS_BLAD2_RX1_P")
	)
	(segment
		(start 409.012136 -16.825722)
		(end 408.634946 -16.448532)
		(width 0.1778)
		(layer "B.Cu")
		(net "SAS_BLAD2_RX1_P")
	)
	(segment
		(start 408.003756 -16.06169)
		(end 408.003756 -15.817342)
		(width 0.1778)
		(layer "B.Cu")
		(net "SAS_BLAD2_RX1_P")
	)
	(segment
		(start 408.003756 -15.817342)
		(end 407.626566 -15.440152)
		(width 0.1778)
		(layer "B.Cu")
		(net "SAS_BLAD2_RX1_P")
	)
	(segment
		(start 410.020516 -18.07845)
		(end 410.020516 -17.834102)
		(width 0.1778)
		(layer "B.Cu")
		(net "SAS_BLAD2_RX1_P")
	)
	(segment
		(start 409.398978 -17.456912)
		(end 409.012136 -17.07007)
		(width 0.1778)
		(layer "B.Cu")
		(net "SAS_BLAD2_RX1_P")
	)
	(segment
		(start 413.989266 -24.402288)
		(end 413.989266 -22.257512)
		(width 0.1778)
		(layer "B.Cu")
		(net "SAS_BLAD2_RX1_P")
	)
	(segment
		(start 413.840422 -21.898356)
		(end 410.020516 -18.07845)
		(width 0.1778)
		(layer "B.Cu")
		(net "SAS_BLAD2_RX1_P")
	)
	(segment
		(start 410.020516 -17.834102)
		(end 409.643326 -17.456912)
		(width 0.1778)
		(layer "B.Cu")
		(net "SAS_BLAD2_RX1_P")
	)
	(segment
		(start 416.070288 -30.104334)
		(end 416.070288 -26.903934)
		(width 0.1778)
		(layer "B.Cu")
		(net "SAS_BLAD2_RX1_P")
	)
	(arc
		(start 413.989266 -22.257512)
		(mid 413.950582 -22.063123)
		(end 413.840422 -21.898356)
		(width 0.1778)
		(layer "B.Cu")
		(net "SAS_BLAD2_RX1_P")
	)
	(arc
		(start 416.070288 -26.903934)
		(mid 416.031604 -26.709545)
		(end 415.921444 -26.544778)
		(width 0.1778)
		(layer "B.Cu")
		(net "SAS_BLAD2_RX1_P")
	)
	(arc
		(start 414.13811 -24.761444)
		(mid 414.027952 -24.596676)
		(end 413.989266 -24.402288)
		(width 0.1778)
		(layer "B.Cu")
		(net "SAS_BLAD2_RX1_P")
	)
	(arc
		(start 398.915636 -6.97357)
		(mid 398.750868 -6.863412)
		(end 398.55648 -6.824726)
		(width 0.1778)
		(layer "B.Cu")
		(net "SAS_BLAD2_RX1_P")
	)
	(segment
		(start 341.726266 -2.596896)
		(end 341.530178 -2.400808)
		(width 0.1524)
		(layer "In2.Cu")
		(net "ENET1G_4_MDI1P")
	)
	(segment
		(start 343.834466 -26.736802)
		(end 343.834466 -19.795998)
		(width 0.1524)
		(layer "In2.Cu")
		(net "ENET1G_4_MDI1P")
	)
	(segment
		(start 342.630252 -29.379164)
		(end 343.82583 -29.379164)
		(width 0.1524)
		(layer "In2.Cu")
		(net "ENET1G_4_MDI1P")
	)
	(segment
		(start 341.446866 -29.124402)
		(end 343.834466 -26.736802)
		(width 0.1524)
		(layer "In2.Cu")
		(net "ENET1G_4_MDI1P")
	)
	(segment
		(start 341.970868 -30.3784)
		(end 341.446866 -29.854398)
		(width 0.1524)
		(layer "In2.Cu")
		(net "ENET1G_4_MDI1P")
	)
	(segment
		(start 342.666066 -18.627598)
		(end 342.666066 -3.0226)
		(width 0.1524)
		(layer "In2.Cu")
		(net "ENET1G_4_MDI1P")
	)
	(segment
		(start 343.885266 -30.3784)
		(end 341.970868 -30.3784)
		(width 0.1524)
		(layer "In2.Cu")
		(net "ENET1G_4_MDI1P")
	)
	(segment
		(start 341.446866 -29.854398)
		(end 341.446866 -29.124402)
		(width 0.1524)
		(layer "In2.Cu")
		(net "ENET1G_4_MDI1P")
	)
	(segment
		(start 344.088466 -30.1752)
		(end 343.885266 -30.3784)
		(width 0.1524)
		(layer "In2.Cu")
		(net "ENET1G_4_MDI1P")
	)
	(segment
		(start 342.240362 -2.596896)
		(end 341.726266 -2.596896)
		(width 0.1524)
		(layer "In2.Cu")
		(net "ENET1G_4_MDI1P")
	)
	(segment
		(start 342.666066 -3.0226)
		(end 342.240362 -2.596896)
		(width 0.1524)
		(layer "In2.Cu")
		(net "ENET1G_4_MDI1P")
	)
	(segment
		(start 341.530178 -2.400808)
		(end 341.530178 -2.100072)
		(width 0.1524)
		(layer "In2.Cu")
		(net "ENET1G_4_MDI1P")
	)
	(segment
		(start 343.834466 -19.795998)
		(end 342.666066 -18.627598)
		(width 0.1524)
		(layer "In2.Cu")
		(net "ENET1G_4_MDI1P")
	)
	(segment
		(start 343.82583 -29.379164)
		(end 344.088466 -29.6418)
		(width 0.1524)
		(layer "In2.Cu")
		(net "ENET1G_4_MDI1P")
	)
	(segment
		(start 344.088466 -29.6418)
		(end 344.088466 -30.1752)
		(width 0.1524)
		(layer "In2.Cu")
		(net "ENET1G_4_MDI1P")
	)
	(segment
		(start 411.319472 -24.03856)
		(end 410.859732 -23.57882)
		(width 0.1778)
		(layer "F.Cu")
		(net "SAS_BLAD2_TX3_N")
	)
	(segment
		(start 411.319472 -24.584152)
		(end 411.319472 -24.03856)
		(width 0.1778)
		(layer "F.Cu")
		(net "SAS_BLAD2_TX3_N")
	)
	(segment
		(start 411.094936 -25.899872)
		(end 411.094936 -24.808688)
		(width 0.1778)
		(layer "F.Cu")
		(net "SAS_BLAD2_TX3_N")
	)
	(segment
		(start 411.094936 -24.808688)
		(end 411.319472 -24.584152)
		(width 0.1778)
		(layer "F.Cu")
		(net "SAS_BLAD2_TX3_N")
	)
	(via
		(at 410.859732 -23.57882)
		(size 0.508)
		(drill 0.254)
		(layers "F.Cu" "B.Cu")
		(net "SAS_BLAD2_TX3_N")
	)
	(segment
		(start 395.137894 -14.108684)
		(end 394.959586 -13.930122)
		(width 0.1524)
		(layer "In5.Cu")
		(net "SAS_BLAD2_TX3_N")
	)
	(segment
		(start 393.889992 -8.733028)
		(end 393.889992 -8.999982)
		(width 0.1524)
		(layer "In5.Cu")
		(net "SAS_BLAD2_TX3_N")
	)
	(segment
		(start 411.291786 -23.146766)
		(end 411.291786 -22.531832)
		(width 0.1524)
		(layer "In5.Cu")
		(net "SAS_BLAD2_TX3_N")
	)
	(segment
		(start 394.119862 -8.503158)
		(end 393.889992 -8.733028)
		(width 0.1524)
		(layer "In5.Cu")
		(net "SAS_BLAD2_TX3_N")
	)
	(segment
		(start 394.497306 -8.503158)
		(end 394.119862 -8.503158)
		(width 0.1524)
		(layer "In5.Cu")
		(net "SAS_BLAD2_TX3_N")
	)
	(segment
		(start 394.691616 -13.283438)
		(end 394.691616 -8.697214)
		(width 0.1524)
		(layer "In5.Cu")
		(net "SAS_BLAD2_TX3_N")
	)
	(segment
		(start 411.142942 -22.172676)
		(end 403.49551 -14.525244)
		(width 0.1524)
		(layer "In5.Cu")
		(net "SAS_BLAD2_TX3_N")
	)
	(segment
		(start 403.136354 -14.3764)
		(end 395.784578 -14.3764)
		(width 0.1524)
		(layer "In5.Cu")
		(net "SAS_BLAD2_TX3_N")
	)
	(segment
		(start 410.859732 -23.57882)
		(end 411.291786 -23.146766)
		(width 0.1524)
		(layer "In5.Cu")
		(net "SAS_BLAD2_TX3_N")
	)
	(arc
		(start 411.291786 -22.531832)
		(mid 411.253102 -22.337443)
		(end 411.142942 -22.172676)
		(width 0.1524)
		(layer "In5.Cu")
		(net "SAS_BLAD2_TX3_N")
	)
	(arc
		(start 394.63472 -8.560054)
		(mid 394.571674 -8.517928)
		(end 394.497306 -8.503158)
		(width 0.1524)
		(layer "In5.Cu")
		(net "SAS_BLAD2_TX3_N")
	)
	(arc
		(start 403.49551 -14.525244)
		(mid 403.330742 -14.415086)
		(end 403.136354 -14.3764)
		(width 0.1524)
		(layer "In5.Cu")
		(net "SAS_BLAD2_TX3_N")
	)
	(arc
		(start 394.691616 -8.697214)
		(mid 394.676777 -8.622991)
		(end 394.63472 -8.560054)
		(width 0.1524)
		(layer "In5.Cu")
		(net "SAS_BLAD2_TX3_N")
	)
	(arc
		(start 395.784578 -14.3764)
		(mid 395.434613 -14.306863)
		(end 395.137894 -14.108684)
		(width 0.1524)
		(layer "In5.Cu")
		(net "SAS_BLAD2_TX3_N")
	)
	(arc
		(start 394.959586 -13.930122)
		(mid 394.761283 -13.633435)
		(end 394.691616 -13.283438)
		(width 0.1524)
		(layer "In5.Cu")
		(net "SAS_BLAD2_TX3_N")
	)
	(segment
		(start 408.544776 -29.75102)
		(end 408.544776 -30.006036)
		(width 0.1778)
		(layer "F.Cu")
		(net "SAS_BLAD2_RX4_N")
	)
	(segment
		(start 408.299412 -30.2514)
		(end 406.292812 -30.2514)
		(width 0.1778)
		(layer "F.Cu")
		(net "SAS_BLAD2_RX4_N")
	)
	(segment
		(start 406.038812 -29.9974)
		(end 406.038812 -29.7688)
		(width 0.1778)
		(layer "F.Cu")
		(net "SAS_BLAD2_RX4_N")
	)
	(segment
		(start 408.295094 -29.501338)
		(end 408.544776 -29.75102)
		(width 0.1778)
		(layer "F.Cu")
		(net "SAS_BLAD2_RX4_N")
	)
	(segment
		(start 408.544776 -30.006036)
		(end 408.299412 -30.2514)
		(width 0.1778)
		(layer "F.Cu")
		(net "SAS_BLAD2_RX4_N")
	)
	(segment
		(start 408.295094 -28.4099)
		(end 408.295094 -29.501338)
		(width 0.1778)
		(layer "F.Cu")
		(net "SAS_BLAD2_RX4_N")
	)
	(segment
		(start 406.038812 -29.7688)
		(end 406.498552 -29.30906)
		(width 0.1778)
		(layer "F.Cu")
		(net "SAS_BLAD2_RX4_N")
	)
	(segment
		(start 406.292812 -30.2514)
		(end 406.038812 -29.9974)
		(width 0.1778)
		(layer "F.Cu")
		(net "SAS_BLAD2_RX4_N")
	)
	(via
		(at 406.498552 -29.30906)
		(size 0.508)
		(drill 0.254)
		(layers "F.Cu" "B.Cu")
		(net "SAS_BLAD2_RX4_N")
	)
	(segment
		(start 391.14222 -7.295896)
		(end 391.166096 -7.27202)
		(width 0.1524)
		(layer "In5.Cu")
		(net "SAS_BLAD2_RX4_N")
	)
	(segment
		(start 391.097262 -13.2588)
		(end 391.097262 -7.403846)
		(width 0.1524)
		(layer "In5.Cu")
		(net "SAS_BLAD2_RX4_N")
	)
	(segment
		(start 406.498552 -29.30906)
		(end 406.067006 -28.877514)
		(width 0.1524)
		(layer "In5.Cu")
		(net "SAS_BLAD2_RX4_N")
	)
	(segment
		(start 396.64894 -18.420588)
		(end 395.568678 -17.699736)
		(width 0.1524)
		(layer "In5.Cu")
		(net "SAS_BLAD2_RX4_N")
	)
	(segment
		(start 391.223246 -14.014958)
		(end 391.097262 -13.2588)
		(width 0.1524)
		(layer "In5.Cu")
		(net "SAS_BLAD2_RX4_N")
	)
	(segment
		(start 395.481048 -17.653)
		(end 394.899896 -17.412208)
		(width 0.1524)
		(layer "In5.Cu")
		(net "SAS_BLAD2_RX4_N")
	)
	(segment
		(start 391.889996 -7.357618)
		(end 391.889996 -7.70001)
		(width 0.1524)
		(layer "In5.Cu")
		(net "SAS_BLAD2_RX4_N")
	)
	(segment
		(start 403.231096 -24.989028)
		(end 402.162264 -23.920196)
		(width 0.1524)
		(layer "In5.Cu")
		(net "SAS_BLAD2_RX4_N")
	)
	(segment
		(start 401.62099 -23.378922)
		(end 401.297648 -23.05558)
		(width 0.1524)
		(layer "In5.Cu")
		(net "SAS_BLAD2_RX4_N")
	)
	(segment
		(start 394.705586 -17.3736)
		(end 394.209778 -17.3736)
		(width 0.1524)
		(layer "In5.Cu")
		(net "SAS_BLAD2_RX4_N")
	)
	(segment
		(start 404.645622 -27.689556)
		(end 403.64791 -26.691844)
		(width 0.1524)
		(layer "In5.Cu")
		(net "SAS_BLAD2_RX4_N")
	)
	(segment
		(start 391.735564 -7.203186)
		(end 391.889996 -7.357618)
		(width 0.1524)
		(layer "In5.Cu")
		(net "SAS_BLAD2_RX4_N")
	)
	(segment
		(start 403.499066 -26.332688)
		(end 403.499066 -25.635712)
		(width 0.1524)
		(layer "In5.Cu")
		(net "SAS_BLAD2_RX4_N")
	)
	(segment
		(start 391.331958 -7.203186)
		(end 391.735564 -7.203186)
		(width 0.1524)
		(layer "In5.Cu")
		(net "SAS_BLAD2_RX4_N")
	)
	(segment
		(start 401.838922 -23.378922)
		(end 401.62099 -23.378922)
		(width 0.1524)
		(layer "In5.Cu")
		(net "SAS_BLAD2_RX4_N")
	)
	(segment
		(start 400.756374 -22.514306)
		(end 396.726156 -18.484088)
		(width 0.1524)
		(layer "In5.Cu")
		(net "SAS_BLAD2_RX4_N")
	)
	(segment
		(start 402.162264 -23.920196)
		(end 402.162264 -23.702264)
		(width 0.1524)
		(layer "In5.Cu")
		(net "SAS_BLAD2_RX4_N")
	)
	(segment
		(start 401.297648 -23.05558)
		(end 401.297648 -22.837648)
		(width 0.1524)
		(layer "In5.Cu")
		(net "SAS_BLAD2_RX4_N")
	)
	(segment
		(start 405.396954 -27.8384)
		(end 405.004778 -27.8384)
		(width 0.1524)
		(layer "In5.Cu")
		(net "SAS_BLAD2_RX4_N")
	)
	(segment
		(start 402.162264 -23.702264)
		(end 401.838922 -23.378922)
		(width 0.1524)
		(layer "In5.Cu")
		(net "SAS_BLAD2_RX4_N")
	)
	(segment
		(start 391.634472 -15.008606)
		(end 391.223246 -14.014958)
		(width 0.1524)
		(layer "In5.Cu")
		(net "SAS_BLAD2_RX4_N")
	)
	(segment
		(start 393.850622 -17.224756)
		(end 391.634472 -15.008606)
		(width 0.1524)
		(layer "In5.Cu")
		(net "SAS_BLAD2_RX4_N")
	)
	(segment
		(start 405.918162 -28.149296)
		(end 405.75611 -27.987244)
		(width 0.1524)
		(layer "In5.Cu")
		(net "SAS_BLAD2_RX4_N")
	)
	(segment
		(start 400.974306 -22.514306)
		(end 400.756374 -22.514306)
		(width 0.1524)
		(layer "In5.Cu")
		(net "SAS_BLAD2_RX4_N")
	)
	(segment
		(start 401.297648 -22.837648)
		(end 400.974306 -22.514306)
		(width 0.1524)
		(layer "In5.Cu")
		(net "SAS_BLAD2_RX4_N")
	)
	(segment
		(start 406.067006 -28.877514)
		(end 406.067006 -28.508452)
		(width 0.1524)
		(layer "In5.Cu")
		(net "SAS_BLAD2_RX4_N")
	)
	(arc
		(start 405.75611 -27.987244)
		(mid 405.591342 -27.877086)
		(end 405.396954 -27.8384)
		(width 0.1524)
		(layer "In5.Cu")
		(net "SAS_BLAD2_RX4_N")
	)
	(arc
		(start 405.004778 -27.8384)
		(mid 404.810389 -27.799716)
		(end 404.645622 -27.689556)
		(width 0.1524)
		(layer "In5.Cu")
		(net "SAS_BLAD2_RX4_N")
	)
	(arc
		(start 395.568678 -17.699736)
		(mid 395.526008 -17.674222)
		(end 395.481048 -17.653)
		(width 0.1524)
		(layer "In5.Cu")
		(net "SAS_BLAD2_RX4_N")
	)
	(arc
		(start 396.726156 -18.484088)
		(mid 396.689114 -18.450433)
		(end 396.64894 -18.420588)
		(width 0.1524)
		(layer "In5.Cu")
		(net "SAS_BLAD2_RX4_N")
	)
	(arc
		(start 406.067006 -28.508452)
		(mid 406.028322 -28.314063)
		(end 405.918162 -28.149296)
		(width 0.1524)
		(layer "In5.Cu")
		(net "SAS_BLAD2_RX4_N")
	)
	(arc
		(start 391.097262 -7.403846)
		(mid 391.108947 -7.345373)
		(end 391.14222 -7.295896)
		(width 0.1524)
		(layer "In5.Cu")
		(net "SAS_BLAD2_RX4_N")
	)
	(arc
		(start 403.64791 -26.691844)
		(mid 403.537752 -26.527076)
		(end 403.499066 -26.332688)
		(width 0.1524)
		(layer "In5.Cu")
		(net "SAS_BLAD2_RX4_N")
	)
	(arc
		(start 391.166096 -7.27202)
		(mid 391.242166 -7.221065)
		(end 391.331958 -7.203186)
		(width 0.1524)
		(layer "In5.Cu")
		(net "SAS_BLAD2_RX4_N")
	)
	(arc
		(start 394.899896 -17.412208)
		(mid 394.80464 -17.383344)
		(end 394.705586 -17.3736)
		(width 0.1524)
		(layer "In5.Cu")
		(net "SAS_BLAD2_RX4_N")
	)
	(arc
		(start 394.209778 -17.3736)
		(mid 394.015389 -17.334916)
		(end 393.850622 -17.224756)
		(width 0.1524)
		(layer "In5.Cu")
		(net "SAS_BLAD2_RX4_N")
	)
	(arc
		(start 403.499066 -25.635712)
		(mid 403.429427 -25.285703)
		(end 403.231096 -24.989028)
		(width 0.1524)
		(layer "In5.Cu")
		(net "SAS_BLAD2_RX4_N")
	)
	(segment
		(start 340.255606 -30.679898)
		(end 340.302342 -30.632908)
		(width 0.1524)
		(layer "In5.Cu")
		(net "ENET1G_4_MDI0P")
	)
	(segment
		(start 340.36127 -30.603444)
		(end 340.497668 -30.535372)
		(width 0.1524)
		(layer "In5.Cu")
		(net "ENET1G_4_MDI0P")
	)
	(segment
		(start 343.530174 -3.400044)
		(end 343.530174 -3.765042)
		(width 0.1524)
		(layer "In5.Cu")
		(net "ENET1G_4_MDI0P")
	)
	(segment
		(start 343.662 -3.896868)
		(end 344.3478 -3.896868)
		(width 0.1524)
		(layer "In5.Cu")
		(net "ENET1G_4_MDI0P")
	)
	(segment
		(start 341.9094 -24.450802)
		(end 338.906866 -27.453336)
		(width 0.1524)
		(layer "In5.Cu")
		(net "ENET1G_4_MDI0P")
	)
	(segment
		(start 338.906866 -30.032198)
		(end 339.554566 -30.679898)
		(width 0.1524)
		(layer "In5.Cu")
		(net "ENET1G_4_MDI0P")
	)
	(segment
		(start 340.497668 -30.535372)
		(end 340.565994 -30.330902)
		(width 0.1524)
		(layer "In5.Cu")
		(net "ENET1G_4_MDI0P")
	)
	(segment
		(start 344.3478 -3.896868)
		(end 344.738198 -4.287266)
		(width 0.1524)
		(layer "In5.Cu")
		(net "ENET1G_4_MDI0P")
	)
	(segment
		(start 339.554566 -30.679898)
		(end 340.255606 -30.679898)
		(width 0.1524)
		(layer "In5.Cu")
		(net "ENET1G_4_MDI0P")
	)
	(segment
		(start 338.906866 -27.453336)
		(end 338.906866 -30.032198)
		(width 0.1524)
		(layer "In5.Cu")
		(net "ENET1G_4_MDI0P")
	)
	(segment
		(start 344.738198 -4.287266)
		(end 344.738198 -15.510002)
		(width 0.1524)
		(layer "In5.Cu")
		(net "ENET1G_4_MDI0P")
	)
	(segment
		(start 340.565994 -30.330902)
		(end 340.090252 -29.379164)
		(width 0.1524)
		(layer "In5.Cu")
		(net "ENET1G_4_MDI0P")
	)
	(segment
		(start 340.302342 -30.632908)
		(end 340.36127 -30.603444)
		(width 0.1524)
		(layer "In5.Cu")
		(net "ENET1G_4_MDI0P")
	)
	(segment
		(start 341.9094 -18.3388)
		(end 341.9094 -24.450802)
		(width 0.1524)
		(layer "In5.Cu")
		(net "ENET1G_4_MDI0P")
	)
	(segment
		(start 344.738198 -15.510002)
		(end 341.9094 -18.3388)
		(width 0.1524)
		(layer "In5.Cu")
		(net "ENET1G_4_MDI0P")
	)
	(segment
		(start 343.530174 -3.765042)
		(end 343.662 -3.896868)
		(width 0.1524)
		(layer "In5.Cu")
		(net "ENET1G_4_MDI0P")
	)
	(segment
		(start 327.870312 -8.852408)
		(end 327.769982 -8.952738)
		(width 0.24384)
		(layer "F.Cu")
		(net "ENET10G_4_TDP")
	)
	(segment
		(start 328.412856 -4.845558)
		(end 328.19467 -5.063744)
		(width 0.24384)
		(layer "F.Cu")
		(net "ENET10G_4_TDP")
	)
	(segment
		(start 327.769982 -8.952738)
		(end 327.769982 -10.290048)
		(width 0.24384)
		(layer "F.Cu")
		(net "ENET10G_4_TDP")
	)
	(segment
		(start 334.911954 -4.5212)
		(end 329.195938 -4.5212)
		(width 0.24384)
		(layer "F.Cu")
		(net "ENET10G_4_TDP")
	)
	(segment
		(start 336.183986 -9.1948)
		(end 335.772506 -8.78332)
		(width 0.24384)
		(layer "F.Cu")
		(net "ENET10G_4_TDP")
	)
	(segment
		(start 327.870312 -5.846826)
		(end 327.870312 -8.852408)
		(width 0.24384)
		(layer "F.Cu")
		(net "ENET10G_4_TDP")
	)
	(segment
		(start 335.772506 -8.78332)
		(end 335.772506 -5.381752)
		(width 0.24384)
		(layer "F.Cu")
		(net "ENET10G_4_TDP")
	)
	(segment
		(start 335.623662 -5.022596)
		(end 335.27111 -4.670044)
		(width 0.24384)
		(layer "F.Cu")
		(net "ENET10G_4_TDP")
	)
	(via
		(at 336.183986 -9.1948)
		(size 0.508)
		(drill 0.254)
		(layers "F.Cu" "B.Cu")
		(net "ENET10G_4_TDP")
	)
	(arc
		(start 328.19467 -5.063744)
		(mid 327.954606 -5.423025)
		(end 327.870312 -5.846826)
		(width 0.24384)
		(layer "F.Cu")
		(net "ENET10G_4_TDP")
	)
	(arc
		(start 335.772506 -5.381752)
		(mid 335.733822 -5.187363)
		(end 335.623662 -5.022596)
		(width 0.24384)
		(layer "F.Cu")
		(net "ENET10G_4_TDP")
	)
	(arc
		(start 329.195938 -4.5212)
		(mid 328.772139 -4.605499)
		(end 328.412856 -4.845558)
		(width 0.24384)
		(layer "F.Cu")
		(net "ENET10G_4_TDP")
	)
	(arc
		(start 335.27111 -4.670044)
		(mid 335.106342 -4.559886)
		(end 334.911954 -4.5212)
		(width 0.24384)
		(layer "F.Cu")
		(net "ENET10G_4_TDP")
	)
	(segment
		(start 335.92135 -11.822684)
		(end 336.150204 -12.051538)
		(width 0.24384)
		(layer "B.Cu")
		(net "ENET10G_4_TDP")
	)
	(segment
		(start 336.50936 -12.200382)
		(end 339.129878 -12.200382)
		(width 0.24384)
		(layer "B.Cu")
		(net "ENET10G_4_TDP")
	)
	(segment
		(start 335.772506 -9.60628)
		(end 335.772506 -11.463528)
		(width 0.24384)
		(layer "B.Cu")
		(net "ENET10G_4_TDP")
	)
	(segment
		(start 336.183986 -9.1948)
		(end 335.772506 -9.60628)
		(width 0.24384)
		(layer "B.Cu")
		(net "ENET10G_4_TDP")
	)
	(segment
		(start 339.129878 -12.200382)
		(end 339.530182 -11.800078)
		(width 0.24384)
		(layer "B.Cu")
		(net "ENET10G_4_TDP")
	)
	(arc
		(start 336.150204 -12.051538)
		(mid 336.314972 -12.161696)
		(end 336.50936 -12.200382)
		(width 0.24384)
		(layer "B.Cu")
		(net "ENET10G_4_TDP")
	)
	(arc
		(start 335.772506 -11.463528)
		(mid 335.81119 -11.657917)
		(end 335.92135 -11.822684)
		(width 0.24384)
		(layer "B.Cu")
		(net "ENET10G_4_TDP")
	)
	(segment
		(start 392.260074 -29.72562)
		(end 392.260074 -31.52648)
		(width 0.1778)
		(layer "F.Cu")
		(net "SAS_BLAD2_RX7_P")
	)
	(segment
		(start 392.484864 -29.50083)
		(end 392.260074 -29.72562)
		(width 0.1778)
		(layer "F.Cu")
		(net "SAS_BLAD2_RX7_P")
	)
	(segment
		(start 392.260074 -31.52648)
		(end 392.719814 -31.98622)
		(width 0.1778)
		(layer "F.Cu")
		(net "SAS_BLAD2_RX7_P")
	)
	(segment
		(start 392.484864 -28.4099)
		(end 392.484864 -29.50083)
		(width 0.1778)
		(layer "F.Cu")
		(net "SAS_BLAD2_RX7_P")
	)
	(via
		(at 392.719814 -31.98622)
		(size 0.508)
		(drill 0.254)
		(layers "F.Cu" "B.Cu")
		(net "SAS_BLAD2_RX7_P")
	)
	(segment
		(start 387.090666 -30.244288)
		(end 387.090666 -28.759912)
		(width 0.1524)
		(layer "In5.Cu")
		(net "SAS_BLAD2_RX7_P")
	)
	(segment
		(start 392.288268 -32.417766)
		(end 392.288268 -32.768286)
		(width 0.1524)
		(layer "In5.Cu")
		(net "SAS_BLAD2_RX7_P")
	)
	(segment
		(start 392.139424 -33.127442)
		(end 392.01471 -33.252156)
		(width 0.1524)
		(layer "In5.Cu")
		(net "SAS_BLAD2_RX7_P")
	)
	(segment
		(start 389.600694 -33.13303)
		(end 387.358382 -30.890972)
		(width 0.1524)
		(layer "In5.Cu")
		(net "SAS_BLAD2_RX7_P")
	)
	(segment
		(start 389.888222 -22.380956)
		(end 384.462782 -16.95577)
		(width 0.1524)
		(layer "In5.Cu")
		(net "SAS_BLAD2_RX7_P")
	)
	(segment
		(start 392.719814 -31.98622)
		(end 392.288268 -32.417766)
		(width 0.1524)
		(layer "In5.Cu")
		(net "SAS_BLAD2_RX7_P")
	)
	(segment
		(start 385.715764 -12.296902)
		(end 385.890008 -12.122658)
		(width 0.1524)
		(layer "In5.Cu")
		(net "SAS_BLAD2_RX7_P")
	)
	(segment
		(start 391.655554 -33.401)
		(end 390.247378 -33.401)
		(width 0.1524)
		(layer "In5.Cu")
		(net "SAS_BLAD2_RX7_P")
	)
	(segment
		(start 387.358636 -28.113228)
		(end 390.007348 -25.464516)
		(width 0.1524)
		(layer "In5.Cu")
		(net "SAS_BLAD2_RX7_P")
	)
	(segment
		(start 384.942842 -12.296902)
		(end 385.715764 -12.296902)
		(width 0.1524)
		(layer "In5.Cu")
		(net "SAS_BLAD2_RX7_P")
	)
	(segment
		(start 384.195066 -16.309086)
		(end 384.195066 -13.044424)
		(width 0.1524)
		(layer "In5.Cu")
		(net "SAS_BLAD2_RX7_P")
	)
	(segment
		(start 385.890008 -12.122658)
		(end 385.890008 -11.800078)
		(width 0.1524)
		(layer "In5.Cu")
		(net "SAS_BLAD2_RX7_P")
	)
	(segment
		(start 390.037066 -25.392888)
		(end 390.037066 -22.740112)
		(width 0.1524)
		(layer "In5.Cu")
		(net "SAS_BLAD2_RX7_P")
	)
	(arc
		(start 390.037066 -22.740112)
		(mid 389.998382 -22.545723)
		(end 389.888222 -22.380956)
		(width 0.1524)
		(layer "In5.Cu")
		(net "SAS_BLAD2_RX7_P")
	)
	(arc
		(start 387.358382 -30.890972)
		(mid 387.160162 -30.59427)
		(end 387.090666 -30.244288)
		(width 0.1524)
		(layer "In5.Cu")
		(net "SAS_BLAD2_RX7_P")
	)
	(arc
		(start 384.462782 -16.95577)
		(mid 384.264562 -16.659068)
		(end 384.195066 -16.309086)
		(width 0.1524)
		(layer "In5.Cu")
		(net "SAS_BLAD2_RX7_P")
	)
	(arc
		(start 392.288268 -32.768286)
		(mid 392.249584 -32.962675)
		(end 392.139424 -33.127442)
		(width 0.1524)
		(layer "In5.Cu")
		(net "SAS_BLAD2_RX7_P")
	)
	(arc
		(start 384.41376 -12.51585)
		(mid 384.65652 -12.353736)
		(end 384.942842 -12.296902)
		(width 0.1524)
		(layer "In5.Cu")
		(net "SAS_BLAD2_RX7_P")
	)
	(arc
		(start 387.090666 -28.759912)
		(mid 387.160305 -28.409903)
		(end 387.358636 -28.113228)
		(width 0.1524)
		(layer "In5.Cu")
		(net "SAS_BLAD2_RX7_P")
	)
	(arc
		(start 390.007348 -25.464516)
		(mid 390.02936 -25.431667)
		(end 390.037066 -25.392888)
		(width 0.1524)
		(layer "In5.Cu")
		(net "SAS_BLAD2_RX7_P")
	)
	(arc
		(start 392.01471 -33.252156)
		(mid 391.849942 -33.362314)
		(end 391.655554 -33.401)
		(width 0.1524)
		(layer "In5.Cu")
		(net "SAS_BLAD2_RX7_P")
	)
	(arc
		(start 390.247378 -33.401)
		(mid 389.897369 -33.331361)
		(end 389.600694 -33.13303)
		(width 0.1524)
		(layer "In5.Cu")
		(net "SAS_BLAD2_RX7_P")
	)
	(arc
		(start 384.195066 -13.044424)
		(mid 384.25185 -12.758389)
		(end 384.41376 -12.51585)
		(width 0.1524)
		(layer "In5.Cu")
		(net "SAS_BLAD2_RX7_P")
	)
	(segment
		(start 413.333692 -31.22168)
		(end 413.333692 -29.739844)
		(width 0.1778)
		(layer "F.Cu")
		(net "SAS_BLAD2_RX2_N")
	)
	(segment
		(start 413.333692 -29.739844)
		(end 413.094932 -29.501084)
		(width 0.1778)
		(layer "F.Cu")
		(net "SAS_BLAD2_RX2_N")
	)
	(segment
		(start 412.873952 -31.68142)
		(end 413.333692 -31.22168)
		(width 0.1778)
		(layer "F.Cu")
		(net "SAS_BLAD2_RX2_N")
	)
	(segment
		(start 413.094932 -29.501084)
		(end 413.094932 -28.4099)
		(width 0.1778)
		(layer "F.Cu")
		(net "SAS_BLAD2_RX2_N")
	)
	(via
		(at 412.873952 -31.68142)
		(size 0.508)
		(drill 0.254)
		(layers "F.Cu" "B.Cu")
		(net "SAS_BLAD2_RX2_N")
	)
	(segment
		(start 406.91054 -25.636474)
		(end 406.91054 -25.408382)
		(width 0.1524)
		(layer "In5.Cu")
		(net "SAS_BLAD2_RX2_N")
	)
	(segment
		(start 402.213318 -20.71116)
		(end 401.985226 -20.71116)
		(width 0.1524)
		(layer "In5.Cu")
		(net "SAS_BLAD2_RX2_N")
	)
	(segment
		(start 413.118554 -32.5374)
		(end 412.638748 -32.5374)
		(width 0.1524)
		(layer "In5.Cu")
		(net "SAS_BLAD2_RX2_N")
	)
	(segment
		(start 408.798014 -29.78785)
		(end 408.717242 -29.592778)
		(width 0.1524)
		(layer "In5.Cu")
		(net "SAS_BLAD2_RX2_N")
	)
	(segment
		(start 413.276288 -32.421576)
		(end 413.190182 -32.507682)
		(width 0.1524)
		(layer "In5.Cu")
		(net "SAS_BLAD2_RX2_N")
	)
	(segment
		(start 403.411436 -22.13737)
		(end 403.411436 -21.909278)
		(width 0.1524)
		(layer "In5.Cu")
		(net "SAS_BLAD2_RX2_N")
	)
	(segment
		(start 404.286212 -23.012146)
		(end 404.286212 -22.784054)
		(width 0.1524)
		(layer "In5.Cu")
		(net "SAS_BLAD2_RX2_N")
	)
	(segment
		(start 393.046458 -13.804646)
		(end 393.046458 -13.06703)
		(width 0.1524)
		(layer "In5.Cu")
		(net "SAS_BLAD2_RX2_N")
	)
	(segment
		(start 394.528294 -15.337028)
		(end 393.082018 -13.890752)
		(width 0.1524)
		(layer "In5.Cu")
		(net "SAS_BLAD2_RX2_N")
	)
	(segment
		(start 405.160988 -23.65883)
		(end 404.837646 -23.335488)
		(width 0.1524)
		(layer "In5.Cu")
		(net "SAS_BLAD2_RX2_N")
	)
	(segment
		(start 409.440126 -30.76829)
		(end 408.84475 -29.875226)
		(width 0.1524)
		(layer "In5.Cu")
		(net "SAS_BLAD2_RX2_N")
	)
	(segment
		(start 404.837646 -23.335488)
		(end 404.609554 -23.335488)
		(width 0.1524)
		(layer "In5.Cu")
		(net "SAS_BLAD2_RX2_N")
	)
	(segment
		(start 393.697968 -12.703302)
		(end 393.889992 -12.895326)
		(width 0.1524)
		(layer "In5.Cu")
		(net "SAS_BLAD2_RX2_N")
	)
	(segment
		(start 406.91054 -25.408382)
		(end 406.587198 -25.08504)
		(width 0.1524)
		(layer "In5.Cu")
		(net "SAS_BLAD2_RX2_N")
	)
	(segment
		(start 412.873952 -31.68142)
		(end 413.306006 -32.113474)
		(width 0.1524)
		(layer "In5.Cu")
		(net "SAS_BLAD2_RX2_N")
	)
	(segment
		(start 393.889992 -12.895326)
		(end 393.889992 -13.200126)
		(width 0.1524)
		(layer "In5.Cu")
		(net "SAS_BLAD2_RX2_N")
	)
	(segment
		(start 397.067278 -16.495014)
		(end 394.528294 -15.337028)
		(width 0.1524)
		(layer "In5.Cu")
		(net "SAS_BLAD2_RX2_N")
	)
	(segment
		(start 399.169636 -18.338038)
		(end 397.067278 -16.495014)
		(width 0.1524)
		(layer "In5.Cu")
		(net "SAS_BLAD2_RX2_N")
	)
	(segment
		(start 409.931616 -31.27375)
		(end 409.503626 -30.84576)
		(width 0.1524)
		(layer "In5.Cu")
		(net "SAS_BLAD2_RX2_N")
	)
	(segment
		(start 402.53666 -21.262594)
		(end 402.53666 -21.034502)
		(width 0.1524)
		(layer "In5.Cu")
		(net "SAS_BLAD2_RX2_N")
	)
	(segment
		(start 402.860002 -21.585936)
		(end 402.53666 -21.262594)
		(width 0.1524)
		(layer "In5.Cu")
		(net "SAS_BLAD2_RX2_N")
	)
	(segment
		(start 403.088094 -21.585936)
		(end 402.860002 -21.585936)
		(width 0.1524)
		(layer "In5.Cu")
		(net "SAS_BLAD2_RX2_N")
	)
	(segment
		(start 407.283158 -26.009092)
		(end 406.91054 -25.636474)
		(width 0.1524)
		(layer "In5.Cu")
		(net "SAS_BLAD2_RX2_N")
	)
	(segment
		(start 408.667458 -29.248608)
		(end 407.39314 -26.173684)
		(width 0.1524)
		(layer "In5.Cu")
		(net "SAS_BLAD2_RX2_N")
	)
	(segment
		(start 403.411436 -21.909278)
		(end 403.088094 -21.585936)
		(width 0.1524)
		(layer "In5.Cu")
		(net "SAS_BLAD2_RX2_N")
	)
	(segment
		(start 406.587198 -25.08504)
		(end 406.359106 -25.08504)
		(width 0.1524)
		(layer "In5.Cu")
		(net "SAS_BLAD2_RX2_N")
	)
	(segment
		(start 393.410186 -12.703302)
		(end 393.697968 -12.703302)
		(width 0.1524)
		(layer "In5.Cu")
		(net "SAS_BLAD2_RX2_N")
	)
	(segment
		(start 406.359106 -25.08504)
		(end 406.035764 -24.761698)
		(width 0.1524)
		(layer "In5.Cu")
		(net "SAS_BLAD2_RX2_N")
	)
	(segment
		(start 406.035764 -24.761698)
		(end 406.035764 -24.533606)
		(width 0.1524)
		(layer "In5.Cu")
		(net "SAS_BLAD2_RX2_N")
	)
	(segment
		(start 404.609554 -23.335488)
		(end 404.286212 -23.012146)
		(width 0.1524)
		(layer "In5.Cu")
		(net "SAS_BLAD2_RX2_N")
	)
	(segment
		(start 402.53666 -21.034502)
		(end 402.213318 -20.71116)
		(width 0.1524)
		(layer "In5.Cu")
		(net "SAS_BLAD2_RX2_N")
	)
	(segment
		(start 404.286212 -22.784054)
		(end 403.96287 -22.460712)
		(width 0.1524)
		(layer "In5.Cu")
		(net "SAS_BLAD2_RX2_N")
	)
	(segment
		(start 405.160988 -23.886922)
		(end 405.160988 -23.65883)
		(width 0.1524)
		(layer "In5.Cu")
		(net "SAS_BLAD2_RX2_N")
	)
	(segment
		(start 406.035764 -24.533606)
		(end 405.712422 -24.210264)
		(width 0.1524)
		(layer "In5.Cu")
		(net "SAS_BLAD2_RX2_N")
	)
	(segment
		(start 405.48433 -24.210264)
		(end 405.160988 -23.886922)
		(width 0.1524)
		(layer "In5.Cu")
		(net "SAS_BLAD2_RX2_N")
	)
	(segment
		(start 412.444184 -32.498792)
		(end 410.635704 -31.749238)
		(width 0.1524)
		(layer "In5.Cu")
		(net "SAS_BLAD2_RX2_N")
	)
	(segment
		(start 413.306006 -32.113474)
		(end 413.306006 -32.349948)
		(width 0.1524)
		(layer "In5.Cu")
		(net "SAS_BLAD2_RX2_N")
	)
	(segment
		(start 403.96287 -22.460712)
		(end 403.734778 -22.460712)
		(width 0.1524)
		(layer "In5.Cu")
		(net "SAS_BLAD2_RX2_N")
	)
	(segment
		(start 393.082018 -13.890752)
		(end 393.046458 -13.804646)
		(width 0.1524)
		(layer "In5.Cu")
		(net "SAS_BLAD2_RX2_N")
	)
	(segment
		(start 408.706066 -29.536136)
		(end 408.706066 -29.443172)
		(width 0.1524)
		(layer "In5.Cu")
		(net "SAS_BLAD2_RX2_N")
	)
	(segment
		(start 405.712422 -24.210264)
		(end 405.48433 -24.210264)
		(width 0.1524)
		(layer "In5.Cu")
		(net "SAS_BLAD2_RX2_N")
	)
	(segment
		(start 410.54528 -31.70047)
		(end 410.006038 -31.335218)
		(width 0.1524)
		(layer "In5.Cu")
		(net "SAS_BLAD2_RX2_N")
	)
	(segment
		(start 403.734778 -22.460712)
		(end 403.411436 -22.13737)
		(width 0.1524)
		(layer "In5.Cu")
		(net "SAS_BLAD2_RX2_N")
	)
	(segment
		(start 401.985226 -20.71116)
		(end 401.715478 -20.441412)
		(width 0.1524)
		(layer "In5.Cu")
		(net "SAS_BLAD2_RX2_N")
	)
	(segment
		(start 401.715478 -20.441412)
		(end 399.169636 -18.338038)
		(width 0.1524)
		(layer "In5.Cu")
		(net "SAS_BLAD2_RX2_N")
	)
	(arc
		(start 393.046458 -13.06703)
		(mid 393.07418 -12.927754)
		(end 393.153138 -12.809728)
		(width 0.1524)
		(layer "In5.Cu")
		(net "SAS_BLAD2_RX2_N")
	)
	(arc
		(start 408.717242 -29.592778)
		(mid 408.708862 -29.565008)
		(end 408.706066 -29.536136)
		(width 0.1524)
		(layer "In5.Cu")
		(net "SAS_BLAD2_RX2_N")
	)
	(arc
		(start 410.635704 -31.749238)
		(mid 410.589251 -31.727153)
		(end 410.54528 -31.70047)
		(width 0.1524)
		(layer "In5.Cu")
		(net "SAS_BLAD2_RX2_N")
	)
	(arc
		(start 413.306006 -32.349948)
		(mid 413.298276 -32.388717)
		(end 413.276288 -32.421576)
		(width 0.1524)
		(layer "In5.Cu")
		(net "SAS_BLAD2_RX2_N")
	)
	(arc
		(start 408.84475 -29.875226)
		(mid 408.819241 -29.832683)
		(end 408.798014 -29.78785)
		(width 0.1524)
		(layer "In5.Cu")
		(net "SAS_BLAD2_RX2_N")
	)
	(arc
		(start 408.706066 -29.443172)
		(mid 408.69634 -29.34399)
		(end 408.667458 -29.248608)
		(width 0.1524)
		(layer "In5.Cu")
		(net "SAS_BLAD2_RX2_N")
	)
	(arc
		(start 410.006038 -31.335218)
		(mid 409.96736 -31.30626)
		(end 409.931616 -31.27375)
		(width 0.1524)
		(layer "In5.Cu")
		(net "SAS_BLAD2_RX2_N")
	)
	(arc
		(start 393.153138 -12.809728)
		(mid 393.271087 -12.73098)
		(end 393.410186 -12.703302)
		(width 0.1524)
		(layer "In5.Cu")
		(net "SAS_BLAD2_RX2_N")
	)
	(arc
		(start 409.503626 -30.84576)
		(mid 409.469961 -30.808594)
		(end 409.440126 -30.76829)
		(width 0.1524)
		(layer "In5.Cu")
		(net "SAS_BLAD2_RX2_N")
	)
	(arc
		(start 412.638748 -32.5374)
		(mid 412.539566 -32.527674)
		(end 412.444184 -32.498792)
		(width 0.1524)
		(layer "In5.Cu")
		(net "SAS_BLAD2_RX2_N")
	)
	(arc
		(start 407.39314 -26.173684)
		(mid 407.346248 -26.085975)
		(end 407.283158 -26.009092)
		(width 0.1524)
		(layer "In5.Cu")
		(net "SAS_BLAD2_RX2_N")
	)
	(arc
		(start 413.190182 -32.507682)
		(mid 413.157333 -32.529694)
		(end 413.118554 -32.5374)
		(width 0.1524)
		(layer "In5.Cu")
		(net "SAS_BLAD2_RX2_N")
	)
	(segment
		(start 394.88491 -29.50083)
		(end 394.66012 -29.72562)
		(width 0.1778)
		(layer "F.Cu")
		(net "SAS_BLAD2_RX6_P")
	)
	(segment
		(start 394.66012 -32.43326)
		(end 395.14526 -32.9184)
		(width 0.1778)
		(layer "F.Cu")
		(net "SAS_BLAD2_RX6_P")
	)
	(segment
		(start 394.88491 -28.4099)
		(end 394.88491 -29.50083)
		(width 0.1778)
		(layer "F.Cu")
		(net "SAS_BLAD2_RX6_P")
	)
	(segment
		(start 394.66012 -29.72562)
		(end 394.66012 -32.43326)
		(width 0.1778)
		(layer "F.Cu")
		(net "SAS_BLAD2_RX6_P")
	)
	(via
		(at 395.14526 -32.9184)
		(size 0.508)
		(drill 0.254)
		(layers "F.Cu" "B.Cu")
		(net "SAS_BLAD2_RX6_P")
	)
	(segment
		(start 388.90702 -6.979666)
		(end 388.911846 -6.984492)
		(width 0.1778)
		(layer "B.Cu")
		(net "SAS_BLAD2_RX6_P")
	)
	(segment
		(start 395.238986 -24.089106)
		(end 395.238986 -24.622506)
		(width 0.1778)
		(layer "B.Cu")
		(net "SAS_BLAD2_RX6_P")
	)
	(segment
		(start 394.685774 -31.470854)
		(end 394.685774 -32.458914)
		(width 0.1778)
		(layer "B.Cu")
		(net "SAS_BLAD2_RX6_P")
	)
	(segment
		(start 390.028938 -16.755872)
		(end 393.71143 -20.43811)
		(width 0.1778)
		(layer "B.Cu")
		(net "SAS_BLAD2_RX6_P")
	)
	(segment
		(start 394.858494 -31.298134)
		(end 394.685774 -31.470854)
		(width 0.1778)
		(layer "B.Cu")
		(net "SAS_BLAD2_RX6_P")
	)
	(segment
		(start 394.33246 -20.8153)
		(end 394.33246 -21.059648)
		(width 0.1778)
		(layer "B.Cu")
		(net "SAS_BLAD2_RX6_P")
	)
	(segment
		(start 394.332968 -21.059648)
		(end 394.535406 -21.262086)
		(width 0.1778)
		(layer "B.Cu")
		(net "SAS_BLAD2_RX6_P")
	)
	(segment
		(start 394.33246 -21.059648)
		(end 394.332968 -21.059648)
		(width 0.1778)
		(layer "B.Cu")
		(net "SAS_BLAD2_RX6_P")
	)
	(segment
		(start 395.238986 -23.19655)
		(end 395.066266 -23.36927)
		(width 0.1778)
		(layer "B.Cu")
		(net "SAS_BLAD2_RX6_P")
	)
	(segment
		(start 394.685774 -30.592014)
		(end 394.858494 -30.764734)
		(width 0.1778)
		(layer "B.Cu")
		(net "SAS_BLAD2_RX6_P")
	)
	(segment
		(start 387.890004 -6.299962)
		(end 387.890004 -6.633464)
		(width 0.1778)
		(layer "B.Cu")
		(net "SAS_BLAD2_RX6_P")
	)
	(segment
		(start 394.535406 -21.262594)
		(end 394.53566 -21.262594)
		(width 0.1778)
		(layer "B.Cu")
		(net "SAS_BLAD2_RX6_P")
	)
	(segment
		(start 395.06398 -22.32787)
		(end 395.066266 -22.49043)
		(width 0.1778)
		(layer "B.Cu")
		(net "SAS_BLAD2_RX6_P")
	)
	(segment
		(start 394.535406 -21.262086)
		(end 394.535406 -21.262594)
		(width 0.1778)
		(layer "B.Cu")
		(net "SAS_BLAD2_RX6_P")
	)
	(segment
		(start 395.027658 -22.183852)
		(end 395.063726 -22.327362)
		(width 0.1778)
		(layer "B.Cu")
		(net "SAS_BLAD2_RX6_P")
	)
	(segment
		(start 394.858494 -30.764734)
		(end 394.858494 -31.298134)
		(width 0.1778)
		(layer "B.Cu")
		(net "SAS_BLAD2_RX6_P")
	)
	(segment
		(start 394.685774 -27.794458)
		(end 394.858494 -27.967178)
		(width 0.1778)
		(layer "B.Cu")
		(net "SAS_BLAD2_RX6_P")
	)
	(segment
		(start 395.238986 -22.66315)
		(end 395.238986 -23.19655)
		(width 0.1778)
		(layer "B.Cu")
		(net "SAS_BLAD2_RX6_P")
	)
	(segment
		(start 388.081266 -6.824726)
		(end 388.532878 -6.824726)
		(width 0.1778)
		(layer "B.Cu")
		(net "SAS_BLAD2_RX6_P")
	)
	(segment
		(start 394.762228 -21.543772)
		(end 395.027658 -22.183852)
		(width 0.1778)
		(layer "B.Cu")
		(net "SAS_BLAD2_RX6_P")
	)
	(segment
		(start 394.858494 -28.500578)
		(end 394.685774 -28.673298)
		(width 0.1778)
		(layer "B.Cu")
		(net "SAS_BLAD2_RX6_P")
	)
	(segment
		(start 395.238986 -26.048716)
		(end 395.066266 -26.221436)
		(width 0.1778)
		(layer "B.Cu")
		(net "SAS_BLAD2_RX6_P")
	)
	(segment
		(start 389.336788 -15.078964)
		(end 390.028938 -16.755872)
		(width 0.1778)
		(layer "B.Cu")
		(net "SAS_BLAD2_RX6_P")
	)
	(segment
		(start 395.066266 -23.916386)
		(end 395.238986 -24.089106)
		(width 0.1778)
		(layer "B.Cu")
		(net "SAS_BLAD2_RX6_P")
	)
	(segment
		(start 395.066266 -25.342596)
		(end 395.238986 -25.515316)
		(width 0.1778)
		(layer "B.Cu")
		(net "SAS_BLAD2_RX6_P")
	)
	(segment
		(start 387.890004 -6.633464)
		(end 388.081266 -6.824726)
		(width 0.1778)
		(layer "B.Cu")
		(net "SAS_BLAD2_RX6_P")
	)
	(segment
		(start 394.858494 -27.967178)
		(end 394.858494 -28.500578)
		(width 0.1778)
		(layer "B.Cu")
		(net "SAS_BLAD2_RX6_P")
	)
	(segment
		(start 395.066266 -24.795226)
		(end 395.066266 -25.342596)
		(width 0.1778)
		(layer "B.Cu")
		(net "SAS_BLAD2_RX6_P")
	)
	(segment
		(start 395.066266 -22.49043)
		(end 395.238986 -22.66315)
		(width 0.1778)
		(layer "B.Cu")
		(net "SAS_BLAD2_RX6_P")
	)
	(segment
		(start 395.066266 -26.221436)
		(end 395.066266 -26.632408)
		(width 0.1778)
		(layer "B.Cu")
		(net "SAS_BLAD2_RX6_P")
	)
	(segment
		(start 394.685774 -28.673298)
		(end 394.685774 -30.592014)
		(width 0.1778)
		(layer "B.Cu")
		(net "SAS_BLAD2_RX6_P")
	)
	(segment
		(start 394.53566 -21.262594)
		(end 394.652246 -21.37918)
		(width 0.1778)
		(layer "B.Cu")
		(net "SAS_BLAD2_RX6_P")
	)
	(segment
		(start 395.238986 -25.515316)
		(end 395.238986 -26.048716)
		(width 0.1778)
		(layer "B.Cu")
		(net "SAS_BLAD2_RX6_P")
	)
	(segment
		(start 395.063726 -22.327362)
		(end 395.06398 -22.32787)
		(width 0.1778)
		(layer "B.Cu")
		(net "SAS_BLAD2_RX6_P")
	)
	(segment
		(start 394.685774 -32.458914)
		(end 395.14526 -32.9184)
		(width 0.1778)
		(layer "B.Cu")
		(net "SAS_BLAD2_RX6_P")
	)
	(segment
		(start 393.71143 -20.43811)
		(end 393.955524 -20.43811)
		(width 0.1778)
		(layer "B.Cu")
		(net "SAS_BLAD2_RX6_P")
	)
	(segment
		(start 395.066266 -23.36927)
		(end 395.066266 -23.916386)
		(width 0.1778)
		(layer "B.Cu")
		(net "SAS_BLAD2_RX6_P")
	)
	(segment
		(start 393.955524 -20.43811)
		(end 394.33246 -20.8153)
		(width 0.1778)
		(layer "B.Cu")
		(net "SAS_BLAD2_RX6_P")
	)
	(segment
		(start 389.071866 -7.370572)
		(end 389.071866 -13.97)
		(width 0.1778)
		(layer "B.Cu")
		(net "SAS_BLAD2_RX6_P")
	)
	(segment
		(start 394.917422 -26.991564)
		(end 394.834618 -27.074368)
		(width 0.1778)
		(layer "B.Cu")
		(net "SAS_BLAD2_RX6_P")
	)
	(segment
		(start 395.238986 -24.622506)
		(end 395.066266 -24.795226)
		(width 0.1778)
		(layer "B.Cu")
		(net "SAS_BLAD2_RX6_P")
	)
	(segment
		(start 394.685774 -27.433524)
		(end 394.685774 -27.794458)
		(width 0.1778)
		(layer "B.Cu")
		(net "SAS_BLAD2_RX6_P")
	)
	(segment
		(start 389.071866 -13.97)
		(end 389.336788 -15.078964)
		(width 0.1778)
		(layer "B.Cu")
		(net "SAS_BLAD2_RX6_P")
	)
	(arc
		(start 388.911846 -6.984492)
		(mid 389.030287 -7.161612)
		(end 389.071866 -7.370572)
		(width 0.1778)
		(layer "B.Cu")
		(net "SAS_BLAD2_RX6_P")
	)
	(arc
		(start 388.532878 -6.824726)
		(mid 388.735374 -6.864947)
		(end 388.90702 -6.979666)
		(width 0.1778)
		(layer "B.Cu")
		(net "SAS_BLAD2_RX6_P")
	)
	(arc
		(start 394.652246 -21.37918)
		(mid 394.715323 -21.456072)
		(end 394.762228 -21.543772)
		(width 0.1778)
		(layer "B.Cu")
		(net "SAS_BLAD2_RX6_P")
	)
	(arc
		(start 395.066266 -26.632408)
		(mid 395.027582 -26.826797)
		(end 394.917422 -26.991564)
		(width 0.1778)
		(layer "B.Cu")
		(net "SAS_BLAD2_RX6_P")
	)
	(arc
		(start 394.834618 -27.074368)
		(mid 394.72446 -27.239136)
		(end 394.685774 -27.433524)
		(width 0.1778)
		(layer "B.Cu")
		(net "SAS_BLAD2_RX6_P")
	)
	(segment
		(start 389.509508 -29.72562)
		(end 389.509508 -30.27426)
		(width 0.1778)
		(layer "F.Cu")
		(net "SAS_BLAD2_RX8_N")
	)
	(segment
		(start 389.284972 -28.4099)
		(end 389.284972 -29.501084)
		(width 0.1778)
		(layer "F.Cu")
		(net "SAS_BLAD2_RX8_N")
	)
	(segment
		(start 389.509508 -30.27426)
		(end 389.049768 -30.734)
		(width 0.1778)
		(layer "F.Cu")
		(net "SAS_BLAD2_RX8_N")
	)
	(segment
		(start 389.284972 -29.501084)
		(end 389.509508 -29.72562)
		(width 0.1778)
		(layer "F.Cu")
		(net "SAS_BLAD2_RX8_N")
	)
	(via
		(at 389.049768 -30.734)
		(size 0.508)
		(drill 0.254)
		(layers "F.Cu" "B.Cu")
		(net "SAS_BLAD2_RX8_N")
	)
	(segment
		(start 384.316986 -23.863808)
		(end 384.316986 -23.141432)
		(width 0.1778)
		(layer "B.Cu")
		(net "SAS_BLAD2_RX8_N")
	)
	(segment
		(start 389.463534 -31.624524)
		(end 389.455406 -31.632652)
		(width 0.1778)
		(layer "B.Cu")
		(net "SAS_BLAD2_RX8_N")
	)
	(segment
		(start 384.316986 -23.141432)
		(end 384.489706 -22.968966)
		(width 0.1778)
		(layer "B.Cu")
		(net "SAS_BLAD2_RX8_N")
	)
	(segment
		(start 387.089142 -26.846276)
		(end 384.46583 -24.222964)
		(width 0.1778)
		(layer "B.Cu")
		(net "SAS_BLAD2_RX8_N")
	)
	(segment
		(start 384.316986 -22.2631)
		(end 384.316986 -21.7297)
		(width 0.1778)
		(layer "B.Cu")
		(net "SAS_BLAD2_RX8_N")
	)
	(segment
		(start 384.489706 -21.02358)
		(end 384.316986 -20.851114)
		(width 0.1778)
		(layer "B.Cu")
		(net "SAS_BLAD2_RX8_N")
	)
	(segment
		(start 384.489706 -22.968966)
		(end 384.489706 -22.435566)
		(width 0.1778)
		(layer "B.Cu")
		(net "SAS_BLAD2_RX8_N")
	)
	(segment
		(start 388.394702 -31.530036)
		(end 387.38683 -30.522164)
		(width 0.1778)
		(layer "B.Cu")
		(net "SAS_BLAD2_RX8_N")
	)
	(segment
		(start 387.237986 -30.163008)
		(end 387.237986 -27.205432)
		(width 0.1778)
		(layer "B.Cu")
		(net "SAS_BLAD2_RX8_N")
	)
	(segment
		(start 389.344154 -31.67888)
		(end 388.753858 -31.67888)
		(width 0.1778)
		(layer "B.Cu")
		(net "SAS_BLAD2_RX8_N")
	)
	(segment
		(start 384.98145 -4.275328)
		(end 385.365244 -4.275328)
		(width 0.1778)
		(layer "B.Cu")
		(net "SAS_BLAD2_RX8_N")
	)
	(segment
		(start 384.316986 -21.7297)
		(end 384.489706 -21.55698)
		(width 0.1778)
		(layer "B.Cu")
		(net "SAS_BLAD2_RX8_N")
	)
	(segment
		(start 384.316986 -20.851114)
		(end 384.316986 -4.939792)
		(width 0.1778)
		(layer "B.Cu")
		(net "SAS_BLAD2_RX8_N")
	)
	(segment
		(start 384.46583 -4.580636)
		(end 384.622294 -4.424172)
		(width 0.1778)
		(layer "B.Cu")
		(net "SAS_BLAD2_RX8_N")
	)
	(segment
		(start 384.489706 -22.435566)
		(end 384.316986 -22.2631)
		(width 0.1778)
		(layer "B.Cu")
		(net "SAS_BLAD2_RX8_N")
	)
	(segment
		(start 389.049768 -30.734)
		(end 389.509762 -31.193994)
		(width 0.1778)
		(layer "B.Cu")
		(net "SAS_BLAD2_RX8_N")
	)
	(segment
		(start 384.489706 -21.55698)
		(end 384.489706 -21.02358)
		(width 0.1778)
		(layer "B.Cu")
		(net "SAS_BLAD2_RX8_N")
	)
	(segment
		(start 385.365244 -4.275328)
		(end 385.890008 -4.800092)
		(width 0.1778)
		(layer "B.Cu")
		(net "SAS_BLAD2_RX8_N")
	)
	(segment
		(start 389.509762 -31.193994)
		(end 389.509762 -31.513272)
		(width 0.1778)
		(layer "B.Cu")
		(net "SAS_BLAD2_RX8_N")
	)
	(arc
		(start 389.509762 -31.513272)
		(mid 389.497744 -31.573508)
		(end 389.463534 -31.624524)
		(width 0.1778)
		(layer "B.Cu")
		(net "SAS_BLAD2_RX8_N")
	)
	(arc
		(start 384.316986 -4.939792)
		(mid 384.35567 -4.745403)
		(end 384.46583 -4.580636)
		(width 0.1778)
		(layer "B.Cu")
		(net "SAS_BLAD2_RX8_N")
	)
	(arc
		(start 387.237986 -27.205432)
		(mid 387.199302 -27.011043)
		(end 387.089142 -26.846276)
		(width 0.1778)
		(layer "B.Cu")
		(net "SAS_BLAD2_RX8_N")
	)
	(arc
		(start 384.622294 -4.424172)
		(mid 384.787062 -4.314014)
		(end 384.98145 -4.275328)
		(width 0.1778)
		(layer "B.Cu")
		(net "SAS_BLAD2_RX8_N")
	)
	(arc
		(start 388.753858 -31.67888)
		(mid 388.559469 -31.640196)
		(end 388.394702 -31.530036)
		(width 0.1778)
		(layer "B.Cu")
		(net "SAS_BLAD2_RX8_N")
	)
	(arc
		(start 384.46583 -24.222964)
		(mid 384.355672 -24.058196)
		(end 384.316986 -23.863808)
		(width 0.1778)
		(layer "B.Cu")
		(net "SAS_BLAD2_RX8_N")
	)
	(arc
		(start 389.455406 -31.632652)
		(mid 389.404392 -31.666865)
		(end 389.344154 -31.67888)
		(width 0.1778)
		(layer "B.Cu")
		(net "SAS_BLAD2_RX8_N")
	)
	(arc
		(start 387.38683 -30.522164)
		(mid 387.276672 -30.357396)
		(end 387.237986 -30.163008)
		(width 0.1778)
		(layer "B.Cu")
		(net "SAS_BLAD2_RX8_N")
	)
	(segment
		(start 387.217412 -23.3934)
		(end 387.654292 -23.83028)
		(width 0.1778)
		(layer "F.Cu")
		(net "SAS_BLAD2_TX8_P")
	)
	(segment
		(start 390.260078 -24.251666)
		(end 390.260078 -24.584152)
		(width 0.1778)
		(layer "F.Cu")
		(net "SAS_BLAD2_TX8_P")
	)
	(segment
		(start 390.260078 -24.584152)
		(end 390.484868 -24.808942)
		(width 0.1778)
		(layer "F.Cu")
		(net "SAS_BLAD2_TX8_P")
	)
	(segment
		(start 390.484868 -24.808942)
		(end 390.484868 -25.899872)
		(width 0.1778)
		(layer "F.Cu")
		(net "SAS_BLAD2_TX8_P")
	)
	(segment
		(start 387.654292 -23.83028)
		(end 389.838692 -23.83028)
		(width 0.1778)
		(layer "F.Cu")
		(net "SAS_BLAD2_TX8_P")
	)
	(segment
		(start 389.838692 -23.83028)
		(end 390.260078 -24.251666)
		(width 0.1778)
		(layer "F.Cu")
		(net "SAS_BLAD2_TX8_P")
	)
	(via
		(at 387.217412 -23.3934)
		(size 0.508)
		(drill 0.254)
		(layers "F.Cu" "B.Cu")
		(net "SAS_BLAD2_TX8_P")
	)
	(segment
		(start 385.393438 -8.096758)
		(end 385.890008 -7.600188)
		(width 0.1524)
		(layer "In5.Cu")
		(net "SAS_BLAD2_TX8_P")
	)
	(segment
		(start 388.055866 -23.665688)
		(end 388.055866 -23.044912)
		(width 0.1524)
		(layer "In5.Cu")
		(net "SAS_BLAD2_TX8_P")
	)
	(segment
		(start 387.217412 -23.3934)
		(end 387.649212 -23.8252)
		(width 0.1524)
		(layer "In5.Cu")
		(net "SAS_BLAD2_TX8_P")
	)
	(segment
		(start 388.026148 -22.973284)
		(end 387.10362 -22.050756)
		(width 0.1524)
		(layer "In5.Cu")
		(net "SAS_BLAD2_TX8_P")
	)
	(segment
		(start 384.450336 -19.397472)
		(end 384.212592 -19.397472)
		(width 0.1524)
		(layer "In5.Cu")
		(net "SAS_BLAD2_TX8_P")
	)
	(segment
		(start 385.09702 -20.2819)
		(end 384.773678 -19.958558)
		(width 0.1524)
		(layer "In5.Cu")
		(net "SAS_BLAD2_TX8_P")
	)
	(segment
		(start 387.967982 -23.795482)
		(end 388.026148 -23.737316)
		(width 0.1524)
		(layer "In5.Cu")
		(net "SAS_BLAD2_TX8_P")
	)
	(segment
		(start 385.334764 -20.2819)
		(end 385.09702 -20.2819)
		(width 0.1524)
		(layer "In5.Cu")
		(net "SAS_BLAD2_TX8_P")
	)
	(segment
		(start 385.658106 -20.842986)
		(end 385.658106 -20.605242)
		(width 0.1524)
		(layer "In5.Cu")
		(net "SAS_BLAD2_TX8_P")
	)
	(segment
		(start 386.542534 -21.48967)
		(end 386.219192 -21.166328)
		(width 0.1524)
		(layer "In5.Cu")
		(net "SAS_BLAD2_TX8_P")
	)
	(segment
		(start 383.565908 -18.513044)
		(end 383.328164 -18.513044)
		(width 0.1524)
		(layer "In5.Cu")
		(net "SAS_BLAD2_TX8_P")
	)
	(segment
		(start 386.865876 -22.050756)
		(end 386.542534 -21.727414)
		(width 0.1524)
		(layer "In5.Cu")
		(net "SAS_BLAD2_TX8_P")
	)
	(segment
		(start 384.773678 -19.720814)
		(end 384.450336 -19.397472)
		(width 0.1524)
		(layer "In5.Cu")
		(net "SAS_BLAD2_TX8_P")
	)
	(segment
		(start 383.88925 -18.836386)
		(end 383.565908 -18.513044)
		(width 0.1524)
		(layer "In5.Cu")
		(net "SAS_BLAD2_TX8_P")
	)
	(segment
		(start 383.004822 -18.189702)
		(end 383.004822 -17.952212)
		(width 0.1524)
		(layer "In5.Cu")
		(net "SAS_BLAD2_TX8_P")
	)
	(segment
		(start 382.608836 -8.885428)
		(end 383.129536 -8.364474)
		(width 0.1524)
		(layer "In5.Cu")
		(net "SAS_BLAD2_TX8_P")
	)
	(segment
		(start 383.004822 -17.952212)
		(end 382.608582 -17.555972)
		(width 0.1524)
		(layer "In5.Cu")
		(net "SAS_BLAD2_TX8_P")
	)
	(segment
		(start 385.981448 -21.166328)
		(end 385.658106 -20.842986)
		(width 0.1524)
		(layer "In5.Cu")
		(net "SAS_BLAD2_TX8_P")
	)
	(segment
		(start 386.219192 -21.166328)
		(end 385.981448 -21.166328)
		(width 0.1524)
		(layer "In5.Cu")
		(net "SAS_BLAD2_TX8_P")
	)
	(segment
		(start 386.542534 -21.727414)
		(end 386.542534 -21.48967)
		(width 0.1524)
		(layer "In5.Cu")
		(net "SAS_BLAD2_TX8_P")
	)
	(segment
		(start 382.340866 -16.909288)
		(end 382.340866 -9.532112)
		(width 0.1524)
		(layer "In5.Cu")
		(net "SAS_BLAD2_TX8_P")
	)
	(segment
		(start 385.658106 -20.605242)
		(end 385.334764 -20.2819)
		(width 0.1524)
		(layer "In5.Cu")
		(net "SAS_BLAD2_TX8_P")
	)
	(segment
		(start 383.88925 -19.07413)
		(end 383.88925 -18.836386)
		(width 0.1524)
		(layer "In5.Cu")
		(net "SAS_BLAD2_TX8_P")
	)
	(segment
		(start 383.77622 -8.096758)
		(end 385.393438 -8.096758)
		(width 0.1524)
		(layer "In5.Cu")
		(net "SAS_BLAD2_TX8_P")
	)
	(segment
		(start 383.328164 -18.513044)
		(end 383.004822 -18.189702)
		(width 0.1524)
		(layer "In5.Cu")
		(net "SAS_BLAD2_TX8_P")
	)
	(segment
		(start 384.773678 -19.958558)
		(end 384.773678 -19.720814)
		(width 0.1524)
		(layer "In5.Cu")
		(net "SAS_BLAD2_TX8_P")
	)
	(segment
		(start 384.212592 -19.397472)
		(end 383.88925 -19.07413)
		(width 0.1524)
		(layer "In5.Cu")
		(net "SAS_BLAD2_TX8_P")
	)
	(segment
		(start 387.10362 -22.050756)
		(end 386.865876 -22.050756)
		(width 0.1524)
		(layer "In5.Cu")
		(net "SAS_BLAD2_TX8_P")
	)
	(segment
		(start 387.649212 -23.8252)
		(end 387.896354 -23.8252)
		(width 0.1524)
		(layer "In5.Cu")
		(net "SAS_BLAD2_TX8_P")
	)
	(arc
		(start 388.026148 -23.737316)
		(mid 388.04816 -23.704467)
		(end 388.055866 -23.665688)
		(width 0.1524)
		(layer "In5.Cu")
		(net "SAS_BLAD2_TX8_P")
	)
	(arc
		(start 382.340866 -9.532112)
		(mid 382.410505 -9.182103)
		(end 382.608836 -8.885428)
		(width 0.1524)
		(layer "In5.Cu")
		(net "SAS_BLAD2_TX8_P")
	)
	(arc
		(start 383.129536 -8.364474)
		(mid 383.426238 -8.166254)
		(end 383.77622 -8.096758)
		(width 0.1524)
		(layer "In5.Cu")
		(net "SAS_BLAD2_TX8_P")
	)
	(arc
		(start 382.608582 -17.555972)
		(mid 382.410362 -17.25927)
		(end 382.340866 -16.909288)
		(width 0.1524)
		(layer "In5.Cu")
		(net "SAS_BLAD2_TX8_P")
	)
	(arc
		(start 388.055866 -23.044912)
		(mid 388.048136 -23.006143)
		(end 388.026148 -22.973284)
		(width 0.1524)
		(layer "In5.Cu")
		(net "SAS_BLAD2_TX8_P")
	)
	(arc
		(start 387.896354 -23.8252)
		(mid 387.935123 -23.81747)
		(end 387.967982 -23.795482)
		(width 0.1524)
		(layer "In5.Cu")
		(net "SAS_BLAD2_TX8_P")
	)
	(segment
		(start 411.494986 -29.500576)
		(end 411.269942 -29.72562)
		(width 0.1778)
		(layer "F.Cu")
		(net "SAS_BLAD2_RX3_P")
	)
	(segment
		(start 411.269942 -30.135068)
		(end 411.729682 -30.594808)
		(width 0.1778)
		(layer "F.Cu")
		(net "SAS_BLAD2_RX3_P")
	)
	(segment
		(start 411.494986 -28.4099)
		(end 411.494986 -29.500576)
		(width 0.1778)
		(layer "F.Cu")
		(net "SAS_BLAD2_RX3_P")
	)
	(segment
		(start 411.269942 -29.72562)
		(end 411.269942 -30.135068)
		(width 0.1778)
		(layer "F.Cu")
		(net "SAS_BLAD2_RX3_P")
	)
	(via
		(at 411.729682 -30.594808)
		(size 0.508)
		(drill 0.254)
		(layers "F.Cu" "B.Cu")
		(net "SAS_BLAD2_RX3_P")
	)
	(segment
		(start 404.747476 -21.547074)
		(end 404.457662 -21.090636)
		(width 0.1778)
		(layer "B.Cu")
		(net "SAS_BLAD2_RX3_P")
	)
	(segment
		(start 394.917168 -4.168902)
		(end 394.821918 -4.073652)
		(width 0.1778)
		(layer "B.Cu")
		(net "SAS_BLAD2_RX3_P")
	)
	(segment
		(start 405.988774 -23.50135)
		(end 405.979884 -23.499572)
		(width 0.1778)
		(layer "B.Cu")
		(net "SAS_BLAD2_RX3_P")
	)
	(segment
		(start 404.45309 -21.090128)
		(end 404.506684 -20.851876)
		(width 0.1778)
		(layer "B.Cu")
		(net "SAS_BLAD2_RX3_P")
	)
	(segment
		(start 403.220174 -19.142202)
		(end 402.838666 -18.54073)
		(width 0.1778)
		(layer "B.Cu")
		(net "SAS_BLAD2_RX3_P")
	)
	(segment
		(start 394.139674 -3.924808)
		(end 393.889992 -3.675126)
		(width 0.1778)
		(layer "B.Cu")
		(net "SAS_BLAD2_RX3_P")
	)
	(segment
		(start 404.457662 -21.090636)
		(end 404.457408 -21.09089)
		(width 0.1778)
		(layer "B.Cu")
		(net "SAS_BLAD2_RX3_P")
	)
	(segment
		(start 403.743668 -19.647408)
		(end 403.457918 -19.196812)
		(width 0.1778)
		(layer "B.Cu")
		(net "SAS_BLAD2_RX3_P")
	)
	(segment
		(start 404.221442 -20.40128)
		(end 403.982936 -20.347686)
		(width 0.1778)
		(layer "B.Cu")
		(net "SAS_BLAD2_RX3_P")
	)
	(segment
		(start 394.462762 -3.924808)
		(end 394.139674 -3.924808)
		(width 0.1778)
		(layer "B.Cu")
		(net "SAS_BLAD2_RX3_P")
	)
	(segment
		(start 409.72613 -27.410918)
		(end 409.72613 -27.166824)
		(width 0.1778)
		(layer "B.Cu")
		(net "SAS_BLAD2_RX3_P")
	)
	(segment
		(start 411.121352 -28.80614)
		(end 410.73451 -28.419298)
		(width 0.1778)
		(layer "B.Cu")
		(net "SAS_BLAD2_RX3_P")
	)
	(segment
		(start 410.73451 -28.17495)
		(end 410.35732 -27.79776)
		(width 0.1778)
		(layer "B.Cu")
		(net "SAS_BLAD2_RX3_P")
	)
	(segment
		(start 403.457918 -19.196812)
		(end 403.219666 -19.143472)
		(width 0.1778)
		(layer "B.Cu")
		(net "SAS_BLAD2_RX3_P")
	)
	(segment
		(start 393.889992 -3.675126)
		(end 393.889992 -3.400044)
		(width 0.1778)
		(layer "B.Cu")
		(net "SAS_BLAD2_RX3_P")
	)
	(segment
		(start 410.73451 -28.419298)
		(end 410.73451 -28.17495)
		(width 0.1778)
		(layer "B.Cu")
		(net "SAS_BLAD2_RX3_P")
	)
	(segment
		(start 404.747476 -21.547328)
		(end 404.747476 -21.547074)
		(width 0.1778)
		(layer "B.Cu")
		(net "SAS_BLAD2_RX3_P")
	)
	(segment
		(start 403.691598 -19.884898)
		(end 403.690074 -19.88566)
		(width 0.1778)
		(layer "B.Cu")
		(net "SAS_BLAD2_RX3_P")
	)
	(segment
		(start 405.511508 -22.749764)
		(end 405.223218 -22.295866)
		(width 0.1778)
		(layer "B.Cu")
		(net "SAS_BLAD2_RX3_P")
	)
	(segment
		(start 405.216614 -22.29485)
		(end 405.270208 -22.056598)
		(width 0.1778)
		(layer "B.Cu")
		(net "SAS_BLAD2_RX3_P")
	)
	(segment
		(start 406.682702 -24.594058)
		(end 405.988774 -23.50135)
		(width 0.1778)
		(layer "B.Cu")
		(net "SAS_BLAD2_RX3_P")
	)
	(segment
		(start 404.506684 -20.851876)
		(end 404.221442 -20.40128)
		(width 0.1778)
		(layer "B.Cu")
		(net "SAS_BLAD2_RX3_P")
	)
	(segment
		(start 395.546326 -13.928852)
		(end 395.112494 -13.49502)
		(width 0.1778)
		(layer "B.Cu")
		(net "SAS_BLAD2_RX3_P")
	)
	(segment
		(start 405.223218 -22.295866)
		(end 405.216614 -22.29485)
		(width 0.1778)
		(layer "B.Cu")
		(net "SAS_BLAD2_RX3_P")
	)
	(segment
		(start 406.033478 -23.261066)
		(end 405.747982 -22.810724)
		(width 0.1778)
		(layer "B.Cu")
		(net "SAS_BLAD2_RX3_P")
	)
	(segment
		(start 405.509476 -22.757384)
		(end 405.511508 -22.749764)
		(width 0.1778)
		(layer "B.Cu")
		(net "SAS_BLAD2_RX3_P")
	)
	(segment
		(start 408.809698 -26.495756)
		(end 406.682702 -24.594058)
		(width 0.1778)
		(layer "B.Cu")
		(net "SAS_BLAD2_RX3_P")
	)
	(segment
		(start 409.72613 -27.166824)
		(end 409.348686 -26.78938)
		(width 0.1778)
		(layer "B.Cu")
		(net "SAS_BLAD2_RX3_P")
	)
	(segment
		(start 404.984712 -21.606002)
		(end 404.746206 -21.552662)
		(width 0.1778)
		(layer "B.Cu")
		(net "SAS_BLAD2_RX3_P")
	)
	(segment
		(start 405.747982 -22.810724)
		(end 405.509476 -22.757384)
		(width 0.1778)
		(layer "B.Cu")
		(net "SAS_BLAD2_RX3_P")
	)
	(segment
		(start 405.270208 -22.056598)
		(end 404.984712 -21.606002)
		(width 0.1778)
		(layer "B.Cu")
		(net "SAS_BLAD2_RX3_P")
	)
	(segment
		(start 411.729682 -30.594808)
		(end 411.270196 -30.135322)
		(width 0.1778)
		(layer "B.Cu")
		(net "SAS_BLAD2_RX3_P")
	)
	(segment
		(start 403.983698 -20.344892)
		(end 403.691598 -19.884898)
		(width 0.1778)
		(layer "B.Cu")
		(net "SAS_BLAD2_RX3_P")
	)
	(segment
		(start 402.838666 -18.54073)
		(end 400.321018 -16.988536)
		(width 0.1778)
		(layer "B.Cu")
		(net "SAS_BLAD2_RX3_P")
	)
	(segment
		(start 400.321018 -16.988536)
		(end 396.897352 -14.228318)
		(width 0.1778)
		(layer "B.Cu")
		(net "SAS_BLAD2_RX3_P")
	)
	(segment
		(start 404.457408 -21.09089)
		(end 404.45309 -21.090128)
		(width 0.1778)
		(layer "B.Cu")
		(net "SAS_BLAD2_RX3_P")
	)
	(segment
		(start 405.979884 -23.499572)
		(end 406.033478 -23.261066)
		(width 0.1778)
		(layer "B.Cu")
		(net "SAS_BLAD2_RX3_P")
	)
	(segment
		(start 409.104592 -26.78938)
		(end 408.830272 -26.51506)
		(width 0.1778)
		(layer "B.Cu")
		(net "SAS_BLAD2_RX3_P")
	)
	(segment
		(start 411.270196 -30.135322)
		(end 411.270196 -29.165296)
		(width 0.1778)
		(layer "B.Cu")
		(net "SAS_BLAD2_RX3_P")
	)
	(segment
		(start 403.219666 -19.143472)
		(end 403.220174 -19.142202)
		(width 0.1778)
		(layer "B.Cu")
		(net "SAS_BLAD2_RX3_P")
	)
	(segment
		(start 395.066266 -13.383768)
		(end 395.066266 -4.528312)
		(width 0.1778)
		(layer "B.Cu")
		(net "SAS_BLAD2_RX3_P")
	)
	(segment
		(start 409.348686 -26.78938)
		(end 409.104592 -26.78938)
		(width 0.1778)
		(layer "B.Cu")
		(net "SAS_BLAD2_RX3_P")
	)
	(segment
		(start 396.897352 -14.228318)
		(end 395.694154 -13.97508)
		(width 0.1778)
		(layer "B.Cu")
		(net "SAS_BLAD2_RX3_P")
	)
	(segment
		(start 404.746206 -21.552662)
		(end 404.747476 -21.547328)
		(width 0.1778)
		(layer "B.Cu")
		(net "SAS_BLAD2_RX3_P")
	)
	(segment
		(start 410.112972 -27.79776)
		(end 409.72613 -27.410918)
		(width 0.1778)
		(layer "B.Cu")
		(net "SAS_BLAD2_RX3_P")
	)
	(segment
		(start 395.694154 -13.97508)
		(end 395.657578 -13.97508)
		(width 0.1778)
		(layer "B.Cu")
		(net "SAS_BLAD2_RX3_P")
	)
	(segment
		(start 410.35732 -27.79776)
		(end 410.112972 -27.79776)
		(width 0.1778)
		(layer "B.Cu")
		(net "SAS_BLAD2_RX3_P")
	)
	(segment
		(start 403.690074 -19.88566)
		(end 403.743668 -19.647408)
		(width 0.1778)
		(layer "B.Cu")
		(net "SAS_BLAD2_RX3_P")
	)
	(segment
		(start 403.982936 -20.347686)
		(end 403.983698 -20.344892)
		(width 0.1778)
		(layer "B.Cu")
		(net "SAS_BLAD2_RX3_P")
	)
	(arc
		(start 395.657578 -13.97508)
		(mid 395.597342 -13.963062)
		(end 395.546326 -13.928852)
		(width 0.1778)
		(layer "B.Cu")
		(net "SAS_BLAD2_RX3_P")
	)
	(arc
		(start 394.821918 -4.073652)
		(mid 394.65715 -3.963494)
		(end 394.462762 -3.924808)
		(width 0.1778)
		(layer "B.Cu")
		(net "SAS_BLAD2_RX3_P")
	)
	(arc
		(start 395.066266 -4.528312)
		(mid 395.027513 -4.333757)
		(end 394.917168 -4.168902)
		(width 0.1778)
		(layer "B.Cu")
		(net "SAS_BLAD2_RX3_P")
	)
	(arc
		(start 408.830272 -26.51506)
		(mid 408.820117 -26.505267)
		(end 408.809698 -26.495756)
		(width 0.1778)
		(layer "B.Cu")
		(net "SAS_BLAD2_RX3_P")
	)
	(arc
		(start 411.270196 -29.165296)
		(mid 411.231512 -28.970907)
		(end 411.121352 -28.80614)
		(width 0.1778)
		(layer "B.Cu")
		(net "SAS_BLAD2_RX3_P")
	)
	(arc
		(start 395.112494 -13.49502)
		(mid 395.078281 -13.444006)
		(end 395.066266 -13.383768)
		(width 0.1778)
		(layer "B.Cu")
		(net "SAS_BLAD2_RX3_P")
	)
	(segment
		(start 389.909558 -24.584152)
		(end 389.684768 -24.808942)
		(width 0.1778)
		(layer "F.Cu")
		(net "SAS_BLAD2_TX8_N")
	)
	(segment
		(start 387.700012 -24.1808)
		(end 389.693404 -24.1808)
		(width 0.1778)
		(layer "F.Cu")
		(net "SAS_BLAD2_TX8_N")
	)
	(segment
		(start 389.909558 -24.396954)
		(end 389.909558 -24.584152)
		(width 0.1778)
		(layer "F.Cu")
		(net "SAS_BLAD2_TX8_N")
	)
	(segment
		(start 387.217412 -24.6634)
		(end 387.700012 -24.1808)
		(width 0.1778)
		(layer "F.Cu")
		(net "SAS_BLAD2_TX8_N")
	)
	(segment
		(start 389.684768 -24.808942)
		(end 389.684768 -25.899872)
		(width 0.1778)
		(layer "F.Cu")
		(net "SAS_BLAD2_TX8_N")
	)
	(segment
		(start 389.693404 -24.1808)
		(end 389.909558 -24.396954)
		(width 0.1778)
		(layer "F.Cu")
		(net "SAS_BLAD2_TX8_N")
	)
	(via
		(at 387.217412 -24.6634)
		(size 0.508)
		(drill 0.254)
		(layers "F.Cu" "B.Cu")
		(net "SAS_BLAD2_TX8_N")
	)
	(segment
		(start 388.462266 -23.665688)
		(end 388.462266 -23.044912)
		(width 0.1524)
		(layer "In5.Cu")
		(net "SAS_BLAD2_TX8_N")
	)
	(segment
		(start 385.393184 -8.503158)
		(end 385.890008 -8.999982)
		(width 0.1524)
		(layer "In5.Cu")
		(net "SAS_BLAD2_TX8_N")
	)
	(segment
		(start 387.217412 -24.6634)
		(end 387.649212 -24.2316)
		(width 0.1524)
		(layer "In5.Cu")
		(net "SAS_BLAD2_TX8_N")
	)
	(segment
		(start 388.25551 -24.082756)
		(end 388.313422 -24.024844)
		(width 0.1524)
		(layer "In5.Cu")
		(net "SAS_BLAD2_TX8_N")
	)
	(segment
		(start 382.89611 -9.172956)
		(end 383.417064 -8.652002)
		(width 0.1524)
		(layer "In5.Cu")
		(net "SAS_BLAD2_TX8_N")
	)
	(segment
		(start 387.649212 -24.2316)
		(end 387.896354 -24.2316)
		(width 0.1524)
		(layer "In5.Cu")
		(net "SAS_BLAD2_TX8_N")
	)
	(segment
		(start 383.77622 -8.503158)
		(end 385.393184 -8.503158)
		(width 0.1524)
		(layer "In5.Cu")
		(net "SAS_BLAD2_TX8_N")
	)
	(segment
		(start 382.747266 -16.909288)
		(end 382.747266 -9.532112)
		(width 0.1524)
		(layer "In5.Cu")
		(net "SAS_BLAD2_TX8_N")
	)
	(segment
		(start 388.313422 -22.685756)
		(end 382.89611 -17.268444)
		(width 0.1524)
		(layer "In5.Cu")
		(net "SAS_BLAD2_TX8_N")
	)
	(arc
		(start 387.896354 -24.2316)
		(mid 388.090743 -24.192916)
		(end 388.25551 -24.082756)
		(width 0.1524)
		(layer "In5.Cu")
		(net "SAS_BLAD2_TX8_N")
	)
	(arc
		(start 383.417064 -8.652002)
		(mid 383.581832 -8.541844)
		(end 383.77622 -8.503158)
		(width 0.1524)
		(layer "In5.Cu")
		(net "SAS_BLAD2_TX8_N")
	)
	(arc
		(start 388.313422 -24.024844)
		(mid 388.42358 -23.860076)
		(end 388.462266 -23.665688)
		(width 0.1524)
		(layer "In5.Cu")
		(net "SAS_BLAD2_TX8_N")
	)
	(arc
		(start 382.89611 -17.268444)
		(mid 382.785952 -17.103676)
		(end 382.747266 -16.909288)
		(width 0.1524)
		(layer "In5.Cu")
		(net "SAS_BLAD2_TX8_N")
	)
	(arc
		(start 388.462266 -23.044912)
		(mid 388.423582 -22.850523)
		(end 388.313422 -22.685756)
		(width 0.1524)
		(layer "In5.Cu")
		(net "SAS_BLAD2_TX8_N")
	)
	(arc
		(start 382.747266 -9.532112)
		(mid 382.78595 -9.337723)
		(end 382.89611 -9.172956)
		(width 0.1524)
		(layer "In5.Cu")
		(net "SAS_BLAD2_TX8_N")
	)
	(segment
		(start 397.685514 -24.1808)
		(end 398.741392 -24.1808)
		(width 0.1778)
		(layer "F.Cu")
		(net "SAS_BLAD2_TX5_P")
	)
	(segment
		(start 397.459962 -24.584152)
		(end 397.459962 -24.406352)
		(width 0.1778)
		(layer "F.Cu")
		(net "SAS_BLAD2_TX5_P")
	)
	(segment
		(start 398.741392 -24.1808)
		(end 399.223992 -24.6634)
		(width 0.1778)
		(layer "F.Cu")
		(net "SAS_BLAD2_TX5_P")
	)
	(segment
		(start 397.684752 -25.899872)
		(end 397.684752 -24.808942)
		(width 0.1778)
		(layer "F.Cu")
		(net "SAS_BLAD2_TX5_P")
	)
	(segment
		(start 397.459962 -24.406352)
		(end 397.685514 -24.1808)
		(width 0.1778)
		(layer "F.Cu")
		(net "SAS_BLAD2_TX5_P")
	)
	(segment
		(start 397.684752 -24.808942)
		(end 397.459962 -24.584152)
		(width 0.1778)
		(layer "F.Cu")
		(net "SAS_BLAD2_TX5_P")
	)
	(via
		(at 399.223992 -24.6634)
		(size 0.508)
		(drill 0.254)
		(layers "F.Cu" "B.Cu")
		(net "SAS_BLAD2_TX5_P")
	)
	(segment
		(start 397.759682 -21.03628)
		(end 397.932402 -20.86356)
		(width 0.1778)
		(layer "B.Cu")
		(net "SAS_BLAD2_TX5_P")
	)
	(segment
		(start 396.533624 -20.110704)
		(end 396.533624 -20.111212)
		(width 0.1778)
		(layer "B.Cu")
		(net "SAS_BLAD2_TX5_P")
	)
	(segment
		(start 400.185636 -21.78177)
		(end 400.185636 -22.022562)
		(width 0.1778)
		(layer "B.Cu")
		(net "SAS_BLAD2_TX5_P")
	)
	(segment
		(start 399.989294 -24.20366)
		(end 399.683732 -24.20366)
		(width 0.1778)
		(layer "B.Cu")
		(net "SAS_BLAD2_TX5_P")
	)
	(segment
		(start 396.146782 -19.723862)
		(end 396.533624 -20.110704)
		(width 0.1778)
		(layer "B.Cu")
		(net "SAS_BLAD2_TX5_P")
	)
	(segment
		(start 395.138402 -18.715736)
		(end 395.525244 -19.102578)
		(width 0.1778)
		(layer "B.Cu")
		(net "SAS_BLAD2_TX5_P")
	)
	(segment
		(start 400.454368 -23.948898)
		(end 400.34845 -24.054816)
		(width 0.1778)
		(layer "B.Cu")
		(net "SAS_BLAD2_TX5_P")
	)
	(segment
		(start 396.146782 -19.479768)
		(end 396.146782 -19.723862)
		(width 0.1778)
		(layer "B.Cu")
		(net "SAS_BLAD2_TX5_P")
	)
	(segment
		(start 400.185636 -22.022562)
		(end 400.352006 -22.188932)
		(width 0.1778)
		(layer "B.Cu")
		(net "SAS_BLAD2_TX5_P")
	)
	(segment
		(start 395.525244 -19.102578)
		(end 395.769592 -19.102578)
		(width 0.1778)
		(layer "B.Cu")
		(net "SAS_BLAD2_TX5_P")
	)
	(segment
		(start 390.101074 -8.124698)
		(end 390.522714 -8.124698)
		(width 0.1778)
		(layer "B.Cu")
		(net "SAS_BLAD2_TX5_P")
	)
	(segment
		(start 394.516864 -18.094198)
		(end 394.761212 -18.094198)
		(width 0.1778)
		(layer "B.Cu")
		(net "SAS_BLAD2_TX5_P")
	)
	(segment
		(start 396.777972 -20.111212)
		(end 397.155162 -20.488148)
		(width 0.1778)
		(layer "B.Cu")
		(net "SAS_BLAD2_TX5_P")
	)
	(segment
		(start 398.638522 -21.03628)
		(end 398.843754 -21.03628)
		(width 0.1778)
		(layer "B.Cu")
		(net "SAS_BLAD2_TX5_P")
	)
	(segment
		(start 389.89 -7.600188)
		(end 389.89 -7.913624)
		(width 0.1778)
		(layer "B.Cu")
		(net "SAS_BLAD2_TX5_P")
	)
	(segment
		(start 391.061194 -13.8938)
		(end 391.245852 -14.650466)
		(width 0.1778)
		(layer "B.Cu")
		(net "SAS_BLAD2_TX5_P")
	)
	(segment
		(start 399.683732 -24.20366)
		(end 399.223992 -24.6634)
		(width 0.1778)
		(layer "B.Cu")
		(net "SAS_BLAD2_TX5_P")
	)
	(segment
		(start 399.567654 -21.40458)
		(end 399.808446 -21.40458)
		(width 0.1778)
		(layer "B.Cu")
		(net "SAS_BLAD2_TX5_P")
	)
	(segment
		(start 389.89 -7.913624)
		(end 390.101074 -8.124698)
		(width 0.1778)
		(layer "B.Cu")
		(net "SAS_BLAD2_TX5_P")
	)
	(segment
		(start 394.35405 -17.93113)
		(end 394.516864 -18.094198)
		(width 0.1778)
		(layer "B.Cu")
		(net "SAS_BLAD2_TX5_P")
	)
	(segment
		(start 397.932402 -20.86356)
		(end 398.465802 -20.86356)
		(width 0.1778)
		(layer "B.Cu")
		(net "SAS_BLAD2_TX5_P")
	)
	(segment
		(start 391.621518 -15.554452)
		(end 393.746736 -17.67967)
		(width 0.1778)
		(layer "B.Cu")
		(net "SAS_BLAD2_TX5_P")
	)
	(segment
		(start 397.155162 -20.732496)
		(end 397.412718 -20.990052)
		(width 0.1778)
		(layer "B.Cu")
		(net "SAS_BLAD2_TX5_P")
	)
	(segment
		(start 396.533624 -20.111212)
		(end 396.777972 -20.111212)
		(width 0.1778)
		(layer "B.Cu")
		(net "SAS_BLAD2_TX5_P")
	)
	(segment
		(start 394.761212 -18.094198)
		(end 395.138402 -18.471388)
		(width 0.1778)
		(layer "B.Cu")
		(net "SAS_BLAD2_TX5_P")
	)
	(segment
		(start 395.138402 -18.471388)
		(end 395.138402 -18.715736)
		(width 0.1778)
		(layer "B.Cu")
		(net "SAS_BLAD2_TX5_P")
	)
	(segment
		(start 399.808446 -21.40458)
		(end 400.185636 -21.78177)
		(width 0.1778)
		(layer "B.Cu")
		(net "SAS_BLAD2_TX5_P")
	)
	(segment
		(start 391.245852 -14.650466)
		(end 391.621518 -15.554452)
		(width 0.1778)
		(layer "B.Cu")
		(net "SAS_BLAD2_TX5_P")
	)
	(segment
		(start 400.603466 -22.795992)
		(end 400.603466 -23.589488)
		(width 0.1778)
		(layer "B.Cu")
		(net "SAS_BLAD2_TX5_P")
	)
	(segment
		(start 397.52397 -21.03628)
		(end 397.759682 -21.03628)
		(width 0.1778)
		(layer "B.Cu")
		(net "SAS_BLAD2_TX5_P")
	)
	(segment
		(start 399.450814 -21.28774)
		(end 399.567654 -21.40458)
		(width 0.1778)
		(layer "B.Cu")
		(net "SAS_BLAD2_TX5_P")
	)
	(segment
		(start 395.769592 -19.102578)
		(end 396.146782 -19.479768)
		(width 0.1778)
		(layer "B.Cu")
		(net "SAS_BLAD2_TX5_P")
	)
	(segment
		(start 397.155162 -20.488148)
		(end 397.155162 -20.732496)
		(width 0.1778)
		(layer "B.Cu")
		(net "SAS_BLAD2_TX5_P")
	)
	(segment
		(start 391.061194 -8.662924)
		(end 391.061194 -13.8938)
		(width 0.1778)
		(layer "B.Cu")
		(net "SAS_BLAD2_TX5_P")
	)
	(segment
		(start 398.465802 -20.86356)
		(end 398.638522 -21.03628)
		(width 0.1778)
		(layer "B.Cu")
		(net "SAS_BLAD2_TX5_P")
	)
	(arc
		(start 394.050266 -17.8054)
		(mid 394.214673 -17.838027)
		(end 394.35405 -17.93113)
		(width 0.1778)
		(layer "B.Cu")
		(net "SAS_BLAD2_TX5_P")
	)
	(arc
		(start 400.603466 -23.589488)
		(mid 400.564713 -23.784043)
		(end 400.454368 -23.948898)
		(width 0.1778)
		(layer "B.Cu")
		(net "SAS_BLAD2_TX5_P")
	)
	(arc
		(start 393.746736 -17.67967)
		(mid 393.885997 -17.772721)
		(end 394.050266 -17.8054)
		(width 0.1778)
		(layer "B.Cu")
		(net "SAS_BLAD2_TX5_P")
	)
	(arc
		(start 390.522714 -8.124698)
		(mid 390.728893 -8.165692)
		(end 390.903714 -8.282432)
		(width 0.1778)
		(layer "B.Cu")
		(net "SAS_BLAD2_TX5_P")
	)
	(arc
		(start 400.34845 -24.054816)
		(mid 400.183682 -24.164974)
		(end 399.989294 -24.20366)
		(width 0.1778)
		(layer "B.Cu")
		(net "SAS_BLAD2_TX5_P")
	)
	(arc
		(start 398.843754 -21.03628)
		(mid 399.172295 -21.101631)
		(end 399.450814 -21.28774)
		(width 0.1778)
		(layer "B.Cu")
		(net "SAS_BLAD2_TX5_P")
	)
	(arc
		(start 397.412718 -20.990052)
		(mid 397.463732 -21.024265)
		(end 397.52397 -21.03628)
		(width 0.1778)
		(layer "B.Cu")
		(net "SAS_BLAD2_TX5_P")
	)
	(arc
		(start 400.352006 -22.188932)
		(mid 400.538108 -22.467453)
		(end 400.603466 -22.795992)
		(width 0.1778)
		(layer "B.Cu")
		(net "SAS_BLAD2_TX5_P")
	)
	(arc
		(start 390.903714 -8.282432)
		(mid 391.020251 -8.457032)
		(end 391.061194 -8.662924)
		(width 0.1778)
		(layer "B.Cu")
		(net "SAS_BLAD2_TX5_P")
	)
	(segment
		(start 409.49499 -25.899872)
		(end 409.49499 -24.809196)
		(width 0.1778)
		(layer "F.Cu")
		(net "SAS_BLAD2_TX4_P")
	)
	(segment
		(start 409.49499 -24.809196)
		(end 409.269946 -24.584152)
		(width 0.1778)
		(layer "F.Cu")
		(net "SAS_BLAD2_TX4_P")
	)
	(segment
		(start 409.269946 -23.957534)
		(end 408.705812 -23.3934)
		(width 0.1778)
		(layer "F.Cu")
		(net "SAS_BLAD2_TX4_P")
	)
	(segment
		(start 405.459692 -24.93772)
		(end 405.459692 -26.36012)
		(width 0.1778)
		(layer "F.Cu")
		(net "SAS_BLAD2_TX4_P")
	)
	(segment
		(start 409.269946 -24.584152)
		(end 409.269946 -23.957534)
		(width 0.1778)
		(layer "F.Cu")
		(net "SAS_BLAD2_TX4_P")
	)
	(segment
		(start 408.705812 -23.3934)
		(end 407.004012 -23.3934)
		(width 0.1778)
		(layer "F.Cu")
		(net "SAS_BLAD2_TX4_P")
	)
	(segment
		(start 407.004012 -23.3934)
		(end 405.459692 -24.93772)
		(width 0.1778)
		(layer "F.Cu")
		(net "SAS_BLAD2_TX4_P")
	)
	(segment
		(start 405.459692 -26.36012)
		(end 404.997412 -26.8224)
		(width 0.1778)
		(layer "F.Cu")
		(net "SAS_BLAD2_TX4_P")
	)
	(via
		(at 404.997412 -26.8224)
		(size 0.508)
		(drill 0.254)
		(layers "F.Cu" "B.Cu")
		(net "SAS_BLAD2_TX4_P")
	)
	(segment
		(start 402.965666 -23.341076)
		(end 402.965666 -23.913846)
		(width 0.1778)
		(layer "B.Cu")
		(net "SAS_BLAD2_TX4_P")
	)
	(segment
		(start 402.965666 -24.792686)
		(end 402.965666 -25.336246)
		(width 0.1778)
		(layer "B.Cu")
		(net "SAS_BLAD2_TX4_P")
	)
	(segment
		(start 402.965666 -23.913846)
		(end 403.138386 -24.086566)
		(width 0.1778)
		(layer "B.Cu")
		(net "SAS_BLAD2_TX4_P")
	)
	(segment
		(start 405.457406 -27.282394)
		(end 404.997412 -26.8224)
		(width 0.1778)
		(layer "B.Cu")
		(net "SAS_BLAD2_TX4_P")
	)
	(segment
		(start 391.99947 -11.02487)
		(end 392.531346 -11.02487)
		(width 0.1778)
		(layer "B.Cu")
		(net "SAS_BLAD2_TX4_P")
	)
	(segment
		(start 393.06119 -11.554968)
		(end 393.06119 -13.906246)
		(width 0.1778)
		(layer "B.Cu")
		(net "SAS_BLAD2_TX4_P")
	)
	(segment
		(start 399.776442 -19.11477)
		(end 400.555714 -19.437858)
		(width 0.1778)
		(layer "B.Cu")
		(net "SAS_BLAD2_TX4_P")
	)
	(segment
		(start 393.250928 -14.364462)
		(end 394.638022 -15.751556)
		(width 0.1778)
		(layer "B.Cu")
		(net "SAS_BLAD2_TX4_P")
	)
	(segment
		(start 403.138386 -24.619966)
		(end 402.965666 -24.792686)
		(width 0.1778)
		(layer "B.Cu")
		(net "SAS_BLAD2_TX4_P")
	)
	(segment
		(start 398.642586 -18.39722)
		(end 398.642586 -18.61312)
		(width 0.1778)
		(layer "B.Cu")
		(net "SAS_BLAD2_TX4_P")
	)
	(segment
		(start 392.905488 -11.17981)
		(end 392.905742 -11.180064)
		(width 0.1778)
		(layer "B.Cu")
		(net "SAS_BLAD2_TX4_P")
	)
	(segment
		(start 398.049496 -18.02003)
		(end 398.265396 -18.02003)
		(width 0.1778)
		(layer "B.Cu")
		(net "SAS_BLAD2_TX4_P")
	)
	(segment
		(start 403.138386 -25.508966)
		(end 403.138386 -26.042366)
		(width 0.1778)
		(layer "B.Cu")
		(net "SAS_BLAD2_TX4_P")
	)
	(segment
		(start 402.965666 -26.215086)
		(end 402.965666 -26.535888)
		(width 0.1778)
		(layer "B.Cu")
		(net "SAS_BLAD2_TX4_P")
	)
	(segment
		(start 401.980654 -20.862798)
		(end 402.927058 -23.146512)
		(width 0.1778)
		(layer "B.Cu")
		(net "SAS_BLAD2_TX4_P")
	)
	(segment
		(start 398.642586 -18.61312)
		(end 398.961102 -18.931636)
		(width 0.1778)
		(layer "B.Cu")
		(net "SAS_BLAD2_TX4_P")
	)
	(segment
		(start 395.426438 -15.932658)
		(end 396.248128 -16.273272)
		(width 0.1778)
		(layer "B.Cu")
		(net "SAS_BLAD2_TX4_P")
	)
	(segment
		(start 396.41272 -16.383254)
		(end 398.049496 -18.02003)
		(width 0.1778)
		(layer "B.Cu")
		(net "SAS_BLAD2_TX4_P")
	)
	(segment
		(start 402.965666 -25.336246)
		(end 403.138386 -25.508966)
		(width 0.1778)
		(layer "B.Cu")
		(net "SAS_BLAD2_TX4_P")
	)
	(segment
		(start 391.889996 -10.500106)
		(end 391.889996 -10.915396)
		(width 0.1778)
		(layer "B.Cu")
		(net "SAS_BLAD2_TX4_P")
	)
	(segment
		(start 403.11451 -26.895044)
		(end 404.015702 -27.796236)
		(width 0.1778)
		(layer "B.Cu")
		(net "SAS_BLAD2_TX4_P")
	)
	(segment
		(start 403.138386 -26.042366)
		(end 402.965666 -26.215086)
		(width 0.1778)
		(layer "B.Cu")
		(net "SAS_BLAD2_TX4_P")
	)
	(segment
		(start 398.265396 -18.02003)
		(end 398.642586 -18.39722)
		(width 0.1778)
		(layer "B.Cu")
		(net "SAS_BLAD2_TX4_P")
	)
	(segment
		(start 404.374858 -27.94508)
		(end 405.092154 -27.94508)
		(width 0.1778)
		(layer "B.Cu")
		(net "SAS_BLAD2_TX4_P")
	)
	(segment
		(start 405.203406 -27.898852)
		(end 405.411178 -27.69108)
		(width 0.1778)
		(layer "B.Cu")
		(net "SAS_BLAD2_TX4_P")
	)
	(segment
		(start 399.320258 -19.08048)
		(end 399.603976 -19.08048)
		(width 0.1778)
		(layer "B.Cu")
		(net "SAS_BLAD2_TX4_P")
	)
	(segment
		(start 391.889996 -10.915396)
		(end 391.99947 -11.02487)
		(width 0.1778)
		(layer "B.Cu")
		(net "SAS_BLAD2_TX4_P")
	)
	(segment
		(start 405.457406 -27.579828)
		(end 405.457406 -27.282394)
		(width 0.1778)
		(layer "B.Cu")
		(net "SAS_BLAD2_TX4_P")
	)
	(segment
		(start 403.138386 -24.086566)
		(end 403.138386 -24.619966)
		(width 0.1778)
		(layer "B.Cu")
		(net "SAS_BLAD2_TX4_P")
	)
	(segment
		(start 400.720306 -19.54784)
		(end 401.870672 -20.698206)
		(width 0.1778)
		(layer "B.Cu")
		(net "SAS_BLAD2_TX4_P")
	)
	(segment
		(start 394.997178 -15.9004)
		(end 395.264132 -15.9004)
		(width 0.1778)
		(layer "B.Cu")
		(net "SAS_BLAD2_TX4_P")
	)
	(segment
		(start 393.06119 -13.906246)
		(end 393.250928 -14.364462)
		(width 0.1778)
		(layer "B.Cu")
		(net "SAS_BLAD2_TX4_P")
	)
	(arc
		(start 405.411178 -27.69108)
		(mid 405.445391 -27.640066)
		(end 405.457406 -27.579828)
		(width 0.1778)
		(layer "B.Cu")
		(net "SAS_BLAD2_TX4_P")
	)
	(arc
		(start 394.638022 -15.751556)
		(mid 394.80279 -15.861714)
		(end 394.997178 -15.9004)
		(width 0.1778)
		(layer "B.Cu")
		(net "SAS_BLAD2_TX4_P")
	)
	(arc
		(start 400.555714 -19.437858)
		(mid 400.643423 -19.48475)
		(end 400.720306 -19.54784)
		(width 0.1778)
		(layer "B.Cu")
		(net "SAS_BLAD2_TX4_P")
	)
	(arc
		(start 404.015702 -27.796236)
		(mid 404.18047 -27.906394)
		(end 404.374858 -27.94508)
		(width 0.1778)
		(layer "B.Cu")
		(net "SAS_BLAD2_TX4_P")
	)
	(arc
		(start 396.248128 -16.273272)
		(mid 396.335837 -16.320164)
		(end 396.41272 -16.383254)
		(width 0.1778)
		(layer "B.Cu")
		(net "SAS_BLAD2_TX4_P")
	)
	(arc
		(start 401.870672 -20.698206)
		(mid 401.933749 -20.775098)
		(end 401.980654 -20.862798)
		(width 0.1778)
		(layer "B.Cu")
		(net "SAS_BLAD2_TX4_P")
	)
	(arc
		(start 392.905742 -11.180064)
		(mid 393.020757 -11.352056)
		(end 393.06119 -11.554968)
		(width 0.1778)
		(layer "B.Cu")
		(net "SAS_BLAD2_TX4_P")
	)
	(arc
		(start 399.603976 -19.08048)
		(mid 399.691897 -19.089136)
		(end 399.776442 -19.11477)
		(width 0.1778)
		(layer "B.Cu")
		(net "SAS_BLAD2_TX4_P")
	)
	(arc
		(start 395.264132 -15.9004)
		(mid 395.346872 -15.908543)
		(end 395.426438 -15.932658)
		(width 0.1778)
		(layer "B.Cu")
		(net "SAS_BLAD2_TX4_P")
	)
	(arc
		(start 405.092154 -27.94508)
		(mid 405.15239 -27.933062)
		(end 405.203406 -27.898852)
		(width 0.1778)
		(layer "B.Cu")
		(net "SAS_BLAD2_TX4_P")
	)
	(arc
		(start 392.531346 -11.02487)
		(mid 392.733842 -11.065091)
		(end 392.905488 -11.17981)
		(width 0.1778)
		(layer "B.Cu")
		(net "SAS_BLAD2_TX4_P")
	)
	(arc
		(start 402.927058 -23.146512)
		(mid 402.955961 -23.24189)
		(end 402.965666 -23.341076)
		(width 0.1778)
		(layer "B.Cu")
		(net "SAS_BLAD2_TX4_P")
	)
	(arc
		(start 402.965666 -26.535888)
		(mid 403.00435 -26.730277)
		(end 403.11451 -26.895044)
		(width 0.1778)
		(layer "B.Cu")
		(net "SAS_BLAD2_TX4_P")
	)
	(arc
		(start 398.961102 -18.931636)
		(mid 399.12587 -19.041794)
		(end 399.320258 -19.08048)
		(width 0.1778)
		(layer "B.Cu")
		(net "SAS_BLAD2_TX4_P")
	)
	(segment
		(start 142.9512 -3.44805)
		(end 142.09395 -3.44805)
		(width 0.4572)
		(layer "F.Cu")
		(net "P3V3_10G_1_VCCR")
	)
	(segment
		(start 156.959046 -32.0548)
		(end 156.959046 -33.36544)
		(width 0.508)
		(layer "F.Cu")
		(net "P3V3_10G_1_VCCR")
	)
	(segment
		(start 157.00756 -30.545532)
		(end 157.00756 -32.006286)
		(width 0.508)
		(layer "F.Cu")
		(net "P3V3_10G_1_VCCR")
	)
	(segment
		(start 157.00756 -30.545532)
		(end 158.0388 -30.545532)
		(width 0.508)
		(layer "F.Cu")
		(net "P3V3_10G_1_VCCR")
	)
	(segment
		(start 157.00756 -32.006286)
		(end 156.959046 -32.0548)
		(width 0.508)
		(layer "F.Cu")
		(net "P3V3_10G_1_VCCR")
	)
	(segment
		(start 144.0942 -3.44805)
		(end 142.9512 -3.44805)
		(width 0.4572)
		(layer "F.Cu")
		(net "P3V3_10G_1_VCCR")
	)
	(segment
		(start 142.290292 -10.290048)
		(end 142.290292 -11.7094)
		(width 0.4572)
		(layer "F.Cu")
		(net "P3V3_10G_1_VCCR")
	)
	(via
		(at 158.0388 -30.545532)
		(size 0.508)
		(drill 0.254)
		(layers "F.Cu" "B.Cu")
		(net "P3V3_10G_1_VCCR")
	)
	(via
		(at 142.09395 -3.44805)
		(size 0.508)
		(drill 0.254)
		(layers "F.Cu" "B.Cu")
		(net "P3V3_10G_1_VCCR")
	)
	(via
		(at 142.290292 -11.7094)
		(size 0.508)
		(drill 0.254)
		(layers "F.Cu" "B.Cu")
		(net "P3V3_10G_1_VCCR")
	)
	(segment
		(start 158.0388 -29.449522)
		(end 155.575 -26.985722)
		(width 0.4572)
		(layer "In2.Cu")
		(net "P3V3_10G_1_VCCR")
	)
	(segment
		(start 155.575 -23.5712)
		(end 150.659338 -18.655538)
		(width 0.4572)
		(layer "In2.Cu")
		(net "P3V3_10G_1_VCCR")
	)
	(segment
		(start 150.659338 -18.655538)
		(end 150.659338 -7.98576)
		(width 0.4572)
		(layer "In2.Cu")
		(net "P3V3_10G_1_VCCR")
	)
	(segment
		(start 150.659338 -7.98576)
		(end 146.508978 -3.8354)
		(width 0.4572)
		(layer "In2.Cu")
		(net "P3V3_10G_1_VCCR")
	)
	(segment
		(start 155.575 -26.985722)
		(end 155.575 -23.5712)
		(width 0.4572)
		(layer "In2.Cu")
		(net "P3V3_10G_1_VCCR")
	)
	(segment
		(start 158.0388 -30.545532)
		(end 158.0388 -29.449522)
		(width 0.4572)
		(layer "In2.Cu")
		(net "P3V3_10G_1_VCCR")
	)
	(segment
		(start 146.508978 -3.8354)
		(end 142.4813 -3.8354)
		(width 0.4572)
		(layer "In2.Cu")
		(net "P3V3_10G_1_VCCR")
	)
	(segment
		(start 142.4813 -3.8354)
		(end 142.09395 -3.44805)
		(width 0.4572)
		(layer "In2.Cu")
		(net "P3V3_10G_1_VCCR")
	)
	(segment
		(start 141.859 -12.319)
		(end 142.290292 -11.887708)
		(width 0.4572)
		(layer "In5.Cu")
		(net "P3V3_10G_1_VCCR")
	)
	(segment
		(start 136.6266 -7.6962)
		(end 136.6266 -8.636)
		(width 0.4572)
		(layer "In5.Cu")
		(net "P3V3_10G_1_VCCR")
	)
	(segment
		(start 142.09395 -3.44805)
		(end 140.87475 -3.44805)
		(width 0.4572)
		(layer "In5.Cu")
		(net "P3V3_10G_1_VCCR")
	)
	(segment
		(start 137.922 -9.9314)
		(end 137.922 -11.4808)
		(width 0.4572)
		(layer "In5.Cu")
		(net "P3V3_10G_1_VCCR")
	)
	(segment
		(start 137.922 -11.4808)
		(end 138.7602 -12.319)
		(width 0.4572)
		(layer "In5.Cu")
		(net "P3V3_10G_1_VCCR")
	)
	(segment
		(start 140.87475 -3.44805)
		(end 136.6266 -7.6962)
		(width 0.4572)
		(layer "In5.Cu")
		(net "P3V3_10G_1_VCCR")
	)
	(segment
		(start 142.290292 -11.887708)
		(end 142.290292 -11.7094)
		(width 0.4572)
		(layer "In5.Cu")
		(net "P3V3_10G_1_VCCR")
	)
	(segment
		(start 138.7602 -12.319)
		(end 141.859 -12.319)
		(width 0.4572)
		(layer "In5.Cu")
		(net "P3V3_10G_1_VCCR")
	)
	(segment
		(start 136.6266 -8.636)
		(end 137.922 -9.9314)
		(width 0.4572)
		(layer "In5.Cu")
		(net "P3V3_10G_1_VCCR")
	)
	(segment
		(start 405.810212 -25.083008)
		(end 405.810212 -26.3652)
		(width 0.1778)
		(layer "F.Cu")
		(net "SAS_BLAD2_TX4_N")
	)
	(segment
		(start 405.810212 -26.3652)
		(end 406.267412 -26.8224)
		(width 0.1778)
		(layer "F.Cu")
		(net "SAS_BLAD2_TX4_N")
	)
	(segment
		(start 408.560524 -23.74392)
		(end 407.1493 -23.74392)
		(width 0.1778)
		(layer "F.Cu")
		(net "SAS_BLAD2_TX4_N")
	)
	(segment
		(start 407.1493 -23.74392)
		(end 405.810212 -25.083008)
		(width 0.1778)
		(layer "F.Cu")
		(net "SAS_BLAD2_TX4_N")
	)
	(segment
		(start 408.69489 -24.808688)
		(end 408.919426 -24.584152)
		(width 0.1778)
		(layer "F.Cu")
		(net "SAS_BLAD2_TX4_N")
	)
	(segment
		(start 408.919426 -24.102822)
		(end 408.560524 -23.74392)
		(width 0.1778)
		(layer "F.Cu")
		(net "SAS_BLAD2_TX4_N")
	)
	(segment
		(start 408.69489 -25.899872)
		(end 408.69489 -24.808688)
		(width 0.1778)
		(layer "F.Cu")
		(net "SAS_BLAD2_TX4_N")
	)
	(segment
		(start 408.919426 -24.584152)
		(end 408.919426 -24.102822)
		(width 0.1778)
		(layer "F.Cu")
		(net "SAS_BLAD2_TX4_N")
	)
	(via
		(at 406.267412 -26.8224)
		(size 0.508)
		(drill 0.254)
		(layers "F.Cu" "B.Cu")
		(net "SAS_BLAD2_TX4_N")
	)
	(segment
		(start 406.267412 -26.8224)
		(end 405.807926 -27.281886)
		(width 0.1778)
		(layer "B.Cu")
		(net "SAS_BLAD2_TX4_N")
	)
	(segment
		(start 392.953748 -14.56309)
		(end 392.71067 -13.976096)
		(width 0.1778)
		(layer "B.Cu")
		(net "SAS_BLAD2_TX4_N")
	)
	(segment
		(start 405.659082 -27.938984)
		(end 405.451564 -28.146502)
		(width 0.1778)
		(layer "B.Cu")
		(net "SAS_BLAD2_TX4_N")
	)
	(segment
		(start 392.531346 -11.37539)
		(end 392.07567 -11.37539)
		(width 0.1778)
		(layer "B.Cu")
		(net "SAS_BLAD2_TX4_N")
	)
	(segment
		(start 396.113762 -16.597376)
		(end 395.292326 -16.256508)
		(width 0.1778)
		(layer "B.Cu")
		(net "SAS_BLAD2_TX4_N")
	)
	(segment
		(start 401.622768 -20.94611)
		(end 400.472402 -19.795744)
		(width 0.1778)
		(layer "B.Cu")
		(net "SAS_BLAD2_TX4_N")
	)
	(segment
		(start 391.889996 -11.561064)
		(end 391.889996 -11.900154)
		(width 0.1778)
		(layer "B.Cu")
		(net "SAS_BLAD2_TX4_N")
	)
	(segment
		(start 394.390118 -15.99946)
		(end 392.953748 -14.56309)
		(width 0.1778)
		(layer "B.Cu")
		(net "SAS_BLAD2_TX4_N")
	)
	(segment
		(start 402.615146 -26.535888)
		(end 402.615146 -23.340822)
		(width 0.1778)
		(layer "B.Cu")
		(net "SAS_BLAD2_TX4_N")
	)
	(segment
		(start 405.807926 -27.281886)
		(end 405.807926 -27.579828)
		(width 0.1778)
		(layer "B.Cu")
		(net "SAS_BLAD2_TX4_N")
	)
	(segment
		(start 405.092154 -28.2956)
		(end 404.374858 -28.2956)
		(width 0.1778)
		(layer "B.Cu")
		(net "SAS_BLAD2_TX4_N")
	)
	(segment
		(start 392.07567 -11.37539)
		(end 391.889996 -11.561064)
		(width 0.1778)
		(layer "B.Cu")
		(net "SAS_BLAD2_TX4_N")
	)
	(segment
		(start 399.603976 -19.431)
		(end 399.320258 -19.431)
		(width 0.1778)
		(layer "B.Cu")
		(net "SAS_BLAD2_TX4_N")
	)
	(segment
		(start 403.767798 -28.04414)
		(end 402.866606 -27.142948)
		(width 0.1778)
		(layer "B.Cu")
		(net "SAS_BLAD2_TX4_N")
	)
	(segment
		(start 392.71067 -13.976096)
		(end 392.71067 -11.555222)
		(width 0.1778)
		(layer "B.Cu")
		(net "SAS_BLAD2_TX4_N")
	)
	(segment
		(start 398.713198 -19.17954)
		(end 396.164816 -16.631158)
		(width 0.1778)
		(layer "B.Cu")
		(net "SAS_BLAD2_TX4_N")
	)
	(segment
		(start 392.657838 -11.427968)
		(end 392.657584 -11.427714)
		(width 0.1778)
		(layer "B.Cu")
		(net "SAS_BLAD2_TX4_N")
	)
	(segment
		(start 400.421348 -19.761708)
		(end 399.64233 -19.43862)
		(width 0.1778)
		(layer "B.Cu")
		(net "SAS_BLAD2_TX4_N")
	)
	(segment
		(start 402.602954 -23.280624)
		(end 401.656804 -20.99691)
		(width 0.1778)
		(layer "B.Cu")
		(net "SAS_BLAD2_TX4_N")
	)
	(segment
		(start 395.264132 -16.25092)
		(end 394.997178 -16.25092)
		(width 0.1778)
		(layer "B.Cu")
		(net "SAS_BLAD2_TX4_N")
	)
	(arc
		(start 402.866606 -27.142948)
		(mid 402.680504 -26.864427)
		(end 402.615146 -26.535888)
		(width 0.1778)
		(layer "B.Cu")
		(net "SAS_BLAD2_TX4_N")
	)
	(arc
		(start 399.64233 -19.43862)
		(mid 399.623528 -19.432923)
		(end 399.603976 -19.431)
		(width 0.1778)
		(layer "B.Cu")
		(net "SAS_BLAD2_TX4_N")
	)
	(arc
		(start 405.807926 -27.579828)
		(mid 405.769242 -27.774217)
		(end 405.659082 -27.938984)
		(width 0.1778)
		(layer "B.Cu")
		(net "SAS_BLAD2_TX4_N")
	)
	(arc
		(start 392.71067 -11.555222)
		(mid 392.696947 -11.48632)
		(end 392.657838 -11.427968)
		(width 0.1778)
		(layer "B.Cu")
		(net "SAS_BLAD2_TX4_N")
	)
	(arc
		(start 405.451564 -28.146502)
		(mid 405.286708 -28.256845)
		(end 405.092154 -28.2956)
		(width 0.1778)
		(layer "B.Cu")
		(net "SAS_BLAD2_TX4_N")
	)
	(arc
		(start 399.320258 -19.431)
		(mid 398.991717 -19.365649)
		(end 398.713198 -19.17954)
		(width 0.1778)
		(layer "B.Cu")
		(net "SAS_BLAD2_TX4_N")
	)
	(arc
		(start 402.615146 -23.340822)
		(mid 402.612023 -23.31012)
		(end 402.602954 -23.280624)
		(width 0.1778)
		(layer "B.Cu")
		(net "SAS_BLAD2_TX4_N")
	)
	(arc
		(start 404.374858 -28.2956)
		(mid 404.046317 -28.230249)
		(end 403.767798 -28.04414)
		(width 0.1778)
		(layer "B.Cu")
		(net "SAS_BLAD2_TX4_N")
	)
	(arc
		(start 394.997178 -16.25092)
		(mid 394.668637 -16.185569)
		(end 394.390118 -15.99946)
		(width 0.1778)
		(layer "B.Cu")
		(net "SAS_BLAD2_TX4_N")
	)
	(arc
		(start 400.472402 -19.795744)
		(mid 400.448552 -19.77621)
		(end 400.421348 -19.761708)
		(width 0.1778)
		(layer "B.Cu")
		(net "SAS_BLAD2_TX4_N")
	)
	(arc
		(start 396.164816 -16.631158)
		(mid 396.140955 -16.611747)
		(end 396.113762 -16.597376)
		(width 0.1778)
		(layer "B.Cu")
		(net "SAS_BLAD2_TX4_N")
	)
	(arc
		(start 395.292326 -16.256508)
		(mid 395.278503 -16.25233)
		(end 395.264132 -16.25092)
		(width 0.1778)
		(layer "B.Cu")
		(net "SAS_BLAD2_TX4_N")
	)
	(arc
		(start 392.657584 -11.427714)
		(mid 392.599679 -11.38899)
		(end 392.531346 -11.37539)
		(width 0.1778)
		(layer "B.Cu")
		(net "SAS_BLAD2_TX4_N")
	)
	(arc
		(start 401.656804 -20.99691)
		(mid 401.642273 -20.969844)
		(end 401.622768 -20.94611)
		(width 0.1778)
		(layer "B.Cu")
		(net "SAS_BLAD2_TX4_N")
	)
	(segment
		(start 146.3294 -3.44805)
		(end 147.19935 -3.44805)
		(width 0.4572)
		(layer "F.Cu")
		(net "P3V3_10G_1_VCCT")
	)
	(segment
		(start 147.19935 -3.44805)
		(end 147.933664 -4.182364)
		(width 0.4572)
		(layer "F.Cu")
		(net "P3V3_10G_1_VCCT")
	)
	(segment
		(start 158.155132 -28.488132)
		(end 159.047942 -29.380942)
		(width 0.508)
		(layer "F.Cu")
		(net "P3V3_10G_1_VCCT")
	)
	(segment
		(start 157.00756 -28.488132)
		(end 158.155132 -28.488132)
		(width 0.508)
		(layer "F.Cu")
		(net "P3V3_10G_1_VCCT")
	)
	(segment
		(start 159.047942 -29.380942)
		(end 159.047942 -33.36544)
		(width 0.508)
		(layer "F.Cu")
		(net "P3V3_10G_1_VCCT")
	)
	(segment
		(start 143.090138 -10.290048)
		(end 143.090138 -11.7094)
		(width 0.4572)
		(layer "F.Cu")
		(net "P3V3_10G_1_VCCT")
	)
	(segment
		(start 145.2118 -3.44805)
		(end 146.3294 -3.44805)
		(width 0.4572)
		(layer "F.Cu")
		(net "P3V3_10G_1_VCCT")
	)
	(via
		(at 147.933664 -4.182364)
		(size 0.508)
		(drill 0.254)
		(layers "F.Cu" "B.Cu")
		(net "P3V3_10G_1_VCCT")
	)
	(via
		(at 158.155132 -28.488132)
		(size 0.508)
		(drill 0.254)
		(layers "F.Cu" "B.Cu")
		(net "P3V3_10G_1_VCCT")
	)
	(via
		(at 143.090138 -11.7094)
		(size 0.508)
		(drill 0.254)
		(layers "F.Cu" "B.Cu")
		(net "P3V3_10G_1_VCCT")
	)
	(segment
		(start 151.421338 -18.299938)
		(end 155.1178 -21.9964)
		(width 0.4572)
		(layer "In2.Cu")
		(net "P3V3_10G_1_VCCT")
	)
	(segment
		(start 155.1178 -21.9964)
		(end 156.467048 -21.9964)
		(width 0.4572)
		(layer "In2.Cu")
		(net "P3V3_10G_1_VCCT")
	)
	(segment
		(start 156.467048 -21.9964)
		(end 156.972 -22.501352)
		(width 0.4572)
		(layer "In2.Cu")
		(net "P3V3_10G_1_VCCT")
	)
	(segment
		(start 156.972 -22.501352)
		(end 156.972 -27.305)
		(width 0.4572)
		(layer "In2.Cu")
		(net "P3V3_10G_1_VCCT")
	)
	(segment
		(start 156.972 -27.305)
		(end 158.155132 -28.488132)
		(width 0.4572)
		(layer "In2.Cu")
		(net "P3V3_10G_1_VCCT")
	)
	(segment
		(start 151.421338 -7.670038)
		(end 151.421338 -18.299938)
		(width 0.4572)
		(layer "In2.Cu")
		(net "P3V3_10G_1_VCCT")
	)
	(segment
		(start 147.933664 -4.182364)
		(end 151.421338 -7.670038)
		(width 0.4572)
		(layer "In2.Cu")
		(net "P3V3_10G_1_VCCT")
	)
	(segment
		(start 146.3929 -2.6416)
		(end 140.589 -2.6416)
		(width 0.4572)
		(layer "In5.Cu")
		(net "P3V3_10G_1_VCCT")
	)
	(segment
		(start 137.1346 -10.287)
		(end 137.1346 -11.7856)
		(width 0.4572)
		(layer "In5.Cu")
		(net "P3V3_10G_1_VCCT")
	)
	(segment
		(start 135.8646 -9.017)
		(end 137.1346 -10.287)
		(width 0.4572)
		(layer "In5.Cu")
		(net "P3V3_10G_1_VCCT")
	)
	(segment
		(start 137.1346 -11.7856)
		(end 138.5316 -13.1826)
		(width 0.4572)
		(layer "In5.Cu")
		(net "P3V3_10G_1_VCCT")
	)
	(segment
		(start 147.933664 -4.182364)
		(end 146.3929 -2.6416)
		(width 0.4572)
		(layer "In5.Cu")
		(net "P3V3_10G_1_VCCT")
	)
	(segment
		(start 138.5316 -13.1826)
		(end 142.1384 -13.1826)
		(width 0.4572)
		(layer "In5.Cu")
		(net "P3V3_10G_1_VCCT")
	)
	(segment
		(start 135.8646 -7.366)
		(end 135.8646 -9.017)
		(width 0.4572)
		(layer "In5.Cu")
		(net "P3V3_10G_1_VCCT")
	)
	(segment
		(start 143.090138 -12.230862)
		(end 143.090138 -11.7094)
		(width 0.4572)
		(layer "In5.Cu")
		(net "P3V3_10G_1_VCCT")
	)
	(segment
		(start 140.589 -2.6416)
		(end 135.8646 -7.366)
		(width 0.4572)
		(layer "In5.Cu")
		(net "P3V3_10G_1_VCCT")
	)
	(segment
		(start 142.1384 -13.1826)
		(end 143.090138 -12.230862)
		(width 0.4572)
		(layer "In5.Cu")
		(net "P3V3_10G_1_VCCT")
	)
	(segment
		(start 344.735404 -30.578552)
		(end 344.669364 -30.38094)
		(width 0.14732)
		(layer "B.Cu")
		(net "ENET1G_4_MDI2N")
	)
	(segment
		(start 342.225122 -7.152386)
		(end 342.488266 -7.41553)
		(width 0.14732)
		(layer "B.Cu")
		(net "ENET1G_4_MDI2N")
	)
	(segment
		(start 345.18219 -26.284682)
		(end 345.18219 -26.51379)
		(width 0.14732)
		(layer "B.Cu")
		(net "ENET1G_4_MDI2N")
	)
	(segment
		(start 342.488266 -7.41553)
		(end 342.488266 -23.590758)
		(width 0.14732)
		(layer "B.Cu")
		(net "ENET1G_4_MDI2N")
	)
	(segment
		(start 344.911426 -30.666436)
		(end 344.86723 -30.644338)
		(width 0.14732)
		(layer "B.Cu")
		(net "ENET1G_4_MDI2N")
	)
	(segment
		(start 346.1004 -30.328108)
		(end 345.669108 -30.7594)
		(width 0.14732)
		(layer "B.Cu")
		(net "ENET1G_4_MDI2N")
	)
	(segment
		(start 343.474294 -24.805894)
		(end 343.786714 -25.118314)
		(width 0.14732)
		(layer "B.Cu")
		(net "ENET1G_4_MDI2N")
	)
	(segment
		(start 346.1004 -27.202892)
		(end 346.1004 -30.328108)
		(width 0.14732)
		(layer "B.Cu")
		(net "ENET1G_4_MDI2N")
	)
	(segment
		(start 344.640662 -25.972262)
		(end 344.86977 -25.972262)
		(width 0.14732)
		(layer "B.Cu")
		(net "ENET1G_4_MDI2N")
	)
	(segment
		(start 344.86977 -25.972262)
		(end 345.18219 -26.284682)
		(width 0.14732)
		(layer "B.Cu")
		(net "ENET1G_4_MDI2N")
	)
	(segment
		(start 341.530178 -7.252208)
		(end 341.63 -7.152386)
		(width 0.14732)
		(layer "B.Cu")
		(net "ENET1G_4_MDI2N")
	)
	(segment
		(start 342.488266 -23.590758)
		(end 343.474294 -24.576786)
		(width 0.14732)
		(layer "B.Cu")
		(net "ENET1G_4_MDI2N")
	)
	(segment
		(start 345.49461 -26.82621)
		(end 345.723718 -26.82621)
		(width 0.14732)
		(layer "B.Cu")
		(net "ENET1G_4_MDI2N")
	)
	(segment
		(start 345.18219 -26.51379)
		(end 345.49461 -26.82621)
		(width 0.14732)
		(layer "B.Cu")
		(net "ENET1G_4_MDI2N")
	)
	(segment
		(start 344.669364 -30.38094)
		(end 345.170252 -29.379164)
		(width 0.14732)
		(layer "B.Cu")
		(net "ENET1G_4_MDI2N")
	)
	(segment
		(start 345.00439 -30.7594)
		(end 344.911426 -30.666436)
		(width 0.14732)
		(layer "B.Cu")
		(net "ENET1G_4_MDI2N")
	)
	(segment
		(start 344.015822 -25.118314)
		(end 344.328242 -25.430734)
		(width 0.14732)
		(layer "B.Cu")
		(net "ENET1G_4_MDI2N")
	)
	(segment
		(start 341.530178 -7.70001)
		(end 341.530178 -7.252208)
		(width 0.14732)
		(layer "B.Cu")
		(net "ENET1G_4_MDI2N")
	)
	(segment
		(start 345.723718 -26.82621)
		(end 346.1004 -27.202892)
		(width 0.14732)
		(layer "B.Cu")
		(net "ENET1G_4_MDI2N")
	)
	(segment
		(start 344.86723 -30.644338)
		(end 344.735404 -30.578552)
		(width 0.14732)
		(layer "B.Cu")
		(net "ENET1G_4_MDI2N")
	)
	(segment
		(start 344.328242 -25.659842)
		(end 344.640662 -25.972262)
		(width 0.14732)
		(layer "B.Cu")
		(net "ENET1G_4_MDI2N")
	)
	(segment
		(start 341.63 -7.152386)
		(end 342.225122 -7.152386)
		(width 0.14732)
		(layer "B.Cu")
		(net "ENET1G_4_MDI2N")
	)
	(segment
		(start 343.474294 -24.576786)
		(end 343.474294 -24.805894)
		(width 0.14732)
		(layer "B.Cu")
		(net "ENET1G_4_MDI2N")
	)
	(segment
		(start 345.669108 -30.7594)
		(end 345.00439 -30.7594)
		(width 0.14732)
		(layer "B.Cu")
		(net "ENET1G_4_MDI2N")
	)
	(segment
		(start 343.786714 -25.118314)
		(end 344.015822 -25.118314)
		(width 0.14732)
		(layer "B.Cu")
		(net "ENET1G_4_MDI2N")
	)
	(segment
		(start 344.328242 -25.430734)
		(end 344.328242 -25.659842)
		(width 0.14732)
		(layer "B.Cu")
		(net "ENET1G_4_MDI2N")
	)
	(segment
		(start 397.109442 -24.261064)
		(end 397.540226 -23.83028)
		(width 0.1778)
		(layer "F.Cu")
		(net "SAS_BLAD2_TX5_N")
	)
	(segment
		(start 396.884906 -24.808688)
		(end 397.109442 -24.584152)
		(width 0.1778)
		(layer "F.Cu")
		(net "SAS_BLAD2_TX5_N")
	)
	(segment
		(start 398.787112 -23.83028)
		(end 399.223992 -23.3934)
		(width 0.1778)
		(layer "F.Cu")
		(net "SAS_BLAD2_TX5_N")
	)
	(segment
		(start 396.884906 -25.899872)
		(end 396.884906 -24.808688)
		(width 0.1778)
		(layer "F.Cu")
		(net "SAS_BLAD2_TX5_N")
	)
	(segment
		(start 397.109442 -24.584152)
		(end 397.109442 -24.261064)
		(width 0.1778)
		(layer "F.Cu")
		(net "SAS_BLAD2_TX5_N")
	)
	(segment
		(start 397.540226 -23.83028)
		(end 398.787112 -23.83028)
		(width 0.1778)
		(layer "F.Cu")
		(net "SAS_BLAD2_TX5_N")
	)
	(via
		(at 399.223992 -23.3934)
		(size 0.508)
		(drill 0.254)
		(layers "F.Cu" "B.Cu")
		(net "SAS_BLAD2_TX5_N")
	)
	(segment
		(start 399.683732 -23.85314)
		(end 399.989294 -23.85314)
		(width 0.1778)
		(layer "B.Cu")
		(net "SAS_BLAD2_TX5_N")
	)
	(segment
		(start 400.252946 -23.589488)
		(end 400.252946 -22.795992)
		(width 0.1778)
		(layer "B.Cu")
		(net "SAS_BLAD2_TX5_N")
	)
	(segment
		(start 390.797542 -14.292834)
		(end 390.72058 -13.976858)
		(width 0.1778)
		(layer "B.Cu")
		(net "SAS_BLAD2_TX5_N")
	)
	(segment
		(start 399.223992 -23.3934)
		(end 399.683732 -23.85314)
		(width 0.1778)
		(layer "B.Cu")
		(net "SAS_BLAD2_TX5_N")
	)
	(segment
		(start 389.89 -8.660892)
		(end 389.89 -8.999982)
		(width 0.1778)
		(layer "B.Cu")
		(net "SAS_BLAD2_TX5_N")
	)
	(segment
		(start 397.164814 -21.237956)
		(end 394.105892 -18.179034)
		(width 0.1778)
		(layer "B.Cu")
		(net "SAS_BLAD2_TX5_N")
	)
	(segment
		(start 390.522714 -8.475218)
		(end 390.075674 -8.475218)
		(width 0.1778)
		(layer "B.Cu")
		(net "SAS_BLAD2_TX5_N")
	)
	(segment
		(start 400.104102 -22.436836)
		(end 399.20291 -21.535644)
		(width 0.1778)
		(layer "B.Cu")
		(net "SAS_BLAD2_TX5_N")
	)
	(segment
		(start 393.498832 -17.927574)
		(end 391.34923 -15.778226)
		(width 0.1778)
		(layer "B.Cu")
		(net "SAS_BLAD2_TX5_N")
	)
	(segment
		(start 390.075674 -8.475218)
		(end 389.89 -8.660892)
		(width 0.1778)
		(layer "B.Cu")
		(net "SAS_BLAD2_TX5_N")
	)
	(segment
		(start 391.310876 -15.720822)
		(end 390.916922 -14.77264)
		(width 0.1778)
		(layer "B.Cu")
		(net "SAS_BLAD2_TX5_N")
	)
	(segment
		(start 400.100546 -23.806912)
		(end 400.206718 -23.70074)
		(width 0.1778)
		(layer "B.Cu")
		(net "SAS_BLAD2_TX5_N")
	)
	(segment
		(start 398.843754 -21.3868)
		(end 397.52397 -21.3868)
		(width 0.1778)
		(layer "B.Cu")
		(net "SAS_BLAD2_TX5_N")
	)
	(segment
		(start 390.710674 -13.8938)
		(end 390.710674 -8.662924)
		(width 0.1778)
		(layer "B.Cu")
		(net "SAS_BLAD2_TX5_N")
	)
	(segment
		(start 390.908286 -14.746478)
		(end 390.897364 -14.702536)
		(width 0.1778)
		(layer "B.Cu")
		(net "SAS_BLAD2_TX5_N")
	)
	(segment
		(start 390.897364 -14.702536)
		(end 390.797542 -14.292834)
		(width 0.1778)
		(layer "B.Cu")
		(net "SAS_BLAD2_TX5_N")
	)
	(segment
		(start 390.72058 -13.976858)
		(end 390.710674 -13.8938)
		(width 0.1778)
		(layer "B.Cu")
		(net "SAS_BLAD2_TX5_N")
	)
	(arc
		(start 400.252946 -22.795992)
		(mid 400.214262 -22.601603)
		(end 400.104102 -22.436836)
		(width 0.1778)
		(layer "B.Cu")
		(net "SAS_BLAD2_TX5_N")
	)
	(arc
		(start 400.206718 -23.70074)
		(mid 400.240931 -23.649726)
		(end 400.252946 -23.589488)
		(width 0.1778)
		(layer "B.Cu")
		(net "SAS_BLAD2_TX5_N")
	)
	(arc
		(start 390.710674 -8.662924)
		(mid 390.69642 -8.591175)
		(end 390.65581 -8.530336)
		(width 0.1778)
		(layer "B.Cu")
		(net "SAS_BLAD2_TX5_N")
	)
	(arc
		(start 390.65581 -8.530336)
		(mid 390.594745 -8.489534)
		(end 390.522714 -8.475218)
		(width 0.1778)
		(layer "B.Cu")
		(net "SAS_BLAD2_TX5_N")
	)
	(arc
		(start 399.989294 -23.85314)
		(mid 400.04953 -23.841122)
		(end 400.100546 -23.806912)
		(width 0.1778)
		(layer "B.Cu")
		(net "SAS_BLAD2_TX5_N")
	)
	(arc
		(start 394.050266 -18.15592)
		(mid 393.751843 -18.096578)
		(end 393.498832 -17.927574)
		(width 0.1778)
		(layer "B.Cu")
		(net "SAS_BLAD2_TX5_N")
	)
	(arc
		(start 390.916922 -14.77264)
		(mid 390.912103 -14.759725)
		(end 390.908286 -14.746478)
		(width 0.1778)
		(layer "B.Cu")
		(net "SAS_BLAD2_TX5_N")
	)
	(arc
		(start 397.52397 -21.3868)
		(mid 397.329581 -21.348116)
		(end 397.164814 -21.237956)
		(width 0.1778)
		(layer "B.Cu")
		(net "SAS_BLAD2_TX5_N")
	)
	(arc
		(start 399.20291 -21.535644)
		(mid 399.038142 -21.425486)
		(end 398.843754 -21.3868)
		(width 0.1778)
		(layer "B.Cu")
		(net "SAS_BLAD2_TX5_N")
	)
	(arc
		(start 394.105892 -18.179034)
		(mid 394.080385 -18.161927)
		(end 394.050266 -18.15592)
		(width 0.1778)
		(layer "B.Cu")
		(net "SAS_BLAD2_TX5_N")
	)
	(arc
		(start 391.34923 -15.778226)
		(mid 391.327244 -15.751402)
		(end 391.310876 -15.720822)
		(width 0.1778)
		(layer "B.Cu")
		(net "SAS_BLAD2_TX5_N")
	)
	(segment
		(start 349.530162 -2.100072)
		(end 350.026986 -2.596896)
		(width 0.1524)
		(layer "In5.Cu")
		(net "ENET1G_3_MDI0P")
	)
	(segment
		(start 351.222564 -2.596896)
		(end 352.241866 -3.616198)
		(width 0.1524)
		(layer "In5.Cu")
		(net "ENET1G_3_MDI0P")
	)
	(segment
		(start 350.026986 -2.596896)
		(end 351.222564 -2.596896)
		(width 0.1524)
		(layer "In5.Cu")
		(net "ENET1G_3_MDI0P")
	)
	(segment
		(start 348.572328 -37.362384)
		(end 348.504002 -37.566854)
		(width 0.1524)
		(layer "In5.Cu")
		(net "ENET1G_3_MDI0P")
	)
	(segment
		(start 348.504002 -37.566854)
		(end 348.980252 -38.5191)
		(width 0.1524)
		(layer "In5.Cu")
		(net "ENET1G_3_MDI0P")
	)
	(segment
		(start 352.241866 -3.616198)
		(end 352.241866 -20.2946)
		(width 0.1524)
		(layer "In5.Cu")
		(net "ENET1G_3_MDI0P")
	)
	(segment
		(start 352.241866 -20.2946)
		(end 350.336866 -22.1996)
		(width 0.1524)
		(layer "In5.Cu")
		(net "ENET1G_3_MDI0P")
	)
	(segment
		(start 350.336866 -22.1996)
		(end 350.336866 -35.666172)
		(width 0.1524)
		(layer "In5.Cu")
		(net "ENET1G_3_MDI0P")
	)
	(segment
		(start 350.336866 -35.666172)
		(end 348.708726 -37.294312)
		(width 0.1524)
		(layer "In5.Cu")
		(net "ENET1G_3_MDI0P")
	)
	(segment
		(start 348.708726 -37.294312)
		(end 348.572328 -37.362384)
		(width 0.1524)
		(layer "In5.Cu")
		(net "ENET1G_3_MDI0P")
	)
	(segment
		(start 416.675062 -24.20112)
		(end 418.192712 -24.20112)
		(width 0.1778)
		(layer "F.Cu")
		(net "SAS_BLAD2_TX1_P")
	)
	(segment
		(start 418.192712 -24.20112)
		(end 418.662612 -24.67102)
		(width 0.1778)
		(layer "F.Cu")
		(net "SAS_BLAD2_TX1_P")
	)
	(segment
		(start 416.46983 -24.584152)
		(end 416.46983 -24.406352)
		(width 0.1778)
		(layer "F.Cu")
		(net "SAS_BLAD2_TX1_P")
	)
	(segment
		(start 416.694874 -25.899872)
		(end 416.694874 -24.809196)
		(width 0.1778)
		(layer "F.Cu")
		(net "SAS_BLAD2_TX1_P")
	)
	(segment
		(start 416.694874 -24.809196)
		(end 416.46983 -24.584152)
		(width 0.1778)
		(layer "F.Cu")
		(net "SAS_BLAD2_TX1_P")
	)
	(segment
		(start 416.46983 -24.406352)
		(end 416.675062 -24.20112)
		(width 0.1778)
		(layer "F.Cu")
		(net "SAS_BLAD2_TX1_P")
	)
	(via
		(at 418.662612 -24.67102)
		(size 0.508)
		(drill 0.254)
		(layers "F.Cu" "B.Cu")
		(net "SAS_BLAD2_TX1_P")
	)
	(segment
		(start 408.30754 -7.196074)
		(end 408.069288 -7.196074)
		(width 0.1524)
		(layer "In5.Cu")
		(net "SAS_BLAD2_TX1_P")
	)
	(segment
		(start 409.191968 -8.080502)
		(end 408.953716 -8.080502)
		(width 0.1524)
		(layer "In5.Cu")
		(net "SAS_BLAD2_TX1_P")
	)
	(segment
		(start 420.097458 -22.746716)
		(end 419.52799 -21.37283)
		(width 0.1524)
		(layer "In5.Cu")
		(net "SAS_BLAD2_TX1_P")
	)
	(segment
		(start 419.480746 -21.28393)
		(end 414.113472 -13.253212)
		(width 0.1524)
		(layer "In5.Cu")
		(net "SAS_BLAD2_TX1_P")
	)
	(segment
		(start 420.136066 -23.516336)
		(end 420.136066 -22.94128)
		(width 0.1524)
		(layer "In5.Cu")
		(net "SAS_BLAD2_TX1_P")
	)
	(segment
		(start 408.630628 -7.519162)
		(end 408.30754 -7.196074)
		(width 0.1524)
		(layer "In5.Cu")
		(net "SAS_BLAD2_TX1_P")
	)
	(segment
		(start 412.72968 -11.618214)
		(end 412.491428 -11.618214)
		(width 0.1524)
		(layer "In5.Cu")
		(net "SAS_BLAD2_TX1_P")
	)
	(segment
		(start 410.076396 -8.96493)
		(end 409.838144 -8.96493)
		(width 0.1524)
		(layer "In5.Cu")
		(net "SAS_BLAD2_TX1_P")
	)
	(segment
		(start 411.283912 -10.410698)
		(end 411.283912 -10.172446)
		(width 0.1524)
		(layer "In5.Cu")
		(net "SAS_BLAD2_TX1_P")
	)
	(segment
		(start 410.722572 -9.849358)
		(end 410.399484 -9.52627)
		(width 0.1524)
		(layer "In5.Cu")
		(net "SAS_BLAD2_TX1_P")
	)
	(segment
		(start 412.16834 -11.056874)
		(end 411.845252 -10.733786)
		(width 0.1524)
		(layer "In5.Cu")
		(net "SAS_BLAD2_TX1_P")
	)
	(segment
		(start 412.491428 -11.618214)
		(end 412.16834 -11.295126)
		(width 0.1524)
		(layer "In5.Cu")
		(net "SAS_BLAD2_TX1_P")
	)
	(segment
		(start 413.052768 -11.941302)
		(end 412.72968 -11.618214)
		(width 0.1524)
		(layer "In5.Cu")
		(net "SAS_BLAD2_TX1_P")
	)
	(segment
		(start 414.113472 -13.253212)
		(end 414.085532 -13.212318)
		(width 0.1524)
		(layer "In5.Cu")
		(net "SAS_BLAD2_TX1_P")
	)
	(segment
		(start 418.662612 -24.67102)
		(end 419.094412 -24.23922)
		(width 0.1524)
		(layer "In5.Cu")
		(net "SAS_BLAD2_TX1_P")
	)
	(segment
		(start 419.481254 -21.284946)
		(end 419.480746 -21.284184)
		(width 0.1524)
		(layer "In5.Cu")
		(net "SAS_BLAD2_TX1_P")
	)
	(segment
		(start 412.16834 -11.295126)
		(end 412.16834 -11.056874)
		(width 0.1524)
		(layer "In5.Cu")
		(net "SAS_BLAD2_TX1_P")
	)
	(segment
		(start 419.480746 -21.284184)
		(end 419.480746 -21.28393)
		(width 0.1524)
		(layer "In5.Cu")
		(net "SAS_BLAD2_TX1_P")
	)
	(segment
		(start 409.515056 -8.40359)
		(end 409.191968 -8.080502)
		(width 0.1524)
		(layer "In5.Cu")
		(net "SAS_BLAD2_TX1_P")
	)
	(segment
		(start 398.815814 -2.5908)
		(end 396.380716 -2.5908)
		(width 0.1524)
		(layer "In5.Cu")
		(net "SAS_BLAD2_TX1_P")
	)
	(segment
		(start 406.515824 -5.718048)
		(end 399.167096 -2.66065)
		(width 0.1524)
		(layer "In5.Cu")
		(net "SAS_BLAD2_TX1_P")
	)
	(segment
		(start 410.399484 -9.52627)
		(end 410.399484 -9.288018)
		(width 0.1524)
		(layer "In5.Cu")
		(net "SAS_BLAD2_TX1_P")
	)
	(segment
		(start 410.960824 -9.849358)
		(end 410.722572 -9.849358)
		(width 0.1524)
		(layer "In5.Cu")
		(net "SAS_BLAD2_TX1_P")
	)
	(segment
		(start 410.399484 -9.288018)
		(end 410.076396 -8.96493)
		(width 0.1524)
		(layer "In5.Cu")
		(net "SAS_BLAD2_TX1_P")
	)
	(segment
		(start 411.607 -10.733786)
		(end 411.283912 -10.410698)
		(width 0.1524)
		(layer "In5.Cu")
		(net "SAS_BLAD2_TX1_P")
	)
	(segment
		(start 413.052768 -12.179554)
		(end 413.052768 -11.941302)
		(width 0.1524)
		(layer "In5.Cu")
		(net "SAS_BLAD2_TX1_P")
	)
	(segment
		(start 411.845252 -10.733786)
		(end 411.607 -10.733786)
		(width 0.1524)
		(layer "In5.Cu")
		(net "SAS_BLAD2_TX1_P")
	)
	(segment
		(start 408.953716 -8.080502)
		(end 408.630628 -7.757414)
		(width 0.1524)
		(layer "In5.Cu")
		(net "SAS_BLAD2_TX1_P")
	)
	(segment
		(start 419.094412 -24.23922)
		(end 419.413182 -24.23922)
		(width 0.1524)
		(layer "In5.Cu")
		(net "SAS_BLAD2_TX1_P")
	)
	(segment
		(start 409.515056 -8.641842)
		(end 409.515056 -8.40359)
		(width 0.1524)
		(layer "In5.Cu")
		(net "SAS_BLAD2_TX1_P")
	)
	(segment
		(start 396.380716 -2.5908)
		(end 395.889988 -2.100072)
		(width 0.1524)
		(layer "In5.Cu")
		(net "SAS_BLAD2_TX1_P")
	)
	(segment
		(start 414.085532 -13.212318)
		(end 413.052768 -12.179554)
		(width 0.1524)
		(layer "In5.Cu")
		(net "SAS_BLAD2_TX1_P")
	)
	(segment
		(start 411.283912 -10.172446)
		(end 410.960824 -9.849358)
		(width 0.1524)
		(layer "In5.Cu")
		(net "SAS_BLAD2_TX1_P")
	)
	(segment
		(start 408.630628 -7.757414)
		(end 408.630628 -7.519162)
		(width 0.1524)
		(layer "In5.Cu")
		(net "SAS_BLAD2_TX1_P")
	)
	(segment
		(start 408.069288 -7.196074)
		(end 406.744932 -5.871718)
		(width 0.1524)
		(layer "In5.Cu")
		(net "SAS_BLAD2_TX1_P")
	)
	(segment
		(start 409.838144 -8.96493)
		(end 409.515056 -8.641842)
		(width 0.1524)
		(layer "In5.Cu")
		(net "SAS_BLAD2_TX1_P")
	)
	(arc
		(start 406.578562 -5.74802)
		(mid 406.547563 -5.732259)
		(end 406.515824 -5.718048)
		(width 0.1524)
		(layer "In5.Cu")
		(net "SAS_BLAD2_TX1_P")
	)
	(arc
		(start 420.136066 -22.94128)
		(mid 420.12634 -22.842098)
		(end 420.097458 -22.746716)
		(width 0.1524)
		(layer "In5.Cu")
		(net "SAS_BLAD2_TX1_P")
	)
	(arc
		(start 419.924484 -24.027638)
		(mid 420.081147 -23.793036)
		(end 420.136066 -23.516336)
		(width 0.1524)
		(layer "In5.Cu")
		(net "SAS_BLAD2_TX1_P")
	)
	(arc
		(start 419.413182 -24.23922)
		(mid 419.689871 -24.184277)
		(end 419.924484 -24.027638)
		(width 0.1524)
		(layer "In5.Cu")
		(net "SAS_BLAD2_TX1_P")
	)
	(arc
		(start 406.744932 -5.871718)
		(mid 406.693615 -5.82516)
		(end 406.637998 -5.783834)
		(width 0.1524)
		(layer "In5.Cu")
		(net "SAS_BLAD2_TX1_P")
	)
	(arc
		(start 419.52799 -21.37283)
		(mid 419.506768 -21.327748)
		(end 419.481254 -21.284946)
		(width 0.1524)
		(layer "In5.Cu")
		(net "SAS_BLAD2_TX1_P")
	)
	(arc
		(start 406.637998 -5.783834)
		(mid 406.60872 -5.765197)
		(end 406.578562 -5.74802)
		(width 0.1524)
		(layer "In5.Cu")
		(net "SAS_BLAD2_TX1_P")
	)
	(arc
		(start 399.167096 -2.66065)
		(mid 398.994908 -2.608357)
		(end 398.815814 -2.5908)
		(width 0.1524)
		(layer "In5.Cu")
		(net "SAS_BLAD2_TX1_P")
	)
	(via
		(at 29.0322 -34.2646)
		(size 0.508)
		(drill 0.254)
		(layers "F.Cu" "B.Cu")
		(net "NODE3_RXD")
	)
	(segment
		(start 29.0322 -34.2646)
		(end 23.82774 -34.2646)
		(width 0.28956)
		(layer "B.Cu")
		(net "NODE3_RXD")
	)
	(segment
		(start 10.531348 -40.393112)
		(end 7.300214 -43.624246)
		(width 0.28956)
		(layer "B.Cu")
		(net "NODE3_RXD")
	)
	(segment
		(start 7.300214 -43.624246)
		(end 7.300214 -49.30013)
		(width 0.28956)
		(layer "B.Cu")
		(net "NODE3_RXD")
	)
	(segment
		(start 18.8087 -39.28364)
		(end 13.179552 -39.28364)
		(width 0.28956)
		(layer "B.Cu")
		(net "NODE3_RXD")
	)
	(segment
		(start 12.07008 -40.393112)
		(end 10.531348 -40.393112)
		(width 0.28956)
		(layer "B.Cu")
		(net "NODE3_RXD")
	)
	(segment
		(start 13.179552 -39.28364)
		(end 12.07008 -40.393112)
		(width 0.28956)
		(layer "B.Cu")
		(net "NODE3_RXD")
	)
	(segment
		(start 23.82774 -34.2646)
		(end 18.8087 -39.28364)
		(width 0.28956)
		(layer "B.Cu")
		(net "NODE3_RXD")
	)
	(segment
		(start 30.1752 -33.1216)
		(end 81.209388 -33.1216)
		(width 0.18288)
		(layer "In5.Cu")
		(net "NODE3_RXD")
	)
	(segment
		(start 344.799666 -32.258)
		(end 344.799666 -31.4706)
		(width 0.18288)
		(layer "In5.Cu")
		(net "NODE3_RXD")
	)
	(segment
		(start 343.694766 -30.3657)
		(end 343.694766 -28.161234)
		(width 0.18288)
		(layer "In5.Cu")
		(net "NODE3_RXD")
	)
	(segment
		(start 344.7034 -27.1526)
		(end 344.7034 -21.082)
		(width 0.18288)
		(layer "In5.Cu")
		(net "NODE3_RXD")
	)
	(segment
		(start 343.402666 -33.655)
		(end 344.799666 -32.258)
		(width 0.18288)
		(layer "In5.Cu")
		(net "NODE3_RXD")
	)
	(segment
		(start 86.822788 -38.735)
		(end 110.600236 -38.735)
		(width 0.18288)
		(layer "In5.Cu")
		(net "NODE3_RXD")
	)
	(segment
		(start 110.600236 -38.735)
		(end 113.789968 -41.924732)
		(width 0.18288)
		(layer "In5.Cu")
		(net "NODE3_RXD")
	)
	(segment
		(start 344.799666 -31.4706)
		(end 343.694766 -30.3657)
		(width 0.18288)
		(layer "In5.Cu")
		(net "NODE3_RXD")
	)
	(segment
		(start 339.315806 -33.655)
		(end 343.402666 -33.655)
		(width 0.18288)
		(layer "In5.Cu")
		(net "NODE3_RXD")
	)
	(segment
		(start 321.816984 -31.496)
		(end 337.156806 -31.496)
		(width 0.18288)
		(layer "In5.Cu")
		(net "NODE3_RXD")
	)
	(segment
		(start 29.0322 -34.2646)
		(end 30.1752 -33.1216)
		(width 0.18288)
		(layer "In5.Cu")
		(net "NODE3_RXD")
	)
	(segment
		(start 206.189834 -35.44316)
		(end 317.869824 -35.44316)
		(width 0.18288)
		(layer "In5.Cu")
		(net "NODE3_RXD")
	)
	(segment
		(start 337.156806 -31.496)
		(end 339.315806 -33.655)
		(width 0.18288)
		(layer "In5.Cu")
		(net "NODE3_RXD")
	)
	(segment
		(start 202.964034 -38.66896)
		(end 206.189834 -35.44316)
		(width 0.18288)
		(layer "In5.Cu")
		(net "NODE3_RXD")
	)
	(segment
		(start 131.404868 -41.924732)
		(end 134.66064 -38.66896)
		(width 0.18288)
		(layer "In5.Cu")
		(net "NODE3_RXD")
	)
	(segment
		(start 346.329 -19.4564)
		(end 346.329 -11.298936)
		(width 0.18288)
		(layer "In5.Cu")
		(net "NODE3_RXD")
	)
	(segment
		(start 113.789968 -41.924732)
		(end 131.404868 -41.924732)
		(width 0.18288)
		(layer "In5.Cu")
		(net "NODE3_RXD")
	)
	(segment
		(start 346.329 -11.298936)
		(end 345.53017 -10.500106)
		(width 0.18288)
		(layer "In5.Cu")
		(net "NODE3_RXD")
	)
	(segment
		(start 134.66064 -38.66896)
		(end 202.964034 -38.66896)
		(width 0.18288)
		(layer "In5.Cu")
		(net "NODE3_RXD")
	)
	(segment
		(start 81.209388 -33.1216)
		(end 86.822788 -38.735)
		(width 0.18288)
		(layer "In5.Cu")
		(net "NODE3_RXD")
	)
	(segment
		(start 343.694766 -28.161234)
		(end 344.7034 -27.1526)
		(width 0.18288)
		(layer "In5.Cu")
		(net "NODE3_RXD")
	)
	(segment
		(start 344.7034 -21.082)
		(end 346.329 -19.4564)
		(width 0.18288)
		(layer "In5.Cu")
		(net "NODE3_RXD")
	)
	(segment
		(start 317.869824 -35.44316)
		(end 321.816984 -31.496)
		(width 0.18288)
		(layer "In5.Cu")
		(net "NODE3_RXD")
	)
	(segment
		(start 344.647266 -17.190466)
		(end 344.647266 -12.783058)
		(width 0.28956)
		(layer "F.Cu")
		(net "NODE3_TXD")
	)
	(segment
		(start 344.9828 -17.526)
		(end 344.647266 -17.190466)
		(width 0.28956)
		(layer "F.Cu")
		(net "NODE3_TXD")
	)
	(segment
		(start 344.647266 -12.783058)
		(end 345.53017 -11.900154)
		(width 0.28956)
		(layer "F.Cu")
		(net "NODE3_TXD")
	)
	(via
		(at 27.6606 -34.8742)
		(size 0.508)
		(drill 0.254)
		(layers "F.Cu" "B.Cu")
		(net "NODE3_TXD")
	)
	(via
		(at 344.9828 -17.526)
		(size 0.508)
		(drill 0.254)
		(layers "F.Cu" "B.Cu")
		(net "NODE3_TXD")
	)
	(segment
		(start 24.059134 -34.8742)
		(end 19.055334 -39.878)
		(width 0.28956)
		(layer "B.Cu")
		(net "NODE3_TXD")
	)
	(segment
		(start 19.055334 -39.878)
		(end 13.425932 -39.878)
		(width 0.28956)
		(layer "B.Cu")
		(net "NODE3_TXD")
	)
	(segment
		(start 10.777728 -40.987472)
		(end 8.570214 -43.194986)
		(width 0.28956)
		(layer "B.Cu")
		(net "NODE3_TXD")
	)
	(segment
		(start 27.6606 -34.8742)
		(end 24.059134 -34.8742)
		(width 0.28956)
		(layer "B.Cu")
		(net "NODE3_TXD")
	)
	(segment
		(start 8.570214 -43.194986)
		(end 8.570214 -49.30013)
		(width 0.28956)
		(layer "B.Cu")
		(net "NODE3_TXD")
	)
	(segment
		(start 13.425932 -39.878)
		(end 12.31646 -40.987472)
		(width 0.28956)
		(layer "B.Cu")
		(net "NODE3_TXD")
	)
	(segment
		(start 12.31646 -40.987472)
		(end 10.777728 -40.987472)
		(width 0.28956)
		(layer "B.Cu")
		(net "NODE3_TXD")
	)
	(segment
		(start 339.504274 -33.153604)
		(end 341.871808 -33.153604)
		(width 0.18288)
		(layer "In5.Cu")
		(net "NODE3_TXD")
	)
	(segment
		(start 342.742266 -30.8102)
		(end 341.726266 -29.7942)
		(width 0.18288)
		(layer "In5.Cu")
		(net "NODE3_TXD")
	)
	(segment
		(start 345.821 -19.1516)
		(end 345.821 -18.3642)
		(width 0.18288)
		(layer "In5.Cu")
		(net "NODE3_TXD")
	)
	(segment
		(start 81.391252 -32.6136)
		(end 87.004652 -38.227)
		(width 0.18288)
		(layer "In5.Cu")
		(net "NODE3_TXD")
	)
	(segment
		(start 131.028948 -41.437052)
		(end 134.28472 -38.18128)
		(width 0.18288)
		(layer "In5.Cu")
		(net "NODE3_TXD")
	)
	(segment
		(start 317.66764 -34.95548)
		(end 321.6148 -31.00832)
		(width 0.18288)
		(layer "In5.Cu")
		(net "NODE3_TXD")
	)
	(segment
		(start 341.871808 -33.153604)
		(end 342.742266 -32.283146)
		(width 0.18288)
		(layer "In5.Cu")
		(net "NODE3_TXD")
	)
	(segment
		(start 341.726266 -28.2956)
		(end 344.205306 -25.81656)
		(width 0.18288)
		(layer "In5.Cu")
		(net "NODE3_TXD")
	)
	(segment
		(start 29.9212 -32.6136)
		(end 81.391252 -32.6136)
		(width 0.18288)
		(layer "In5.Cu")
		(net "NODE3_TXD")
	)
	(segment
		(start 205.958948 -34.95548)
		(end 317.66764 -34.95548)
		(width 0.18288)
		(layer "In5.Cu")
		(net "NODE3_TXD")
	)
	(segment
		(start 87.004652 -38.227)
		(end 110.782354 -38.227)
		(width 0.18288)
		(layer "In5.Cu")
		(net "NODE3_TXD")
	)
	(segment
		(start 113.992406 -41.437052)
		(end 131.028948 -41.437052)
		(width 0.18288)
		(layer "In5.Cu")
		(net "NODE3_TXD")
	)
	(segment
		(start 345.821 -18.3642)
		(end 344.9828 -17.526)
		(width 0.18288)
		(layer "In5.Cu")
		(net "NODE3_TXD")
	)
	(segment
		(start 202.733148 -38.18128)
		(end 205.958948 -34.95548)
		(width 0.18288)
		(layer "In5.Cu")
		(net "NODE3_TXD")
	)
	(segment
		(start 337.35899 -31.00832)
		(end 339.504274 -33.153604)
		(width 0.18288)
		(layer "In5.Cu")
		(net "NODE3_TXD")
	)
	(segment
		(start 134.28472 -38.18128)
		(end 202.733148 -38.18128)
		(width 0.18288)
		(layer "In5.Cu")
		(net "NODE3_TXD")
	)
	(segment
		(start 344.205306 -25.81656)
		(end 344.205306 -20.767294)
		(width 0.18288)
		(layer "In5.Cu")
		(net "NODE3_TXD")
	)
	(segment
		(start 110.782354 -38.227)
		(end 113.992406 -41.437052)
		(width 0.18288)
		(layer "In5.Cu")
		(net "NODE3_TXD")
	)
	(segment
		(start 344.205306 -20.767294)
		(end 345.821 -19.1516)
		(width 0.18288)
		(layer "In5.Cu")
		(net "NODE3_TXD")
	)
	(segment
		(start 342.742266 -32.283146)
		(end 342.742266 -30.8102)
		(width 0.18288)
		(layer "In5.Cu")
		(net "NODE3_TXD")
	)
	(segment
		(start 341.726266 -29.7942)
		(end 341.726266 -28.2956)
		(width 0.18288)
		(layer "In5.Cu")
		(net "NODE3_TXD")
	)
	(segment
		(start 321.6148 -31.00832)
		(end 337.35899 -31.00832)
		(width 0.18288)
		(layer "In5.Cu")
		(net "NODE3_TXD")
	)
	(segment
		(start 27.6606 -34.8742)
		(end 29.9212 -32.6136)
		(width 0.18288)
		(layer "In5.Cu")
		(net "NODE3_TXD")
	)
	(via
		(at 30.4292 -31.59506)
		(size 0.508)
		(drill 0.254)
		(layers "F.Cu" "B.Cu")
		(net "NODE4_RXD")
	)
	(segment
		(start 30.4292 -31.59506)
		(end 28.03906 -31.59506)
		(width 0.28956)
		(layer "B.Cu")
		(net "NODE4_RXD")
	)
	(segment
		(start 24.35606 -31.1658)
		(end 23.87346 -31.6484)
		(width 0.28956)
		(layer "B.Cu")
		(net "NODE4_RXD")
	)
	(segment
		(start 11.3792 -36.5252)
		(end 11.0236 -36.1696)
		(width 0.28956)
		(layer "B.Cu")
		(net "NODE4_RXD")
	)
	(segment
		(start 22.441662 -31.6484)
		(end 17.564862 -36.5252)
		(width 0.28956)
		(layer "B.Cu")
		(net "NODE4_RXD")
	)
	(segment
		(start 11.0236 -36.1696)
		(end 9.7282 -36.1696)
		(width 0.28956)
		(layer "B.Cu")
		(net "NODE4_RXD")
	)
	(segment
		(start 2.220214 -43.677586)
		(end 2.220214 -49.30013)
		(width 0.28956)
		(layer "B.Cu")
		(net "NODE4_RXD")
	)
	(segment
		(start 9.7282 -36.1696)
		(end 2.220214 -43.677586)
		(width 0.28956)
		(layer "B.Cu")
		(net "NODE4_RXD")
	)
	(segment
		(start 27.6098 -31.1658)
		(end 24.35606 -31.1658)
		(width 0.28956)
		(layer "B.Cu")
		(net "NODE4_RXD")
	)
	(segment
		(start 17.564862 -36.5252)
		(end 11.3792 -36.5252)
		(width 0.28956)
		(layer "B.Cu")
		(net "NODE4_RXD")
	)
	(segment
		(start 23.87346 -31.6484)
		(end 22.441662 -31.6484)
		(width 0.28956)
		(layer "B.Cu")
		(net "NODE4_RXD")
	)
	(segment
		(start 28.03906 -31.59506)
		(end 27.6098 -31.1658)
		(width 0.28956)
		(layer "B.Cu")
		(net "NODE4_RXD")
	)
	(segment
		(start 205.33106 -33.98012)
		(end 317.184024 -33.98012)
		(width 0.18288)
		(layer "In5.Cu")
		(net "NODE4_RXD")
	)
	(segment
		(start 321.131184 -30.03296)
		(end 332.83144 -30.03296)
		(width 0.18288)
		(layer "In5.Cu")
		(net "NODE4_RXD")
	)
	(segment
		(start 133.67766 -37.20592)
		(end 155.63088 -37.20592)
		(width 0.18288)
		(layer "In5.Cu")
		(net "NODE4_RXD")
	)
	(segment
		(start 116.713 -37.084)
		(end 119.87022 -40.24122)
		(width 0.18288)
		(layer "In5.Cu")
		(net "NODE4_RXD")
	)
	(segment
		(start 317.184024 -33.98012)
		(end 321.131184 -30.03296)
		(width 0.18288)
		(layer "In5.Cu")
		(net "NODE4_RXD")
	)
	(segment
		(start 342.259666 -13.6144)
		(end 342.259666 -11.670538)
		(width 0.18288)
		(layer "In5.Cu")
		(net "NODE4_RXD")
	)
	(segment
		(start 337.5406 -25.3238)
		(end 337.5406 -24.3586)
		(width 0.18288)
		(layer "In5.Cu")
		(net "NODE4_RXD")
	)
	(segment
		(start 342.259666 -11.670538)
		(end 343.530174 -10.40003)
		(width 0.18288)
		(layer "In5.Cu")
		(net "NODE4_RXD")
	)
	(segment
		(start 87.24138 -37.084)
		(end 116.713 -37.084)
		(width 0.18288)
		(layer "In5.Cu")
		(net "NODE4_RXD")
	)
	(segment
		(start 130.64236 -40.24122)
		(end 133.67766 -37.20592)
		(width 0.18288)
		(layer "In5.Cu")
		(net "NODE4_RXD")
	)
	(segment
		(start 159.258 -36.3474)
		(end 160.11652 -37.20592)
		(width 0.18288)
		(layer "In5.Cu")
		(net "NODE4_RXD")
	)
	(segment
		(start 30.4292 -31.59506)
		(end 81.75244 -31.59506)
		(width 0.18288)
		(layer "In5.Cu")
		(net "NODE4_RXD")
	)
	(segment
		(start 119.87022 -40.24122)
		(end 130.64236 -40.24122)
		(width 0.18288)
		(layer "In5.Cu")
		(net "NODE4_RXD")
	)
	(segment
		(start 160.11652 -37.20592)
		(end 202.10526 -37.20592)
		(width 0.18288)
		(layer "In5.Cu")
		(net "NODE4_RXD")
	)
	(segment
		(start 155.63088 -37.20592)
		(end 156.4894 -36.3474)
		(width 0.18288)
		(layer "In5.Cu")
		(net "NODE4_RXD")
	)
	(segment
		(start 339.7504 -22.1488)
		(end 339.7504 -16.123666)
		(width 0.18288)
		(layer "In5.Cu")
		(net "NODE4_RXD")
	)
	(segment
		(start 81.75244 -31.59506)
		(end 87.24138 -37.084)
		(width 0.18288)
		(layer "In5.Cu")
		(net "NODE4_RXD")
	)
	(segment
		(start 156.4894 -36.3474)
		(end 159.258 -36.3474)
		(width 0.18288)
		(layer "In5.Cu")
		(net "NODE4_RXD")
	)
	(segment
		(start 337.5406 -24.3586)
		(end 339.7504 -22.1488)
		(width 0.18288)
		(layer "In5.Cu")
		(net "NODE4_RXD")
	)
	(segment
		(start 339.7504 -16.123666)
		(end 342.259666 -13.6144)
		(width 0.18288)
		(layer "In5.Cu")
		(net "NODE4_RXD")
	)
	(segment
		(start 202.10526 -37.20592)
		(end 205.33106 -33.98012)
		(width 0.18288)
		(layer "In5.Cu")
		(net "NODE4_RXD")
	)
	(segment
		(start 332.83144 -30.03296)
		(end 337.5406 -25.3238)
		(width 0.18288)
		(layer "In5.Cu")
		(net "NODE4_RXD")
	)
	(segment
		(start 14.490192 -38.81374)
		(end 12.150852 -41.15308)
		(width 0.28956)
		(layer "F.Cu")
		(net "NODE1_TXD")
	)
	(segment
		(start 10.84072 -41.15308)
		(end 8.570214 -43.423586)
		(width 0.28956)
		(layer "F.Cu")
		(net "NODE1_TXD")
	)
	(segment
		(start 124.1552 -17.7038)
		(end 123.6472 -17.1958)
		(width 0.28956)
		(layer "F.Cu")
		(net "NODE1_TXD")
	)
	(segment
		(start 124.1552 -18.7198)
		(end 124.1552 -17.7038)
		(width 0.28956)
		(layer "F.Cu")
		(net "NODE1_TXD")
	)
	(segment
		(start 123.6472 -17.1958)
		(end 123.6472 -12.783058)
		(width 0.28956)
		(layer "F.Cu")
		(net "NODE1_TXD")
	)
	(segment
		(start 25.1714 -32.37738)
		(end 23.518114 -32.37738)
		(width 0.28956)
		(layer "F.Cu")
		(net "NODE1_TXD")
	)
	(segment
		(start 17.081754 -38.81374)
		(end 14.490192 -38.81374)
		(width 0.28956)
		(layer "F.Cu")
		(net "NODE1_TXD")
	)
	(segment
		(start 123.6472 -12.783058)
		(end 124.530104 -11.900154)
		(width 0.28956)
		(layer "F.Cu")
		(net "NODE1_TXD")
	)
	(segment
		(start 12.150852 -41.15308)
		(end 10.84072 -41.15308)
		(width 0.28956)
		(layer "F.Cu")
		(net "NODE1_TXD")
	)
	(segment
		(start 23.518114 -32.37738)
		(end 17.081754 -38.81374)
		(width 0.28956)
		(layer "F.Cu")
		(net "NODE1_TXD")
	)
	(segment
		(start 8.570214 -43.423586)
		(end 8.570214 -49.30013)
		(width 0.28956)
		(layer "F.Cu")
		(net "NODE1_TXD")
	)
	(via
		(at 25.1714 -32.37738)
		(size 0.508)
		(drill 0.254)
		(layers "F.Cu" "B.Cu")
		(net "NODE1_TXD")
	)
	(via
		(at 124.1552 -18.7198)
		(size 0.508)
		(drill 0.254)
		(layers "F.Cu" "B.Cu")
		(net "NODE1_TXD")
	)
	(segment
		(start 82.672428 -29.57322)
		(end 87.11311 -34.013902)
		(width 0.18288)
		(layer "In5.Cu")
		(net "NODE1_TXD")
	)
	(segment
		(start 116.4082 -30.9626)
		(end 119.0244 -33.5788)
		(width 0.18288)
		(layer "In5.Cu")
		(net "NODE1_TXD")
	)
	(segment
		(start 87.11311 -34.013902)
		(end 109.512862 -34.013902)
		(width 0.18288)
		(layer "In5.Cu")
		(net "NODE1_TXD")
	)
	(segment
		(start 121.7422 -32.2834)
		(end 121.7422 -30.8102)
		(width 0.18288)
		(layer "In5.Cu")
		(net "NODE1_TXD")
	)
	(segment
		(start 25.1714 -32.37738)
		(end 27.97556 -29.57322)
		(width 0.18288)
		(layer "In5.Cu")
		(net "NODE1_TXD")
	)
	(segment
		(start 27.97556 -29.57322)
		(end 82.672428 -29.57322)
		(width 0.18288)
		(layer "In5.Cu")
		(net "NODE1_TXD")
	)
	(segment
		(start 124.6886 -24.3332)
		(end 124.6886 -19.2532)
		(width 0.18288)
		(layer "In5.Cu")
		(net "NODE1_TXD")
	)
	(segment
		(start 120.7262 -29.7942)
		(end 120.7262 -28.2956)
		(width 0.18288)
		(layer "In5.Cu")
		(net "NODE1_TXD")
	)
	(segment
		(start 120.4468 -33.5788)
		(end 121.7422 -32.2834)
		(width 0.18288)
		(layer "In5.Cu")
		(net "NODE1_TXD")
	)
	(segment
		(start 124.6886 -19.2532)
		(end 124.1552 -18.7198)
		(width 0.18288)
		(layer "In5.Cu")
		(net "NODE1_TXD")
	)
	(segment
		(start 121.7422 -30.8102)
		(end 120.7262 -29.7942)
		(width 0.18288)
		(layer "In5.Cu")
		(net "NODE1_TXD")
	)
	(segment
		(start 120.7262 -28.2956)
		(end 124.6886 -24.3332)
		(width 0.18288)
		(layer "In5.Cu")
		(net "NODE1_TXD")
	)
	(segment
		(start 112.564164 -30.9626)
		(end 116.4082 -30.9626)
		(width 0.18288)
		(layer "In5.Cu")
		(net "NODE1_TXD")
	)
	(segment
		(start 109.512862 -34.013902)
		(end 112.564164 -30.9626)
		(width 0.18288)
		(layer "In5.Cu")
		(net "NODE1_TXD")
	)
	(segment
		(start 119.0244 -33.5788)
		(end 120.4468 -33.5788)
		(width 0.18288)
		(layer "In5.Cu")
		(net "NODE1_TXD")
	)
	(via
		(at 31.75 -32.1056)
		(size 0.508)
		(drill 0.254)
		(layers "F.Cu" "B.Cu")
		(net "NODE4_TXD")
	)
	(segment
		(start 26.1366 -31.7754)
		(end 26.7462 -32.385)
		(width 0.28956)
		(layer "B.Cu")
		(net "NODE4_TXD")
	)
	(segment
		(start 3.490214 -49.30013)
		(end 3.490214 -43.271186)
		(width 0.28956)
		(layer "B.Cu")
		(net "NODE4_TXD")
	)
	(segment
		(start 24.5872 -31.7754)
		(end 26.1366 -31.7754)
		(width 0.28956)
		(layer "B.Cu")
		(net "NODE4_TXD")
	)
	(segment
		(start 22.7076 -32.3342)
		(end 24.0284 -32.3342)
		(width 0.28956)
		(layer "B.Cu")
		(net "NODE4_TXD")
	)
	(segment
		(start 11.270234 -38.610032)
		(end 12.760706 -37.11956)
		(width 0.28956)
		(layer "B.Cu")
		(net "NODE4_TXD")
	)
	(segment
		(start 30.7594 -32.1056)
		(end 31.75 -32.1056)
		(width 0.28956)
		(layer "B.Cu")
		(net "NODE4_TXD")
	)
	(segment
		(start 8.151368 -38.610032)
		(end 11.270234 -38.610032)
		(width 0.28956)
		(layer "B.Cu")
		(net "NODE4_TXD")
	)
	(segment
		(start 3.490214 -43.271186)
		(end 8.151368 -38.610032)
		(width 0.28956)
		(layer "B.Cu")
		(net "NODE4_TXD")
	)
	(segment
		(start 12.760706 -37.11956)
		(end 17.92224 -37.11956)
		(width 0.28956)
		(layer "B.Cu")
		(net "NODE4_TXD")
	)
	(segment
		(start 17.92224 -37.11956)
		(end 22.7076 -32.3342)
		(width 0.28956)
		(layer "B.Cu")
		(net "NODE4_TXD")
	)
	(segment
		(start 27.559 -32.385)
		(end 27.7114 -32.2326)
		(width 0.28956)
		(layer "B.Cu")
		(net "NODE4_TXD")
	)
	(segment
		(start 27.7114 -32.2326)
		(end 30.6324 -32.2326)
		(width 0.28956)
		(layer "B.Cu")
		(net "NODE4_TXD")
	)
	(segment
		(start 30.6324 -32.2326)
		(end 30.7594 -32.1056)
		(width 0.28956)
		(layer "B.Cu")
		(net "NODE4_TXD")
	)
	(segment
		(start 26.7462 -32.385)
		(end 27.559 -32.385)
		(width 0.28956)
		(layer "B.Cu")
		(net "NODE4_TXD")
	)
	(segment
		(start 24.0284 -32.3342)
		(end 24.5872 -31.7754)
		(width 0.28956)
		(layer "B.Cu")
		(net "NODE4_TXD")
	)
	(segment
		(start 205.633828 -34.4678)
		(end 317.386462 -34.4678)
		(width 0.18288)
		(layer "In5.Cu")
		(net "NODE4_TXD")
	)
	(segment
		(start 87.110316 -37.6428)
		(end 110.888272 -37.6428)
		(width 0.18288)
		(layer "In5.Cu")
		(net "NODE4_TXD")
	)
	(segment
		(start 321.333622 -30.52064)
		(end 333.05496 -30.52064)
		(width 0.18288)
		(layer "In5.Cu")
		(net "NODE4_TXD")
	)
	(segment
		(start 133.980428 -37.6936)
		(end 155.8544 -37.6936)
		(width 0.18288)
		(layer "In5.Cu")
		(net "NODE4_TXD")
	)
	(segment
		(start 342.818466 -13.8684)
		(end 342.818466 -12.511786)
		(width 0.18288)
		(layer "In5.Cu")
		(net "NODE4_TXD")
	)
	(segment
		(start 338.0994 -25.4762)
		(end 338.0994 -24.511)
		(width 0.18288)
		(layer "In5.Cu")
		(net "NODE4_TXD")
	)
	(segment
		(start 110.888272 -37.6428)
		(end 114.194844 -40.949372)
		(width 0.18288)
		(layer "In5.Cu")
		(net "NODE4_TXD")
	)
	(segment
		(start 338.0994 -24.511)
		(end 340.2584 -22.352)
		(width 0.18288)
		(layer "In5.Cu")
		(net "NODE4_TXD")
	)
	(segment
		(start 317.386462 -34.4678)
		(end 321.333622 -30.52064)
		(width 0.18288)
		(layer "In5.Cu")
		(net "NODE4_TXD")
	)
	(segment
		(start 333.05496 -30.52064)
		(end 338.0994 -25.4762)
		(width 0.18288)
		(layer "In5.Cu")
		(net "NODE4_TXD")
	)
	(segment
		(start 159.0294 -36.8554)
		(end 159.8676 -37.6936)
		(width 0.18288)
		(layer "In5.Cu")
		(net "NODE4_TXD")
	)
	(segment
		(start 81.573116 -32.1056)
		(end 87.110316 -37.6428)
		(width 0.18288)
		(layer "In5.Cu")
		(net "NODE4_TXD")
	)
	(segment
		(start 156.6926 -36.8554)
		(end 159.0294 -36.8554)
		(width 0.18288)
		(layer "In5.Cu")
		(net "NODE4_TXD")
	)
	(segment
		(start 342.818466 -12.511786)
		(end 343.530174 -11.800078)
		(width 0.18288)
		(layer "In5.Cu")
		(net "NODE4_TXD")
	)
	(segment
		(start 31.75 -32.1056)
		(end 81.573116 -32.1056)
		(width 0.18288)
		(layer "In5.Cu")
		(net "NODE4_TXD")
	)
	(segment
		(start 114.194844 -40.949372)
		(end 130.724656 -40.949372)
		(width 0.18288)
		(layer "In5.Cu")
		(net "NODE4_TXD")
	)
	(segment
		(start 340.2584 -22.352)
		(end 340.2584 -16.428466)
		(width 0.18288)
		(layer "In5.Cu")
		(net "NODE4_TXD")
	)
	(segment
		(start 130.724656 -40.949372)
		(end 133.980428 -37.6936)
		(width 0.18288)
		(layer "In5.Cu")
		(net "NODE4_TXD")
	)
	(segment
		(start 340.2584 -16.428466)
		(end 342.818466 -13.8684)
		(width 0.18288)
		(layer "In5.Cu")
		(net "NODE4_TXD")
	)
	(segment
		(start 202.408028 -37.6936)
		(end 205.633828 -34.4678)
		(width 0.18288)
		(layer "In5.Cu")
		(net "NODE4_TXD")
	)
	(segment
		(start 155.8544 -37.6936)
		(end 156.6926 -36.8554)
		(width 0.18288)
		(layer "In5.Cu")
		(net "NODE4_TXD")
	)
	(segment
		(start 159.8676 -37.6936)
		(end 202.408028 -37.6936)
		(width 0.18288)
		(layer "In5.Cu")
		(net "NODE4_TXD")
	)
	(segment
		(start 168.509696 -29.72562)
		(end 168.509696 -30.27426)
		(width 0.1778)
		(layer "F.Cu")
		(net "SAS_BLAD1_RX8_N")
	)
	(segment
		(start 168.28516 -29.501084)
		(end 168.509696 -29.72562)
		(width 0.1778)
		(layer "F.Cu")
		(net "SAS_BLAD1_RX8_N")
	)
	(segment
		(start 168.28516 -28.4099)
		(end 168.28516 -29.501084)
		(width 0.1778)
		(layer "F.Cu")
		(net "SAS_BLAD1_RX8_N")
	)
	(segment
		(start 168.509696 -30.27426)
		(end 168.049956 -30.734)
		(width 0.1778)
		(layer "F.Cu")
		(net "SAS_BLAD1_RX8_N")
	)
	(via
		(at 168.049956 -30.734)
		(size 0.508)
		(drill 0.254)
		(layers "F.Cu" "B.Cu")
		(net "SAS_BLAD1_RX8_N")
	)
	(segment
		(start 163.31692 -23.863808)
		(end 163.31692 -23.141432)
		(width 0.1778)
		(layer "B.Cu")
		(net "SAS_BLAD1_RX8_N")
	)
	(segment
		(start 163.31692 -20.851114)
		(end 163.31692 -4.939792)
		(width 0.1778)
		(layer "B.Cu")
		(net "SAS_BLAD1_RX8_N")
	)
	(segment
		(start 168.463468 -31.624524)
		(end 168.45534 -31.632652)
		(width 0.1778)
		(layer "B.Cu")
		(net "SAS_BLAD1_RX8_N")
	)
	(segment
		(start 163.48964 -21.55698)
		(end 163.48964 -21.02358)
		(width 0.1778)
		(layer "B.Cu")
		(net "SAS_BLAD1_RX8_N")
	)
	(segment
		(start 168.344088 -31.67888)
		(end 167.753792 -31.67888)
		(width 0.1778)
		(layer "B.Cu")
		(net "SAS_BLAD1_RX8_N")
	)
	(segment
		(start 163.48964 -22.968966)
		(end 163.48964 -22.435566)
		(width 0.1778)
		(layer "B.Cu")
		(net "SAS_BLAD1_RX8_N")
	)
	(segment
		(start 167.394636 -31.530036)
		(end 166.386764 -30.522164)
		(width 0.1778)
		(layer "B.Cu")
		(net "SAS_BLAD1_RX8_N")
	)
	(segment
		(start 166.089076 -26.846276)
		(end 163.465764 -24.222964)
		(width 0.1778)
		(layer "B.Cu")
		(net "SAS_BLAD1_RX8_N")
	)
	(segment
		(start 168.049956 -30.734)
		(end 168.509696 -31.19374)
		(width 0.1778)
		(layer "B.Cu")
		(net "SAS_BLAD1_RX8_N")
	)
	(segment
		(start 163.31692 -22.2631)
		(end 163.31692 -21.7297)
		(width 0.1778)
		(layer "B.Cu")
		(net "SAS_BLAD1_RX8_N")
	)
	(segment
		(start 163.981384 -4.275328)
		(end 164.365178 -4.275328)
		(width 0.1778)
		(layer "B.Cu")
		(net "SAS_BLAD1_RX8_N")
	)
	(segment
		(start 163.465764 -4.580636)
		(end 163.622228 -4.424172)
		(width 0.1778)
		(layer "B.Cu")
		(net "SAS_BLAD1_RX8_N")
	)
	(segment
		(start 164.365178 -4.275328)
		(end 164.889942 -4.800092)
		(width 0.1778)
		(layer "B.Cu")
		(net "SAS_BLAD1_RX8_N")
	)
	(segment
		(start 163.48964 -21.02358)
		(end 163.31692 -20.851114)
		(width 0.1778)
		(layer "B.Cu")
		(net "SAS_BLAD1_RX8_N")
	)
	(segment
		(start 163.31692 -21.7297)
		(end 163.48964 -21.55698)
		(width 0.1778)
		(layer "B.Cu")
		(net "SAS_BLAD1_RX8_N")
	)
	(segment
		(start 168.509696 -31.19374)
		(end 168.509696 -31.513272)
		(width 0.1778)
		(layer "B.Cu")
		(net "SAS_BLAD1_RX8_N")
	)
	(segment
		(start 163.48964 -22.435566)
		(end 163.31692 -22.2631)
		(width 0.1778)
		(layer "B.Cu")
		(net "SAS_BLAD1_RX8_N")
	)
	(segment
		(start 166.23792 -30.163008)
		(end 166.23792 -27.205432)
		(width 0.1778)
		(layer "B.Cu")
		(net "SAS_BLAD1_RX8_N")
	)
	(segment
		(start 163.31692 -23.141432)
		(end 163.48964 -22.968966)
		(width 0.1778)
		(layer "B.Cu")
		(net "SAS_BLAD1_RX8_N")
	)
	(arc
		(start 166.386764 -30.522164)
		(mid 166.276606 -30.357396)
		(end 166.23792 -30.163008)
		(width 0.1778)
		(layer "B.Cu")
		(net "SAS_BLAD1_RX8_N")
	)
	(arc
		(start 163.622228 -4.424172)
		(mid 163.786996 -4.314014)
		(end 163.981384 -4.275328)
		(width 0.1778)
		(layer "B.Cu")
		(net "SAS_BLAD1_RX8_N")
	)
	(arc
		(start 163.31692 -4.939792)
		(mid 163.355604 -4.745403)
		(end 163.465764 -4.580636)
		(width 0.1778)
		(layer "B.Cu")
		(net "SAS_BLAD1_RX8_N")
	)
	(arc
		(start 168.509696 -31.513272)
		(mid 168.497678 -31.573508)
		(end 168.463468 -31.624524)
		(width 0.1778)
		(layer "B.Cu")
		(net "SAS_BLAD1_RX8_N")
	)
	(arc
		(start 168.45534 -31.632652)
		(mid 168.404326 -31.666865)
		(end 168.344088 -31.67888)
		(width 0.1778)
		(layer "B.Cu")
		(net "SAS_BLAD1_RX8_N")
	)
	(arc
		(start 163.465764 -24.222964)
		(mid 163.355606 -24.058196)
		(end 163.31692 -23.863808)
		(width 0.1778)
		(layer "B.Cu")
		(net "SAS_BLAD1_RX8_N")
	)
	(arc
		(start 166.23792 -27.205432)
		(mid 166.199236 -27.011043)
		(end 166.089076 -26.846276)
		(width 0.1778)
		(layer "B.Cu")
		(net "SAS_BLAD1_RX8_N")
	)
	(arc
		(start 167.753792 -31.67888)
		(mid 167.559403 -31.640196)
		(end 167.394636 -31.530036)
		(width 0.1778)
		(layer "B.Cu")
		(net "SAS_BLAD1_RX8_N")
	)
	(segment
		(start 15.97914 -35.7124)
		(end 10.4394 -35.7124)
		(width 0.28956)
		(layer "F.Cu")
		(net "NODE2_RXD")
	)
	(segment
		(start 22.30882 -29.38272)
		(end 15.97914 -35.7124)
		(width 0.28956)
		(layer "F.Cu")
		(net "NODE2_RXD")
	)
	(segment
		(start 26.05786 -29.38272)
		(end 22.30882 -29.38272)
		(width 0.28956)
		(layer "F.Cu")
		(net "NODE2_RXD")
	)
	(segment
		(start 10.4394 -35.7124)
		(end 2.220214 -43.931586)
		(width 0.28956)
		(layer "F.Cu")
		(net "NODE2_RXD")
	)
	(segment
		(start 2.220214 -43.931586)
		(end 2.220214 -49.30013)
		(width 0.28956)
		(layer "F.Cu")
		(net "NODE2_RXD")
	)
	(via
		(at 26.05786 -29.38272)
		(size 0.508)
		(drill 0.254)
		(layers "F.Cu" "B.Cu")
		(net "NODE2_RXD")
	)
	(segment
		(start 120.015 -22.131782)
		(end 120.015 -14.859)
		(width 0.18288)
		(layer "In5.Cu")
		(net "NODE2_RXD")
	)
	(segment
		(start 26.9494 -28.49118)
		(end 82.970116 -28.49118)
		(width 0.18288)
		(layer "In5.Cu")
		(net "NODE2_RXD")
	)
	(segment
		(start 109.10824 -33.038542)
		(end 120.015 -22.131782)
		(width 0.18288)
		(layer "In5.Cu")
		(net "NODE2_RXD")
	)
	(segment
		(start 87.517478 -33.038542)
		(end 109.10824 -33.038542)
		(width 0.18288)
		(layer "In5.Cu")
		(net "NODE2_RXD")
	)
	(segment
		(start 26.05786 -29.38272)
		(end 26.9494 -28.49118)
		(width 0.18288)
		(layer "In5.Cu")
		(net "NODE2_RXD")
	)
	(segment
		(start 121.2596 -11.670538)
		(end 122.530108 -10.40003)
		(width 0.18288)
		(layer "In5.Cu")
		(net "NODE2_RXD")
	)
	(segment
		(start 82.970116 -28.49118)
		(end 87.517478 -33.038542)
		(width 0.18288)
		(layer "In5.Cu")
		(net "NODE2_RXD")
	)
	(segment
		(start 120.015 -14.859)
		(end 121.2596 -13.6144)
		(width 0.18288)
		(layer "In5.Cu")
		(net "NODE2_RXD")
	)
	(segment
		(start 121.2596 -13.6144)
		(end 121.2596 -11.670538)
		(width 0.18288)
		(layer "In5.Cu")
		(net "NODE2_RXD")
	)
	(segment
		(start 184.22874 -29.30906)
		(end 184.68848 -29.7688)
		(width 0.1778)
		(layer "F.Cu")
		(net "SAS_BLAD1_RX4_P")
	)
	(segment
		(start 184.68848 -30.142688)
		(end 185.147712 -30.60192)
		(width 0.1778)
		(layer "F.Cu")
		(net "SAS_BLAD1_RX4_P")
	)
	(segment
		(start 187.444888 -30.60192)
		(end 187.895484 -30.151324)
		(width 0.1778)
		(layer "F.Cu")
		(net "SAS_BLAD1_RX4_P")
	)
	(segment
		(start 188.094874 -29.50083)
		(end 188.094874 -28.4099)
		(width 0.1778)
		(layer "F.Cu")
		(net "SAS_BLAD1_RX4_P")
	)
	(segment
		(start 187.895484 -29.70022)
		(end 188.094874 -29.50083)
		(width 0.1778)
		(layer "F.Cu")
		(net "SAS_BLAD1_RX4_P")
	)
	(segment
		(start 187.895484 -30.151324)
		(end 187.895484 -29.70022)
		(width 0.1778)
		(layer "F.Cu")
		(net "SAS_BLAD1_RX4_P")
	)
	(segment
		(start 185.147712 -30.60192)
		(end 187.444888 -30.60192)
		(width 0.1778)
		(layer "F.Cu")
		(net "SAS_BLAD1_RX4_P")
	)
	(segment
		(start 184.68848 -29.7688)
		(end 184.68848 -30.142688)
		(width 0.1778)
		(layer "F.Cu")
		(net "SAS_BLAD1_RX4_P")
	)
	(via
		(at 184.22874 -29.30906)
		(size 0.508)
		(drill 0.254)
		(layers "F.Cu" "B.Cu")
		(net "SAS_BLAD1_RX4_P")
	)
	(segment
		(start 170.331892 -6.796786)
		(end 170.757596 -6.796786)
		(width 0.1524)
		(layer "In5.Cu")
		(net "SAS_BLAD1_RX4_P")
	)
	(segment
		(start 170.757596 -6.796786)
		(end 170.88993 -6.664452)
		(width 0.1524)
		(layer "In5.Cu")
		(net "SAS_BLAD1_RX4_P")
	)
	(segment
		(start 170.88993 -6.664452)
		(end 170.88993 -6.299962)
		(width 0.1524)
		(layer "In5.Cu")
		(net "SAS_BLAD1_RX4_P")
	)
	(segment
		(start 170.289728 -15.23873)
		(end 169.829734 -14.12748)
		(width 0.1524)
		(layer "In5.Cu")
		(net "SAS_BLAD1_RX4_P")
	)
	(segment
		(start 169.829734 -14.12748)
		(end 169.690796 -13.292582)
		(width 0.1524)
		(layer "In5.Cu")
		(net "SAS_BLAD1_RX4_P")
	)
	(segment
		(start 183.358028 -27.97683)
		(end 182.360316 -26.979372)
		(width 0.1524)
		(layer "In5.Cu")
		(net "SAS_BLAD1_RX4_P")
	)
	(segment
		(start 173.70552 -17.78)
		(end 173.209712 -17.78)
		(width 0.1524)
		(layer "In5.Cu")
		(net "SAS_BLAD1_RX4_P")
	)
	(segment
		(start 174.325534 -18.028666)
		(end 173.744382 -17.787874)
		(width 0.1524)
		(layer "In5.Cu")
		(net "SAS_BLAD1_RX4_P")
	)
	(segment
		(start 169.690796 -13.292582)
		(end 169.690796 -7.403846)
		(width 0.1524)
		(layer "In5.Cu")
		(net "SAS_BLAD1_RX4_P")
	)
	(segment
		(start 172.563028 -17.51203)
		(end 170.289728 -15.23873)
		(width 0.1524)
		(layer "In5.Cu")
		(net "SAS_BLAD1_RX4_P")
	)
	(segment
		(start 175.422814 -18.758662)
		(end 174.34306 -18.038064)
		(width 0.1524)
		(layer "In5.Cu")
		(net "SAS_BLAD1_RX4_P")
	)
	(segment
		(start 181.943756 -25.276556)
		(end 175.438308 -18.771108)
		(width 0.1524)
		(layer "In5.Cu")
		(net "SAS_BLAD1_RX4_P")
	)
	(segment
		(start 184.396888 -28.2448)
		(end 184.004712 -28.2448)
		(width 0.1524)
		(layer "In5.Cu")
		(net "SAS_BLAD1_RX4_P")
	)
	(segment
		(start 184.22874 -29.30906)
		(end 184.66054 -28.87726)
		(width 0.1524)
		(layer "In5.Cu")
		(net "SAS_BLAD1_RX4_P")
	)
	(segment
		(start 169.855134 -7.008114)
		(end 169.878502 -6.984746)
		(width 0.1524)
		(layer "In5.Cu")
		(net "SAS_BLAD1_RX4_P")
	)
	(segment
		(start 184.630822 -28.436824)
		(end 184.468516 -28.274518)
		(width 0.1524)
		(layer "In5.Cu")
		(net "SAS_BLAD1_RX4_P")
	)
	(segment
		(start 184.66054 -28.87726)
		(end 184.66054 -28.508452)
		(width 0.1524)
		(layer "In5.Cu")
		(net "SAS_BLAD1_RX4_P")
	)
	(segment
		(start 182.0926 -26.332688)
		(end 182.0926 -25.635712)
		(width 0.1524)
		(layer "In5.Cu")
		(net "SAS_BLAD1_RX4_P")
	)
	(arc
		(start 169.690796 -7.403846)
		(mid 169.733519 -7.189602)
		(end 169.855134 -7.008114)
		(width 0.1524)
		(layer "In5.Cu")
		(net "SAS_BLAD1_RX4_P")
	)
	(arc
		(start 184.66054 -28.508452)
		(mid 184.65281 -28.469683)
		(end 184.630822 -28.436824)
		(width 0.1524)
		(layer "In5.Cu")
		(net "SAS_BLAD1_RX4_P")
	)
	(arc
		(start 182.0926 -25.635712)
		(mid 182.053916 -25.441323)
		(end 181.943756 -25.276556)
		(width 0.1524)
		(layer "In5.Cu")
		(net "SAS_BLAD1_RX4_P")
	)
	(arc
		(start 184.004712 -28.2448)
		(mid 183.654703 -28.175161)
		(end 183.358028 -27.97683)
		(width 0.1524)
		(layer "In5.Cu")
		(net "SAS_BLAD1_RX4_P")
	)
	(arc
		(start 184.468516 -28.274518)
		(mid 184.435667 -28.252506)
		(end 184.396888 -28.2448)
		(width 0.1524)
		(layer "In5.Cu")
		(net "SAS_BLAD1_RX4_P")
	)
	(arc
		(start 173.744382 -17.787874)
		(mid 173.72534 -17.782009)
		(end 173.70552 -17.78)
		(width 0.1524)
		(layer "In5.Cu")
		(net "SAS_BLAD1_RX4_P")
	)
	(arc
		(start 175.438308 -18.771108)
		(mid 175.430866 -18.764506)
		(end 175.422814 -18.758662)
		(width 0.1524)
		(layer "In5.Cu")
		(net "SAS_BLAD1_RX4_P")
	)
	(arc
		(start 173.209712 -17.78)
		(mid 172.859703 -17.710361)
		(end 172.563028 -17.51203)
		(width 0.1524)
		(layer "In5.Cu")
		(net "SAS_BLAD1_RX4_P")
	)
	(arc
		(start 174.34306 -18.038064)
		(mid 174.334524 -18.032943)
		(end 174.325534 -18.028666)
		(width 0.1524)
		(layer "In5.Cu")
		(net "SAS_BLAD1_RX4_P")
	)
	(arc
		(start 182.360316 -26.979372)
		(mid 182.162096 -26.68267)
		(end 182.0926 -26.332688)
		(width 0.1524)
		(layer "In5.Cu")
		(net "SAS_BLAD1_RX4_P")
	)
	(arc
		(start 169.878502 -6.984746)
		(mid 170.086491 -6.845646)
		(end 170.331892 -6.796786)
		(width 0.1524)
		(layer "In5.Cu")
		(net "SAS_BLAD1_RX4_P")
	)
	(segment
		(start 168.860216 -29.72562)
		(end 168.860216 -30.27426)
		(width 0.1778)
		(layer "F.Cu")
		(net "SAS_BLAD1_RX8_P")
	)
	(segment
		(start 168.860216 -30.27426)
		(end 169.319956 -30.734)
		(width 0.1778)
		(layer "F.Cu")
		(net "SAS_BLAD1_RX8_P")
	)
	(segment
		(start 169.085006 -29.50083)
		(end 168.860216 -29.72562)
		(width 0.1778)
		(layer "F.Cu")
		(net "SAS_BLAD1_RX8_P")
	)
	(segment
		(start 169.085006 -28.4099)
		(end 169.085006 -29.50083)
		(width 0.1778)
		(layer "F.Cu")
		(net "SAS_BLAD1_RX8_P")
	)
	(via
		(at 169.319956 -30.734)
		(size 0.508)
		(drill 0.254)
		(layers "F.Cu" "B.Cu")
		(net "SAS_BLAD1_RX8_P")
	)
	(segment
		(start 168.860216 -31.19374)
		(end 168.860216 -31.513272)
		(width 0.1778)
		(layer "B.Cu")
		(net "SAS_BLAD1_RX8_P")
	)
	(segment
		(start 165.841172 -27.09418)
		(end 163.21786 -24.470868)
		(width 0.1778)
		(layer "B.Cu")
		(net "SAS_BLAD1_RX8_P")
	)
	(segment
		(start 165.8874 -30.163008)
		(end 165.8874 -27.205432)
		(width 0.1778)
		(layer "B.Cu")
		(net "SAS_BLAD1_RX8_P")
	)
	(segment
		(start 168.711372 -31.872428)
		(end 168.703498 -31.880302)
		(width 0.1778)
		(layer "B.Cu")
		(net "SAS_BLAD1_RX8_P")
	)
	(segment
		(start 169.319956 -30.734)
		(end 168.860216 -31.19374)
		(width 0.1778)
		(layer "B.Cu")
		(net "SAS_BLAD1_RX8_P")
	)
	(segment
		(start 167.146732 -31.77794)
		(end 166.13886 -30.770068)
		(width 0.1778)
		(layer "B.Cu")
		(net "SAS_BLAD1_RX8_P")
	)
	(segment
		(start 162.9664 -23.863808)
		(end 162.9664 -4.939792)
		(width 0.1778)
		(layer "B.Cu")
		(net "SAS_BLAD1_RX8_P")
	)
	(segment
		(start 168.344088 -32.0294)
		(end 167.753792 -32.0294)
		(width 0.1778)
		(layer "B.Cu")
		(net "SAS_BLAD1_RX8_P")
	)
	(segment
		(start 164.365178 -3.924808)
		(end 164.889942 -3.400044)
		(width 0.1778)
		(layer "B.Cu")
		(net "SAS_BLAD1_RX8_P")
	)
	(segment
		(start 163.981384 -3.924808)
		(end 164.365178 -3.924808)
		(width 0.1778)
		(layer "B.Cu")
		(net "SAS_BLAD1_RX8_P")
	)
	(segment
		(start 163.21786 -4.332732)
		(end 163.374324 -4.176268)
		(width 0.1778)
		(layer "B.Cu")
		(net "SAS_BLAD1_RX8_P")
	)
	(arc
		(start 163.21786 -24.470868)
		(mid 163.031758 -24.192347)
		(end 162.9664 -23.863808)
		(width 0.1778)
		(layer "B.Cu")
		(net "SAS_BLAD1_RX8_P")
	)
	(arc
		(start 165.8874 -27.205432)
		(mid 165.875382 -27.145196)
		(end 165.841172 -27.09418)
		(width 0.1778)
		(layer "B.Cu")
		(net "SAS_BLAD1_RX8_P")
	)
	(arc
		(start 168.860216 -31.513272)
		(mid 168.821532 -31.707661)
		(end 168.711372 -31.872428)
		(width 0.1778)
		(layer "B.Cu")
		(net "SAS_BLAD1_RX8_P")
	)
	(arc
		(start 167.753792 -32.0294)
		(mid 167.425251 -31.964049)
		(end 167.146732 -31.77794)
		(width 0.1778)
		(layer "B.Cu")
		(net "SAS_BLAD1_RX8_P")
	)
	(arc
		(start 162.9664 -4.939792)
		(mid 163.031751 -4.611251)
		(end 163.21786 -4.332732)
		(width 0.1778)
		(layer "B.Cu")
		(net "SAS_BLAD1_RX8_P")
	)
	(arc
		(start 163.374324 -4.176268)
		(mid 163.652845 -3.990166)
		(end 163.981384 -3.924808)
		(width 0.1778)
		(layer "B.Cu")
		(net "SAS_BLAD1_RX8_P")
	)
	(arc
		(start 166.13886 -30.770068)
		(mid 165.952758 -30.491547)
		(end 165.8874 -30.163008)
		(width 0.1778)
		(layer "B.Cu")
		(net "SAS_BLAD1_RX8_P")
	)
	(arc
		(start 168.703498 -31.880302)
		(mid 168.538642 -31.990645)
		(end 168.344088 -32.0294)
		(width 0.1778)
		(layer "B.Cu")
		(net "SAS_BLAD1_RX8_P")
	)
	(segment
		(start 27.27706 -31.77794)
		(end 23.276814 -31.77794)
		(width 0.28956)
		(layer "F.Cu")
		(net "NODE1_RXD")
	)
	(segment
		(start 10.57148 -40.55872)
		(end 7.300214 -43.829986)
		(width 0.28956)
		(layer "F.Cu")
		(net "NODE1_RXD")
	)
	(segment
		(start 16.835374 -38.21938)
		(end 14.243812 -38.21938)
		(width 0.28956)
		(layer "F.Cu")
		(net "NODE1_RXD")
	)
	(segment
		(start 7.300214 -43.829986)
		(end 7.300214 -49.30013)
		(width 0.28956)
		(layer "F.Cu")
		(net "NODE1_RXD")
	)
	(segment
		(start 11.904472 -40.55872)
		(end 10.57148 -40.55872)
		(width 0.28956)
		(layer "F.Cu")
		(net "NODE1_RXD")
	)
	(segment
		(start 14.243812 -38.21938)
		(end 11.904472 -40.55872)
		(width 0.28956)
		(layer "F.Cu")
		(net "NODE1_RXD")
	)
	(segment
		(start 23.276814 -31.77794)
		(end 16.835374 -38.21938)
		(width 0.28956)
		(layer "F.Cu")
		(net "NODE1_RXD")
	)
	(via
		(at 27.27706 -31.77794)
		(size 0.508)
		(drill 0.254)
		(layers "F.Cu" "B.Cu")
		(net "NODE1_RXD")
	)
	(segment
		(start 122.6947 -30.1371)
		(end 122.6947 -27.22372)
		(width 0.18288)
		(layer "In5.Cu")
		(net "NODE1_RXD")
	)
	(segment
		(start 125.222 -24.69642)
		(end 125.222 -21.01342)
		(width 0.18288)
		(layer "In5.Cu")
		(net "NODE1_RXD")
	)
	(segment
		(start 109.715046 -34.501582)
		(end 112.720628 -31.496)
		(width 0.18288)
		(layer "In5.Cu")
		(net "NODE1_RXD")
	)
	(segment
		(start 121.9708 -34.0868)
		(end 123.8504 -32.2072)
		(width 0.18288)
		(layer "In5.Cu")
		(net "NODE1_RXD")
	)
	(segment
		(start 112.720628 -31.496)
		(end 116.205 -31.496)
		(width 0.18288)
		(layer "In5.Cu")
		(net "NODE1_RXD")
	)
	(segment
		(start 86.910926 -34.501582)
		(end 109.715046 -34.501582)
		(width 0.18288)
		(layer "In5.Cu")
		(net "NODE1_RXD")
	)
	(segment
		(start 125.2982 -11.268202)
		(end 124.530104 -10.500106)
		(width 0.18288)
		(layer "In5.Cu")
		(net "NODE1_RXD")
	)
	(segment
		(start 82.470244 -30.0609)
		(end 86.910926 -34.501582)
		(width 0.18288)
		(layer "In5.Cu")
		(net "NODE1_RXD")
	)
	(segment
		(start 122.6947 -27.22372)
		(end 125.222 -24.69642)
		(width 0.18288)
		(layer "In5.Cu")
		(net "NODE1_RXD")
	)
	(segment
		(start 27.27706 -31.77794)
		(end 28.9941 -30.0609)
		(width 0.18288)
		(layer "In5.Cu")
		(net "NODE1_RXD")
	)
	(segment
		(start 125.2982 -20.93722)
		(end 125.2982 -11.268202)
		(width 0.18288)
		(layer "In5.Cu")
		(net "NODE1_RXD")
	)
	(segment
		(start 28.9941 -30.0609)
		(end 82.470244 -30.0609)
		(width 0.18288)
		(layer "In5.Cu")
		(net "NODE1_RXD")
	)
	(segment
		(start 123.8504 -31.2928)
		(end 122.6947 -30.1371)
		(width 0.18288)
		(layer "In5.Cu")
		(net "NODE1_RXD")
	)
	(segment
		(start 123.8504 -32.2072)
		(end 123.8504 -31.2928)
		(width 0.18288)
		(layer "In5.Cu")
		(net "NODE1_RXD")
	)
	(segment
		(start 118.7958 -34.0868)
		(end 121.9708 -34.0868)
		(width 0.18288)
		(layer "In5.Cu")
		(net "NODE1_RXD")
	)
	(segment
		(start 125.222 -21.01342)
		(end 125.2982 -20.93722)
		(width 0.18288)
		(layer "In5.Cu")
		(net "NODE1_RXD")
	)
	(segment
		(start 116.205 -31.496)
		(end 118.7958 -34.0868)
		(width 0.18288)
		(layer "In5.Cu")
		(net "NODE1_RXD")
	)
	(segment
		(start 130.546602 -22.210268)
		(end 131.191 -22.210268)
		(width 0.28956)
		(layer "F.Cu")
		(net "ENET10G_1_LOS")
	)
	(segment
		(start 140.290296 -18.490184)
		(end 140.290296 -19.939)
		(width 0.28956)
		(layer "F.Cu")
		(net "ENET10G_1_LOS")
	)
	(segment
		(start 130.546602 -22.210268)
		(end 130.546602 -22.733)
		(width 0.28956)
		(layer "F.Cu")
		(net "ENET10G_1_LOS")
	)
	(segment
		(start 130.501898 -22.777704)
		(end 130.501898 -23.256494)
		(width 0.28956)
		(layer "F.Cu")
		(net "ENET10G_1_LOS")
	)
	(segment
		(start 130.546602 -22.733)
		(end 130.501898 -22.777704)
		(width 0.28956)
		(layer "F.Cu")
		(net "ENET10G_1_LOS")
	)
	(via
		(at 140.290296 -19.939)
		(size 0.508)
		(drill 0.254)
		(layers "F.Cu" "B.Cu")
		(net "ENET10G_1_LOS")
	)
	(via
		(at 131.191 -22.210268)
		(size 0.508)
		(drill 0.254)
		(layers "F.Cu" "B.Cu")
		(net "ENET10G_1_LOS")
	)
	(segment
		(start 139.960096 -19.6088)
		(end 140.290296 -19.939)
		(width 0.18288)
		(layer "In5.Cu")
		(net "ENET10G_1_LOS")
	)
	(segment
		(start 138.0236 -19.6088)
		(end 139.960096 -19.6088)
		(width 0.18288)
		(layer "In5.Cu")
		(net "ENET10G_1_LOS")
	)
	(segment
		(start 131.887468 -21.5138)
		(end 136.1186 -21.5138)
		(width 0.18288)
		(layer "In5.Cu")
		(net "ENET10G_1_LOS")
	)
	(segment
		(start 131.191 -22.210268)
		(end 131.887468 -21.5138)
		(width 0.18288)
		(layer "In5.Cu")
		(net "ENET10G_1_LOS")
	)
	(segment
		(start 136.1186 -21.5138)
		(end 138.0236 -19.6088)
		(width 0.18288)
		(layer "In5.Cu")
		(net "ENET10G_1_LOS")
	)
	(segment
		(start 187.2996 -30.2514)
		(end 187.544964 -30.006036)
		(width 0.1778)
		(layer "F.Cu")
		(net "SAS_BLAD1_RX4_N")
	)
	(segment
		(start 185.039 -29.7688)
		(end 185.039 -29.9974)
		(width 0.1778)
		(layer "F.Cu")
		(net "SAS_BLAD1_RX4_N")
	)
	(segment
		(start 187.295028 -29.501084)
		(end 187.295028 -28.4099)
		(width 0.1778)
		(layer "F.Cu")
		(net "SAS_BLAD1_RX4_N")
	)
	(segment
		(start 185.49874 -29.30906)
		(end 185.039 -29.7688)
		(width 0.1778)
		(layer "F.Cu")
		(net "SAS_BLAD1_RX4_N")
	)
	(segment
		(start 187.544964 -30.006036)
		(end 187.544964 -29.75102)
		(width 0.1778)
		(layer "F.Cu")
		(net "SAS_BLAD1_RX4_N")
	)
	(segment
		(start 185.293 -30.2514)
		(end 187.2996 -30.2514)
		(width 0.1778)
		(layer "F.Cu")
		(net "SAS_BLAD1_RX4_N")
	)
	(segment
		(start 187.544964 -29.75102)
		(end 187.295028 -29.501084)
		(width 0.1778)
		(layer "F.Cu")
		(net "SAS_BLAD1_RX4_N")
	)
	(segment
		(start 185.039 -29.9974)
		(end 185.293 -30.2514)
		(width 0.1778)
		(layer "F.Cu")
		(net "SAS_BLAD1_RX4_N")
	)
	(via
		(at 185.49874 -29.30906)
		(size 0.508)
		(drill 0.254)
		(layers "F.Cu" "B.Cu")
		(net "SAS_BLAD1_RX4_N")
	)
	(segment
		(start 174.568612 -17.699736)
		(end 175.648874 -18.420588)
		(width 0.1524)
		(layer "In5.Cu")
		(net "SAS_BLAD1_RX4_N")
	)
	(segment
		(start 178.676046 -21.434044)
		(end 178.999134 -21.757132)
		(width 0.1524)
		(layer "In5.Cu")
		(net "SAS_BLAD1_RX4_N")
	)
	(segment
		(start 179.560474 -22.318472)
		(end 182.23103 -24.989028)
		(width 0.1524)
		(layer "In5.Cu")
		(net "SAS_BLAD1_RX4_N")
	)
	(segment
		(start 178.352958 -20.872704)
		(end 178.676046 -21.195792)
		(width 0.1524)
		(layer "In5.Cu")
		(net "SAS_BLAD1_RX4_N")
	)
	(segment
		(start 179.560474 -22.08022)
		(end 179.560474 -22.318472)
		(width 0.1524)
		(layer "In5.Cu")
		(net "SAS_BLAD1_RX4_N")
	)
	(segment
		(start 170.735498 -7.203186)
		(end 170.331892 -7.203186)
		(width 0.1524)
		(layer "In5.Cu")
		(net "SAS_BLAD1_RX4_N")
	)
	(segment
		(start 179.237386 -21.757132)
		(end 179.560474 -22.08022)
		(width 0.1524)
		(layer "In5.Cu")
		(net "SAS_BLAD1_RX4_N")
	)
	(segment
		(start 173.209712 -17.3736)
		(end 173.70552 -17.3736)
		(width 0.1524)
		(layer "In5.Cu")
		(net "SAS_BLAD1_RX4_N")
	)
	(segment
		(start 178.676046 -21.195792)
		(end 178.676046 -21.434044)
		(width 0.1524)
		(layer "In5.Cu")
		(net "SAS_BLAD1_RX4_N")
	)
	(segment
		(start 182.647844 -26.691844)
		(end 183.645556 -27.689556)
		(width 0.1524)
		(layer "In5.Cu")
		(net "SAS_BLAD1_RX4_N")
	)
	(segment
		(start 170.16603 -7.27202)
		(end 170.142154 -7.295896)
		(width 0.1524)
		(layer "In5.Cu")
		(net "SAS_BLAD1_RX4_N")
	)
	(segment
		(start 185.06694 -28.87726)
		(end 185.49874 -29.30906)
		(width 0.1524)
		(layer "In5.Cu")
		(net "SAS_BLAD1_RX4_N")
	)
	(segment
		(start 170.634406 -15.008606)
		(end 172.850556 -17.224756)
		(width 0.1524)
		(layer "In5.Cu")
		(net "SAS_BLAD1_RX4_N")
	)
	(segment
		(start 175.72609 -18.484088)
		(end 178.114706 -20.872704)
		(width 0.1524)
		(layer "In5.Cu")
		(net "SAS_BLAD1_RX4_N")
	)
	(segment
		(start 182.499 -25.635712)
		(end 182.499 -26.332688)
		(width 0.1524)
		(layer "In5.Cu")
		(net "SAS_BLAD1_RX4_N")
	)
	(segment
		(start 178.114706 -20.872704)
		(end 178.352958 -20.872704)
		(width 0.1524)
		(layer "In5.Cu")
		(net "SAS_BLAD1_RX4_N")
	)
	(segment
		(start 173.89983 -17.412208)
		(end 174.480982 -17.653)
		(width 0.1524)
		(layer "In5.Cu")
		(net "SAS_BLAD1_RX4_N")
	)
	(segment
		(start 170.097196 -13.2588)
		(end 170.22318 -14.014958)
		(width 0.1524)
		(layer "In5.Cu")
		(net "SAS_BLAD1_RX4_N")
	)
	(segment
		(start 170.88993 -7.357618)
		(end 170.735498 -7.203186)
		(width 0.1524)
		(layer "In5.Cu")
		(net "SAS_BLAD1_RX4_N")
	)
	(segment
		(start 170.22318 -14.014958)
		(end 170.634406 -15.008606)
		(width 0.1524)
		(layer "In5.Cu")
		(net "SAS_BLAD1_RX4_N")
	)
	(segment
		(start 170.88993 -7.70001)
		(end 170.88993 -7.357618)
		(width 0.1524)
		(layer "In5.Cu")
		(net "SAS_BLAD1_RX4_N")
	)
	(segment
		(start 170.097196 -7.403846)
		(end 170.097196 -13.2588)
		(width 0.1524)
		(layer "In5.Cu")
		(net "SAS_BLAD1_RX4_N")
	)
	(segment
		(start 178.999134 -21.757132)
		(end 179.237386 -21.757132)
		(width 0.1524)
		(layer "In5.Cu")
		(net "SAS_BLAD1_RX4_N")
	)
	(segment
		(start 185.06694 -28.508452)
		(end 185.06694 -28.87726)
		(width 0.1524)
		(layer "In5.Cu")
		(net "SAS_BLAD1_RX4_N")
	)
	(segment
		(start 184.004712 -27.8384)
		(end 184.396888 -27.8384)
		(width 0.1524)
		(layer "In5.Cu")
		(net "SAS_BLAD1_RX4_N")
	)
	(segment
		(start 184.756044 -27.987244)
		(end 184.918096 -28.149296)
		(width 0.1524)
		(layer "In5.Cu")
		(net "SAS_BLAD1_RX4_N")
	)
	(arc
		(start 182.23103 -24.989028)
		(mid 182.429333 -25.285715)
		(end 182.499 -25.635712)
		(width 0.1524)
		(layer "In5.Cu")
		(net "SAS_BLAD1_RX4_N")
	)
	(arc
		(start 174.480982 -17.653)
		(mid 174.525942 -17.67422)
		(end 174.568612 -17.699736)
		(width 0.1524)
		(layer "In5.Cu")
		(net "SAS_BLAD1_RX4_N")
	)
	(arc
		(start 183.645556 -27.689556)
		(mid 183.810324 -27.799714)
		(end 184.004712 -27.8384)
		(width 0.1524)
		(layer "In5.Cu")
		(net "SAS_BLAD1_RX4_N")
	)
	(arc
		(start 184.918096 -28.149296)
		(mid 185.028254 -28.314064)
		(end 185.06694 -28.508452)
		(width 0.1524)
		(layer "In5.Cu")
		(net "SAS_BLAD1_RX4_N")
	)
	(arc
		(start 184.396888 -27.8384)
		(mid 184.591277 -27.877084)
		(end 184.756044 -27.987244)
		(width 0.1524)
		(layer "In5.Cu")
		(net "SAS_BLAD1_RX4_N")
	)
	(arc
		(start 182.499 -26.332688)
		(mid 182.537684 -26.527077)
		(end 182.647844 -26.691844)
		(width 0.1524)
		(layer "In5.Cu")
		(net "SAS_BLAD1_RX4_N")
	)
	(arc
		(start 170.142154 -7.295896)
		(mid 170.108899 -7.345381)
		(end 170.097196 -7.403846)
		(width 0.1524)
		(layer "In5.Cu")
		(net "SAS_BLAD1_RX4_N")
	)
	(arc
		(start 172.850556 -17.224756)
		(mid 173.015324 -17.334914)
		(end 173.209712 -17.3736)
		(width 0.1524)
		(layer "In5.Cu")
		(net "SAS_BLAD1_RX4_N")
	)
	(arc
		(start 170.331892 -7.203186)
		(mid 170.242106 -7.221081)
		(end 170.16603 -7.27202)
		(width 0.1524)
		(layer "In5.Cu")
		(net "SAS_BLAD1_RX4_N")
	)
	(arc
		(start 175.648874 -18.420588)
		(mid 175.689048 -18.450434)
		(end 175.72609 -18.484088)
		(width 0.1524)
		(layer "In5.Cu")
		(net "SAS_BLAD1_RX4_N")
	)
	(arc
		(start 173.70552 -17.3736)
		(mid 173.804574 -17.383346)
		(end 173.89983 -17.412208)
		(width 0.1524)
		(layer "In5.Cu")
		(net "SAS_BLAD1_RX4_N")
	)
	(segment
		(start 28.5242 -29.08554)
		(end 27.63266 -29.97708)
		(width 0.28956)
		(layer "F.Cu")
		(net "NODE2_TXD")
	)
	(segment
		(start 8.456168 -38.610032)
		(end 3.490214 -43.575986)
		(width 0.28956)
		(layer "F.Cu")
		(net "NODE2_TXD")
	)
	(segment
		(start 10.830052 -38.610032)
		(end 8.456168 -38.610032)
		(width 0.28956)
		(layer "F.Cu")
		(net "NODE2_TXD")
	)
	(segment
		(start 32.6644 -29.08554)
		(end 28.5242 -29.08554)
		(width 0.28956)
		(layer "F.Cu")
		(net "NODE2_TXD")
	)
	(segment
		(start 3.490214 -43.575986)
		(end 3.490214 -49.30013)
		(width 0.28956)
		(layer "F.Cu")
		(net "NODE2_TXD")
	)
	(segment
		(start 27.63266 -29.97708)
		(end 22.5552 -29.97708)
		(width 0.28956)
		(layer "F.Cu")
		(net "NODE2_TXD")
	)
	(segment
		(start 22.5552 -29.97708)
		(end 16.17472 -36.35756)
		(width 0.28956)
		(layer "F.Cu")
		(net "NODE2_TXD")
	)
	(segment
		(start 13.082524 -36.35756)
		(end 10.830052 -38.610032)
		(width 0.28956)
		(layer "F.Cu")
		(net "NODE2_TXD")
	)
	(segment
		(start 16.17472 -36.35756)
		(end 13.082524 -36.35756)
		(width 0.28956)
		(layer "F.Cu")
		(net "NODE2_TXD")
	)
	(via
		(at 32.6644 -29.08554)
		(size 0.508)
		(drill 0.254)
		(layers "F.Cu" "B.Cu")
		(net "NODE2_TXD")
	)
	(segment
		(start 109.310678 -33.526222)
		(end 120.5738 -22.2631)
		(width 0.18288)
		(layer "In5.Cu")
		(net "NODE2_TXD")
	)
	(segment
		(start 87.315294 -33.526222)
		(end 109.310678 -33.526222)
		(width 0.18288)
		(layer "In5.Cu")
		(net "NODE2_TXD")
	)
	(segment
		(start 121.8184 -12.511786)
		(end 122.530108 -11.800078)
		(width 0.18288)
		(layer "In5.Cu")
		(net "NODE2_TXD")
	)
	(segment
		(start 82.874612 -29.08554)
		(end 87.315294 -33.526222)
		(width 0.18288)
		(layer "In5.Cu")
		(net "NODE2_TXD")
	)
	(segment
		(start 120.5738 -22.2631)
		(end 120.5738 -15.113)
		(width 0.18288)
		(layer "In5.Cu")
		(net "NODE2_TXD")
	)
	(segment
		(start 120.5738 -15.113)
		(end 121.8184 -13.8684)
		(width 0.18288)
		(layer "In5.Cu")
		(net "NODE2_TXD")
	)
	(segment
		(start 32.6644 -29.08554)
		(end 82.874612 -29.08554)
		(width 0.18288)
		(layer "In5.Cu")
		(net "NODE2_TXD")
	)
	(segment
		(start 121.8184 -13.8684)
		(end 121.8184 -12.511786)
		(width 0.18288)
		(layer "In5.Cu")
		(net "NODE2_TXD")
	)
	(segment
		(start 141.890242 -18.490184)
		(end 141.890242 -20.1168)
		(width 0.28956)
		(layer "F.Cu")
		(net "ENET10G_1_MOD_DEF0")
	)
	(segment
		(start 131.023868 -21.143468)
		(end 132.191506 -22.311106)
		(width 0.28956)
		(layer "F.Cu")
		(net "ENET10G_1_MOD_DEF0")
	)
	(segment
		(start 132.191506 -22.311106)
		(end 132.191506 -23.114)
		(width 0.28956)
		(layer "F.Cu")
		(net "ENET10G_1_MOD_DEF0")
	)
	(segment
		(start 132.191506 -23.114)
		(end 130.956812 -24.348694)
		(width 0.28956)
		(layer "F.Cu")
		(net "ENET10G_1_MOD_DEF0")
	)
	(segment
		(start 130.956812 -24.348694)
		(end 130.501898 -24.348694)
		(width 0.28956)
		(layer "F.Cu")
		(net "ENET10G_1_MOD_DEF0")
	)
	(segment
		(start 130.546602 -21.143468)
		(end 131.023868 -21.143468)
		(width 0.28956)
		(layer "F.Cu")
		(net "ENET10G_1_MOD_DEF0")
	)
	(via
		(at 132.191506 -23.114)
		(size 0.508)
		(drill 0.254)
		(layers "F.Cu" "B.Cu")
		(net "ENET10G_1_MOD_DEF0")
	)
	(via
		(at 141.890242 -20.1168)
		(size 0.508)
		(drill 0.254)
		(layers "F.Cu" "B.Cu")
		(net "ENET10G_1_MOD_DEF0")
	)
	(segment
		(start 135.9662 -23.5204)
		(end 134.1628 -23.5204)
		(width 0.18288)
		(layer "In5.Cu")
		(net "ENET10G_1_MOD_DEF0")
	)
	(segment
		(start 134.1628 -23.5204)
		(end 133.7564 -23.114)
		(width 0.18288)
		(layer "In5.Cu")
		(net "ENET10G_1_MOD_DEF0")
	)
	(segment
		(start 140.7922 -20.447)
		(end 139.0396 -20.447)
		(width 0.18288)
		(layer "In5.Cu")
		(net "ENET10G_1_MOD_DEF0")
	)
	(segment
		(start 141.890242 -20.1168)
		(end 141.1224 -20.1168)
		(width 0.18288)
		(layer "In5.Cu")
		(net "ENET10G_1_MOD_DEF0")
	)
	(segment
		(start 141.1224 -20.1168)
		(end 140.7922 -20.447)
		(width 0.18288)
		(layer "In5.Cu")
		(net "ENET10G_1_MOD_DEF0")
	)
	(segment
		(start 133.7564 -23.114)
		(end 132.191506 -23.114)
		(width 0.18288)
		(layer "In5.Cu")
		(net "ENET10G_1_MOD_DEF0")
	)
	(segment
		(start 139.0396 -20.447)
		(end 135.9662 -23.5204)
		(width 0.18288)
		(layer "In5.Cu")
		(net "ENET10G_1_MOD_DEF0")
	)
	(segment
		(start 142.690088 -18.490184)
		(end 142.690088 -20.5232)
		(width 0.28956)
		(layer "F.Cu")
		(net "ENET10G_1_SCL")
	)
	(segment
		(start 131.9276 -24.4856)
		(end 130.972306 -25.440894)
		(width 0.28956)
		(layer "F.Cu")
		(net "ENET10G_1_SCL")
	)
	(segment
		(start 130.972306 -25.440894)
		(end 130.501898 -25.440894)
		(width 0.28956)
		(layer "F.Cu")
		(net "ENET10G_1_SCL")
	)
	(via
		(at 142.690088 -20.5232)
		(size 0.508)
		(drill 0.254)
		(layers "F.Cu" "B.Cu")
		(net "ENET10G_1_SCL")
	)
	(via
		(at 131.9276 -24.4856)
		(size 0.508)
		(drill 0.254)
		(layers "F.Cu" "B.Cu")
		(net "ENET10G_1_SCL")
	)
	(segment
		(start 125.222 -8.391906)
		(end 125.222 -14.135862)
		(width 0.18288)
		(layer "In2.Cu")
		(net "ENET10G_1_SCL")
	)
	(segment
		(start 127.635 -20.32)
		(end 131.8006 -24.4856)
		(width 0.18288)
		(layer "In2.Cu")
		(net "ENET10G_1_SCL")
	)
	(segment
		(start 125.222 -14.135862)
		(end 127.635 -16.548862)
		(width 0.18288)
		(layer "In2.Cu")
		(net "ENET10G_1_SCL")
	)
	(segment
		(start 124.530104 -7.70001)
		(end 125.222 -8.391906)
		(width 0.18288)
		(layer "In2.Cu")
		(net "ENET10G_1_SCL")
	)
	(segment
		(start 127.635 -16.548862)
		(end 127.635 -20.32)
		(width 0.18288)
		(layer "In2.Cu")
		(net "ENET10G_1_SCL")
	)
	(segment
		(start 131.8006 -24.4856)
		(end 131.9276 -24.4856)
		(width 0.18288)
		(layer "In2.Cu")
		(net "ENET10G_1_SCL")
	)
	(segment
		(start 132.2324 -24.1808)
		(end 131.9276 -24.4856)
		(width 0.18288)
		(layer "In5.Cu")
		(net "ENET10G_1_SCL")
	)
	(segment
		(start 139.30376 -21.14804)
		(end 136.271 -24.1808)
		(width 0.18288)
		(layer "In5.Cu")
		(net "ENET10G_1_SCL")
	)
	(segment
		(start 142.690088 -20.5232)
		(end 142.065248 -21.14804)
		(width 0.18288)
		(layer "In5.Cu")
		(net "ENET10G_1_SCL")
	)
	(segment
		(start 136.271 -24.1808)
		(end 132.2324 -24.1808)
		(width 0.18288)
		(layer "In5.Cu")
		(net "ENET10G_1_SCL")
	)
	(segment
		(start 142.065248 -21.14804)
		(end 139.30376 -21.14804)
		(width 0.18288)
		(layer "In5.Cu")
		(net "ENET10G_1_SCL")
	)
	(segment
		(start 143.490188 -18.490184)
		(end 143.490188 -20.8026)
		(width 0.28956)
		(layer "F.Cu")
		(net "ENET10G_1_SDA")
	)
	(segment
		(start 133.5278 -25.2222)
		(end 132.216906 -26.533094)
		(width 0.28956)
		(layer "F.Cu")
		(net "ENET10G_1_SDA")
	)
	(segment
		(start 132.216906 -26.533094)
		(end 130.501898 -26.533094)
		(width 0.28956)
		(layer "F.Cu")
		(net "ENET10G_1_SDA")
	)
	(via
		(at 143.490188 -20.8026)
		(size 0.508)
		(drill 0.254)
		(layers "F.Cu" "B.Cu")
		(net "ENET10G_1_SDA")
	)
	(via
		(at 133.5278 -25.2222)
		(size 0.508)
		(drill 0.254)
		(layers "F.Cu" "B.Cu")
		(net "ENET10G_1_SDA")
	)
	(segment
		(start 127.0762 -6.8834)
		(end 127.5842 -7.3914)
		(width 0.18288)
		(layer "In2.Cu")
		(net "ENET10G_1_SDA")
	)
	(segment
		(start 133.5278 -24.8666)
		(end 133.5278 -25.2222)
		(width 0.18288)
		(layer "In2.Cu")
		(net "ENET10G_1_SDA")
	)
	(segment
		(start 127.5842 -7.3914)
		(end 127.5842 -15.367)
		(width 0.18288)
		(layer "In2.Cu")
		(net "ENET10G_1_SDA")
	)
	(segment
		(start 125.113542 -6.8834)
		(end 127.0762 -6.8834)
		(width 0.18288)
		(layer "In2.Cu")
		(net "ENET10G_1_SDA")
	)
	(segment
		(start 128.3208 -20.0152)
		(end 132.0292 -23.7236)
		(width 0.18288)
		(layer "In2.Cu")
		(net "ENET10G_1_SDA")
	)
	(segment
		(start 132.3848 -23.7236)
		(end 133.5278 -24.8666)
		(width 0.18288)
		(layer "In2.Cu")
		(net "ENET10G_1_SDA")
	)
	(segment
		(start 127.5842 -15.367)
		(end 128.3208 -16.1036)
		(width 0.18288)
		(layer "In2.Cu")
		(net "ENET10G_1_SDA")
	)
	(segment
		(start 128.3208 -16.1036)
		(end 128.3208 -20.0152)
		(width 0.18288)
		(layer "In2.Cu")
		(net "ENET10G_1_SDA")
	)
	(segment
		(start 132.0292 -23.7236)
		(end 132.3848 -23.7236)
		(width 0.18288)
		(layer "In2.Cu")
		(net "ENET10G_1_SDA")
	)
	(segment
		(start 124.530104 -6.299962)
		(end 125.113542 -6.8834)
		(width 0.18288)
		(layer "In2.Cu")
		(net "ENET10G_1_SDA")
	)
	(segment
		(start 136.178036 -25.2222)
		(end 133.5278 -25.2222)
		(width 0.18288)
		(layer "In5.Cu")
		(net "ENET10G_1_SDA")
	)
	(segment
		(start 143.490188 -20.8026)
		(end 142.270988 -22.0218)
		(width 0.18288)
		(layer "In5.Cu")
		(net "ENET10G_1_SDA")
	)
	(segment
		(start 139.378436 -22.0218)
		(end 136.178036 -25.2222)
		(width 0.18288)
		(layer "In5.Cu")
		(net "ENET10G_1_SDA")
	)
	(segment
		(start 142.270988 -22.0218)
		(end 139.378436 -22.0218)
		(width 0.18288)
		(layer "In5.Cu")
		(net "ENET10G_1_SDA")
	)
	(segment
		(start 156.3624 -24.165306)
		(end 157.381702 -24.165306)
		(width 0.28956)
		(layer "F.Cu")
		(net "ENET10G_1_TX_DIS")
	)
	(segment
		(start 155.29941 -24.165306)
		(end 156.3624 -24.165306)
		(width 0.28956)
		(layer "F.Cu")
		(net "ENET10G_1_TX_DIS")
	)
	(segment
		(start 144.290288 -18.490184)
		(end 144.290288 -20.701)
		(width 0.28956)
		(layer "F.Cu")
		(net "ENET10G_1_TX_DIS")
	)
	(via
		(at 144.290288 -20.701)
		(size 0.508)
		(drill 0.254)
		(layers "F.Cu" "B.Cu")
		(net "ENET10G_1_TX_DIS")
	)
	(via
		(at 156.3624 -24.165306)
		(size 0.508)
		(drill 0.254)
		(layers "F.Cu" "B.Cu")
		(net "ENET10G_1_TX_DIS")
	)
	(segment
		(start 145.052288 -21.463)
		(end 144.290288 -20.701)
		(width 0.18288)
		(layer "In5.Cu")
		(net "ENET10G_1_TX_DIS")
	)
	(segment
		(start 154.15514 -24.165306)
		(end 151.452834 -21.463)
		(width 0.18288)
		(layer "In5.Cu")
		(net "ENET10G_1_TX_DIS")
	)
	(segment
		(start 156.3624 -24.165306)
		(end 154.15514 -24.165306)
		(width 0.18288)
		(layer "In5.Cu")
		(net "ENET10G_1_TX_DIS")
	)
	(segment
		(start 151.452834 -21.463)
		(end 145.052288 -21.463)
		(width 0.18288)
		(layer "In5.Cu")
		(net "ENET10G_1_TX_DIS")
	)
	(segment
		(start 184.8104 -25.083008)
		(end 186.149488 -23.74392)
		(width 0.1778)
		(layer "F.Cu")
		(net "SAS_BLAD1_TX4_N")
	)
	(segment
		(start 185.2676 -26.8224)
		(end 184.8104 -26.3652)
		(width 0.1778)
		(layer "F.Cu")
		(net "SAS_BLAD1_TX4_N")
	)
	(segment
		(start 187.560712 -23.74392)
		(end 187.919614 -24.102822)
		(width 0.1778)
		(layer "F.Cu")
		(net "SAS_BLAD1_TX4_N")
	)
	(segment
		(start 187.919614 -24.102822)
		(end 187.919614 -24.584152)
		(width 0.1778)
		(layer "F.Cu")
		(net "SAS_BLAD1_TX4_N")
	)
	(segment
		(start 187.694824 -24.808942)
		(end 187.694824 -25.899872)
		(width 0.1778)
		(layer "F.Cu")
		(net "SAS_BLAD1_TX4_N")
	)
	(segment
		(start 187.919614 -24.584152)
		(end 187.694824 -24.808942)
		(width 0.1778)
		(layer "F.Cu")
		(net "SAS_BLAD1_TX4_N")
	)
	(segment
		(start 186.149488 -23.74392)
		(end 187.560712 -23.74392)
		(width 0.1778)
		(layer "F.Cu")
		(net "SAS_BLAD1_TX4_N")
	)
	(segment
		(start 184.8104 -26.3652)
		(end 184.8104 -25.083008)
		(width 0.1778)
		(layer "F.Cu")
		(net "SAS_BLAD1_TX4_N")
	)
	(via
		(at 185.2676 -26.8224)
		(size 0.508)
		(drill 0.254)
		(layers "F.Cu" "B.Cu")
		(net "SAS_BLAD1_TX4_N")
	)
	(segment
		(start 177.713132 -19.17954)
		(end 175.16475 -16.631158)
		(width 0.1778)
		(layer "B.Cu")
		(net "SAS_BLAD1_TX4_N")
	)
	(segment
		(start 171.953682 -14.56309)
		(end 171.710604 -13.976096)
		(width 0.1778)
		(layer "B.Cu")
		(net "SAS_BLAD1_TX4_N")
	)
	(segment
		(start 175.113696 -16.597376)
		(end 174.29226 -16.256508)
		(width 0.1778)
		(layer "B.Cu")
		(net "SAS_BLAD1_TX4_N")
	)
	(segment
		(start 171.657772 -11.427968)
		(end 171.657518 -11.427714)
		(width 0.1778)
		(layer "B.Cu")
		(net "SAS_BLAD1_TX4_N")
	)
	(segment
		(start 171.075604 -11.37539)
		(end 170.88993 -11.561064)
		(width 0.1778)
		(layer "B.Cu")
		(net "SAS_BLAD1_TX4_N")
	)
	(segment
		(start 179.421282 -19.761708)
		(end 178.642264 -19.43862)
		(width 0.1778)
		(layer "B.Cu")
		(net "SAS_BLAD1_TX4_N")
	)
	(segment
		(start 170.88993 -11.561064)
		(end 170.88993 -11.900154)
		(width 0.1778)
		(layer "B.Cu")
		(net "SAS_BLAD1_TX4_N")
	)
	(segment
		(start 171.710604 -13.976096)
		(end 171.710604 -11.555222)
		(width 0.1778)
		(layer "B.Cu")
		(net "SAS_BLAD1_TX4_N")
	)
	(segment
		(start 178.60391 -19.431)
		(end 178.320192 -19.431)
		(width 0.1778)
		(layer "B.Cu")
		(net "SAS_BLAD1_TX4_N")
	)
	(segment
		(start 185.2676 -26.8224)
		(end 184.80786 -27.28214)
		(width 0.1778)
		(layer "B.Cu")
		(net "SAS_BLAD1_TX4_N")
	)
	(segment
		(start 184.80786 -27.28214)
		(end 184.80786 -27.579828)
		(width 0.1778)
		(layer "B.Cu")
		(net "SAS_BLAD1_TX4_N")
	)
	(segment
		(start 181.602888 -23.280624)
		(end 180.656738 -20.99691)
		(width 0.1778)
		(layer "B.Cu")
		(net "SAS_BLAD1_TX4_N")
	)
	(segment
		(start 174.264066 -16.25092)
		(end 173.997112 -16.25092)
		(width 0.1778)
		(layer "B.Cu")
		(net "SAS_BLAD1_TX4_N")
	)
	(segment
		(start 173.390052 -15.99946)
		(end 171.953682 -14.56309)
		(width 0.1778)
		(layer "B.Cu")
		(net "SAS_BLAD1_TX4_N")
	)
	(segment
		(start 171.53128 -11.37539)
		(end 171.075604 -11.37539)
		(width 0.1778)
		(layer "B.Cu")
		(net "SAS_BLAD1_TX4_N")
	)
	(segment
		(start 182.767732 -28.04414)
		(end 181.86654 -27.142948)
		(width 0.1778)
		(layer "B.Cu")
		(net "SAS_BLAD1_TX4_N")
	)
	(segment
		(start 180.622702 -20.94611)
		(end 179.472336 -19.795744)
		(width 0.1778)
		(layer "B.Cu")
		(net "SAS_BLAD1_TX4_N")
	)
	(segment
		(start 184.092088 -28.2956)
		(end 183.374792 -28.2956)
		(width 0.1778)
		(layer "B.Cu")
		(net "SAS_BLAD1_TX4_N")
	)
	(segment
		(start 184.659016 -27.938984)
		(end 184.451498 -28.146502)
		(width 0.1778)
		(layer "B.Cu")
		(net "SAS_BLAD1_TX4_N")
	)
	(segment
		(start 181.61508 -26.535888)
		(end 181.61508 -23.340822)
		(width 0.1778)
		(layer "B.Cu")
		(net "SAS_BLAD1_TX4_N")
	)
	(arc
		(start 173.997112 -16.25092)
		(mid 173.668571 -16.185569)
		(end 173.390052 -15.99946)
		(width 0.1778)
		(layer "B.Cu")
		(net "SAS_BLAD1_TX4_N")
	)
	(arc
		(start 184.80786 -27.579828)
		(mid 184.769176 -27.774217)
		(end 184.659016 -27.938984)
		(width 0.1778)
		(layer "B.Cu")
		(net "SAS_BLAD1_TX4_N")
	)
	(arc
		(start 171.657518 -11.427714)
		(mid 171.599613 -11.38899)
		(end 171.53128 -11.37539)
		(width 0.1778)
		(layer "B.Cu")
		(net "SAS_BLAD1_TX4_N")
	)
	(arc
		(start 181.61508 -23.340822)
		(mid 181.611957 -23.31012)
		(end 181.602888 -23.280624)
		(width 0.1778)
		(layer "B.Cu")
		(net "SAS_BLAD1_TX4_N")
	)
	(arc
		(start 178.642264 -19.43862)
		(mid 178.623462 -19.432923)
		(end 178.60391 -19.431)
		(width 0.1778)
		(layer "B.Cu")
		(net "SAS_BLAD1_TX4_N")
	)
	(arc
		(start 178.320192 -19.431)
		(mid 177.991651 -19.365649)
		(end 177.713132 -19.17954)
		(width 0.1778)
		(layer "B.Cu")
		(net "SAS_BLAD1_TX4_N")
	)
	(arc
		(start 183.374792 -28.2956)
		(mid 183.046251 -28.230249)
		(end 182.767732 -28.04414)
		(width 0.1778)
		(layer "B.Cu")
		(net "SAS_BLAD1_TX4_N")
	)
	(arc
		(start 184.451498 -28.146502)
		(mid 184.286642 -28.256845)
		(end 184.092088 -28.2956)
		(width 0.1778)
		(layer "B.Cu")
		(net "SAS_BLAD1_TX4_N")
	)
	(arc
		(start 175.16475 -16.631158)
		(mid 175.140889 -16.611747)
		(end 175.113696 -16.597376)
		(width 0.1778)
		(layer "B.Cu")
		(net "SAS_BLAD1_TX4_N")
	)
	(arc
		(start 179.472336 -19.795744)
		(mid 179.448486 -19.77621)
		(end 179.421282 -19.761708)
		(width 0.1778)
		(layer "B.Cu")
		(net "SAS_BLAD1_TX4_N")
	)
	(arc
		(start 174.29226 -16.256508)
		(mid 174.278437 -16.25233)
		(end 174.264066 -16.25092)
		(width 0.1778)
		(layer "B.Cu")
		(net "SAS_BLAD1_TX4_N")
	)
	(arc
		(start 171.710604 -11.555222)
		(mid 171.696881 -11.48632)
		(end 171.657772 -11.427968)
		(width 0.1778)
		(layer "B.Cu")
		(net "SAS_BLAD1_TX4_N")
	)
	(arc
		(start 181.86654 -27.142948)
		(mid 181.680438 -26.864427)
		(end 181.61508 -26.535888)
		(width 0.1778)
		(layer "B.Cu")
		(net "SAS_BLAD1_TX4_N")
	)
	(arc
		(start 180.656738 -20.99691)
		(mid 180.642207 -20.969844)
		(end 180.622702 -20.94611)
		(width 0.1778)
		(layer "B.Cu")
		(net "SAS_BLAD1_TX4_N")
	)
	(segment
		(start 155.29941 -22.899878)
		(end 156.1846 -22.899878)
		(width 0.28956)
		(layer "F.Cu")
		(net "ENET10G_1_TX_FAULT")
	)
	(segment
		(start 145.090134 -18.490184)
		(end 145.090134 -20.2438)
		(width 0.28956)
		(layer "F.Cu")
		(net "ENET10G_1_TX_FAULT")
	)
	(segment
		(start 156.1846 -22.899878)
		(end 157.381702 -22.899878)
		(width 0.28956)
		(layer "F.Cu")
		(net "ENET10G_1_TX_FAULT")
	)
	(via
		(at 145.090134 -20.2438)
		(size 0.508)
		(drill 0.254)
		(layers "F.Cu" "B.Cu")
		(net "ENET10G_1_TX_FAULT")
	)
	(via
		(at 156.1846 -22.899878)
		(size 0.508)
		(drill 0.254)
		(layers "F.Cu" "B.Cu")
		(net "ENET10G_1_TX_FAULT")
	)
	(segment
		(start 153.608278 -22.899878)
		(end 151.6634 -20.955)
		(width 0.18288)
		(layer "In5.Cu")
		(net "ENET10G_1_TX_FAULT")
	)
	(segment
		(start 145.801334 -20.955)
		(end 145.090134 -20.2438)
		(width 0.18288)
		(layer "In5.Cu")
		(net "ENET10G_1_TX_FAULT")
	)
	(segment
		(start 156.1846 -22.899878)
		(end 153.608278 -22.899878)
		(width 0.18288)
		(layer "In5.Cu")
		(net "ENET10G_1_TX_FAULT")
	)
	(segment
		(start 151.6634 -20.955)
		(end 145.801334 -20.955)
		(width 0.18288)
		(layer "In5.Cu")
		(net "ENET10G_1_TX_FAULT")
	)
	(segment
		(start 166.2176 -24.6634)
		(end 166.7002 -24.1808)
		(width 0.1778)
		(layer "F.Cu")
		(net "SAS_BLAD1_TX8_N")
	)
	(segment
		(start 168.909746 -24.584152)
		(end 168.684956 -24.808942)
		(width 0.1778)
		(layer "F.Cu")
		(net "SAS_BLAD1_TX8_N")
	)
	(segment
		(start 168.684956 -24.808942)
		(end 168.684956 -25.899872)
		(width 0.1778)
		(layer "F.Cu")
		(net "SAS_BLAD1_TX8_N")
	)
	(segment
		(start 166.7002 -24.1808)
		(end 168.693592 -24.1808)
		(width 0.1778)
		(layer "F.Cu")
		(net "SAS_BLAD1_TX8_N")
	)
	(segment
		(start 168.693592 -24.1808)
		(end 168.909746 -24.396954)
		(width 0.1778)
		(layer "F.Cu")
		(net "SAS_BLAD1_TX8_N")
	)
	(segment
		(start 168.909746 -24.396954)
		(end 168.909746 -24.584152)
		(width 0.1778)
		(layer "F.Cu")
		(net "SAS_BLAD1_TX8_N")
	)
	(via
		(at 166.2176 -24.6634)
		(size 0.508)
		(drill 0.254)
		(layers "F.Cu" "B.Cu")
		(net "SAS_BLAD1_TX8_N")
	)
	(segment
		(start 166.6494 -24.2316)
		(end 166.2176 -24.6634)
		(width 0.1524)
		(layer "In5.Cu")
		(net "SAS_BLAD1_TX8_N")
	)
	(segment
		(start 164.393118 -8.503158)
		(end 162.776154 -8.503158)
		(width 0.1524)
		(layer "In5.Cu")
		(net "SAS_BLAD1_TX8_N")
	)
	(segment
		(start 164.889942 -8.999982)
		(end 164.393118 -8.503158)
		(width 0.1524)
		(layer "In5.Cu")
		(net "SAS_BLAD1_TX8_N")
	)
	(segment
		(start 161.896044 -17.268444)
		(end 167.313356 -22.685756)
		(width 0.1524)
		(layer "In5.Cu")
		(net "SAS_BLAD1_TX8_N")
	)
	(segment
		(start 162.416998 -8.652002)
		(end 161.896044 -9.172956)
		(width 0.1524)
		(layer "In5.Cu")
		(net "SAS_BLAD1_TX8_N")
	)
	(segment
		(start 161.7472 -9.532112)
		(end 161.7472 -16.909288)
		(width 0.1524)
		(layer "In5.Cu")
		(net "SAS_BLAD1_TX8_N")
	)
	(segment
		(start 167.313356 -24.024844)
		(end 167.255444 -24.082756)
		(width 0.1524)
		(layer "In5.Cu")
		(net "SAS_BLAD1_TX8_N")
	)
	(segment
		(start 166.896288 -24.2316)
		(end 166.6494 -24.2316)
		(width 0.1524)
		(layer "In5.Cu")
		(net "SAS_BLAD1_TX8_N")
	)
	(segment
		(start 167.4622 -23.044912)
		(end 167.4622 -23.665688)
		(width 0.1524)
		(layer "In5.Cu")
		(net "SAS_BLAD1_TX8_N")
	)
	(arc
		(start 167.313356 -22.685756)
		(mid 167.423514 -22.850524)
		(end 167.4622 -23.044912)
		(width 0.1524)
		(layer "In5.Cu")
		(net "SAS_BLAD1_TX8_N")
	)
	(arc
		(start 162.776154 -8.503158)
		(mid 162.581765 -8.541842)
		(end 162.416998 -8.652002)
		(width 0.1524)
		(layer "In5.Cu")
		(net "SAS_BLAD1_TX8_N")
	)
	(arc
		(start 167.4622 -23.665688)
		(mid 167.423516 -23.860077)
		(end 167.313356 -24.024844)
		(width 0.1524)
		(layer "In5.Cu")
		(net "SAS_BLAD1_TX8_N")
	)
	(arc
		(start 161.7472 -16.909288)
		(mid 161.785884 -17.103677)
		(end 161.896044 -17.268444)
		(width 0.1524)
		(layer "In5.Cu")
		(net "SAS_BLAD1_TX8_N")
	)
	(arc
		(start 167.255444 -24.082756)
		(mid 167.090676 -24.192914)
		(end 166.896288 -24.2316)
		(width 0.1524)
		(layer "In5.Cu")
		(net "SAS_BLAD1_TX8_N")
	)
	(arc
		(start 161.896044 -9.172956)
		(mid 161.785886 -9.337724)
		(end 161.7472 -9.532112)
		(width 0.1524)
		(layer "In5.Cu")
		(net "SAS_BLAD1_TX8_N")
	)
	(segment
		(start 169.260266 -24.584152)
		(end 169.485056 -24.808942)
		(width 0.1778)
		(layer "F.Cu")
		(net "SAS_BLAD1_TX8_P")
	)
	(segment
		(start 166.2176 -23.3934)
		(end 166.65448 -23.83028)
		(width 0.1778)
		(layer "F.Cu")
		(net "SAS_BLAD1_TX8_P")
	)
	(segment
		(start 169.485056 -24.808942)
		(end 169.485056 -25.899872)
		(width 0.1778)
		(layer "F.Cu")
		(net "SAS_BLAD1_TX8_P")
	)
	(segment
		(start 169.260266 -24.251666)
		(end 169.260266 -24.584152)
		(width 0.1778)
		(layer "F.Cu")
		(net "SAS_BLAD1_TX8_P")
	)
	(segment
		(start 168.83888 -23.83028)
		(end 169.260266 -24.251666)
		(width 0.1778)
		(layer "F.Cu")
		(net "SAS_BLAD1_TX8_P")
	)
	(segment
		(start 166.65448 -23.83028)
		(end 168.83888 -23.83028)
		(width 0.1778)
		(layer "F.Cu")
		(net "SAS_BLAD1_TX8_P")
	)
	(via
		(at 166.2176 -23.3934)
		(size 0.508)
		(drill 0.254)
		(layers "F.Cu" "B.Cu")
		(net "SAS_BLAD1_TX8_P")
	)
	(segment
		(start 161.608516 -17.555972)
		(end 162.004756 -17.952212)
		(width 0.1524)
		(layer "In5.Cu")
		(net "SAS_BLAD1_TX8_P")
	)
	(segment
		(start 162.004756 -18.189702)
		(end 162.328098 -18.513044)
		(width 0.1524)
		(layer "In5.Cu")
		(net "SAS_BLAD1_TX8_P")
	)
	(segment
		(start 164.889942 -7.600188)
		(end 164.393372 -8.096758)
		(width 0.1524)
		(layer "In5.Cu")
		(net "SAS_BLAD1_TX8_P")
	)
	(segment
		(start 162.328098 -18.513044)
		(end 162.565842 -18.513044)
		(width 0.1524)
		(layer "In5.Cu")
		(net "SAS_BLAD1_TX8_P")
	)
	(segment
		(start 167.0558 -23.044912)
		(end 167.0558 -23.665688)
		(width 0.1524)
		(layer "In5.Cu")
		(net "SAS_BLAD1_TX8_P")
	)
	(segment
		(start 165.86581 -22.050756)
		(end 166.103554 -22.050756)
		(width 0.1524)
		(layer "In5.Cu")
		(net "SAS_BLAD1_TX8_P")
	)
	(segment
		(start 163.773612 -19.958558)
		(end 164.096954 -20.2819)
		(width 0.1524)
		(layer "In5.Cu")
		(net "SAS_BLAD1_TX8_P")
	)
	(segment
		(start 164.096954 -20.2819)
		(end 164.334698 -20.2819)
		(width 0.1524)
		(layer "In5.Cu")
		(net "SAS_BLAD1_TX8_P")
	)
	(segment
		(start 164.393372 -8.096758)
		(end 162.776154 -8.096758)
		(width 0.1524)
		(layer "In5.Cu")
		(net "SAS_BLAD1_TX8_P")
	)
	(segment
		(start 165.542468 -21.48967)
		(end 165.542468 -21.727414)
		(width 0.1524)
		(layer "In5.Cu")
		(net "SAS_BLAD1_TX8_P")
	)
	(segment
		(start 166.896288 -23.8252)
		(end 166.6494 -23.8252)
		(width 0.1524)
		(layer "In5.Cu")
		(net "SAS_BLAD1_TX8_P")
	)
	(segment
		(start 162.12947 -8.364474)
		(end 161.60877 -8.885428)
		(width 0.1524)
		(layer "In5.Cu")
		(net "SAS_BLAD1_TX8_P")
	)
	(segment
		(start 165.219126 -21.166328)
		(end 165.542468 -21.48967)
		(width 0.1524)
		(layer "In5.Cu")
		(net "SAS_BLAD1_TX8_P")
	)
	(segment
		(start 166.6494 -23.8252)
		(end 166.2176 -23.3934)
		(width 0.1524)
		(layer "In5.Cu")
		(net "SAS_BLAD1_TX8_P")
	)
	(segment
		(start 166.103554 -22.050756)
		(end 167.026082 -22.973284)
		(width 0.1524)
		(layer "In5.Cu")
		(net "SAS_BLAD1_TX8_P")
	)
	(segment
		(start 165.542468 -21.727414)
		(end 165.86581 -22.050756)
		(width 0.1524)
		(layer "In5.Cu")
		(net "SAS_BLAD1_TX8_P")
	)
	(segment
		(start 162.889184 -18.836386)
		(end 162.889184 -19.07413)
		(width 0.1524)
		(layer "In5.Cu")
		(net "SAS_BLAD1_TX8_P")
	)
	(segment
		(start 163.773612 -19.720814)
		(end 163.773612 -19.958558)
		(width 0.1524)
		(layer "In5.Cu")
		(net "SAS_BLAD1_TX8_P")
	)
	(segment
		(start 162.004756 -17.952212)
		(end 162.004756 -18.189702)
		(width 0.1524)
		(layer "In5.Cu")
		(net "SAS_BLAD1_TX8_P")
	)
	(segment
		(start 163.212526 -19.397472)
		(end 163.45027 -19.397472)
		(width 0.1524)
		(layer "In5.Cu")
		(net "SAS_BLAD1_TX8_P")
	)
	(segment
		(start 164.334698 -20.2819)
		(end 164.65804 -20.605242)
		(width 0.1524)
		(layer "In5.Cu")
		(net "SAS_BLAD1_TX8_P")
	)
	(segment
		(start 164.65804 -20.842986)
		(end 164.981382 -21.166328)
		(width 0.1524)
		(layer "In5.Cu")
		(net "SAS_BLAD1_TX8_P")
	)
	(segment
		(start 164.65804 -20.605242)
		(end 164.65804 -20.842986)
		(width 0.1524)
		(layer "In5.Cu")
		(net "SAS_BLAD1_TX8_P")
	)
	(segment
		(start 162.889184 -19.07413)
		(end 163.212526 -19.397472)
		(width 0.1524)
		(layer "In5.Cu")
		(net "SAS_BLAD1_TX8_P")
	)
	(segment
		(start 162.565842 -18.513044)
		(end 162.889184 -18.836386)
		(width 0.1524)
		(layer "In5.Cu")
		(net "SAS_BLAD1_TX8_P")
	)
	(segment
		(start 167.026082 -23.737316)
		(end 166.967916 -23.795482)
		(width 0.1524)
		(layer "In5.Cu")
		(net "SAS_BLAD1_TX8_P")
	)
	(segment
		(start 163.45027 -19.397472)
		(end 163.773612 -19.720814)
		(width 0.1524)
		(layer "In5.Cu")
		(net "SAS_BLAD1_TX8_P")
	)
	(segment
		(start 161.3408 -9.532112)
		(end 161.3408 -16.909288)
		(width 0.1524)
		(layer "In5.Cu")
		(net "SAS_BLAD1_TX8_P")
	)
	(segment
		(start 164.981382 -21.166328)
		(end 165.219126 -21.166328)
		(width 0.1524)
		(layer "In5.Cu")
		(net "SAS_BLAD1_TX8_P")
	)
	(arc
		(start 167.0558 -23.665688)
		(mid 167.04807 -23.704457)
		(end 167.026082 -23.737316)
		(width 0.1524)
		(layer "In5.Cu")
		(net "SAS_BLAD1_TX8_P")
	)
	(arc
		(start 166.967916 -23.795482)
		(mid 166.935067 -23.817494)
		(end 166.896288 -23.8252)
		(width 0.1524)
		(layer "In5.Cu")
		(net "SAS_BLAD1_TX8_P")
	)
	(arc
		(start 162.776154 -8.096758)
		(mid 162.426189 -8.166295)
		(end 162.12947 -8.364474)
		(width 0.1524)
		(layer "In5.Cu")
		(net "SAS_BLAD1_TX8_P")
	)
	(arc
		(start 161.3408 -16.909288)
		(mid 161.410337 -17.259253)
		(end 161.608516 -17.555972)
		(width 0.1524)
		(layer "In5.Cu")
		(net "SAS_BLAD1_TX8_P")
	)
	(arc
		(start 161.60877 -8.885428)
		(mid 161.410467 -9.182115)
		(end 161.3408 -9.532112)
		(width 0.1524)
		(layer "In5.Cu")
		(net "SAS_BLAD1_TX8_P")
	)
	(arc
		(start 167.026082 -22.973284)
		(mid 167.048094 -23.006133)
		(end 167.0558 -23.044912)
		(width 0.1524)
		(layer "In5.Cu")
		(net "SAS_BLAD1_TX8_P")
	)
	(segment
		(start 188.494924 -24.808942)
		(end 188.494924 -25.899872)
		(width 0.1778)
		(layer "F.Cu")
		(net "SAS_BLAD1_TX4_P")
	)
	(segment
		(start 187.706 -23.3934)
		(end 188.270134 -23.957534)
		(width 0.1778)
		(layer "F.Cu")
		(net "SAS_BLAD1_TX4_P")
	)
	(segment
		(start 183.9976 -26.8224)
		(end 184.45988 -26.36012)
		(width 0.1778)
		(layer "F.Cu")
		(net "SAS_BLAD1_TX4_P")
	)
	(segment
		(start 188.270134 -24.584152)
		(end 188.494924 -24.808942)
		(width 0.1778)
		(layer "F.Cu")
		(net "SAS_BLAD1_TX4_P")
	)
	(segment
		(start 184.45988 -24.93772)
		(end 186.0042 -23.3934)
		(width 0.1778)
		(layer "F.Cu")
		(net "SAS_BLAD1_TX4_P")
	)
	(segment
		(start 186.0042 -23.3934)
		(end 187.706 -23.3934)
		(width 0.1778)
		(layer "F.Cu")
		(net "SAS_BLAD1_TX4_P")
	)
	(segment
		(start 184.45988 -26.36012)
		(end 184.45988 -24.93772)
		(width 0.1778)
		(layer "F.Cu")
		(net "SAS_BLAD1_TX4_P")
	)
	(segment
		(start 188.270134 -23.957534)
		(end 188.270134 -24.584152)
		(width 0.1778)
		(layer "F.Cu")
		(net "SAS_BLAD1_TX4_P")
	)
	(via
		(at 183.9976 -26.8224)
		(size 0.508)
		(drill 0.254)
		(layers "F.Cu" "B.Cu")
		(net "SAS_BLAD1_TX4_P")
	)
	(segment
		(start 184.45734 -27.28214)
		(end 184.45734 -27.579828)
		(width 0.1778)
		(layer "B.Cu")
		(net "SAS_BLAD1_TX4_P")
	)
	(segment
		(start 184.411112 -27.69108)
		(end 184.20334 -27.898852)
		(width 0.1778)
		(layer "B.Cu")
		(net "SAS_BLAD1_TX4_P")
	)
	(segment
		(start 170.999404 -11.02487)
		(end 170.88993 -10.915396)
		(width 0.1778)
		(layer "B.Cu")
		(net "SAS_BLAD1_TX4_P")
	)
	(segment
		(start 182.13832 -25.508966)
		(end 181.9656 -25.336246)
		(width 0.1778)
		(layer "B.Cu")
		(net "SAS_BLAD1_TX4_P")
	)
	(segment
		(start 181.9656 -24.792686)
		(end 182.13832 -24.619966)
		(width 0.1778)
		(layer "B.Cu")
		(net "SAS_BLAD1_TX4_P")
	)
	(segment
		(start 177.64252 -18.61312)
		(end 177.64252 -18.39722)
		(width 0.1778)
		(layer "B.Cu")
		(net "SAS_BLAD1_TX4_P")
	)
	(segment
		(start 182.13832 -24.619966)
		(end 182.13832 -24.086566)
		(width 0.1778)
		(layer "B.Cu")
		(net "SAS_BLAD1_TX4_P")
	)
	(segment
		(start 175.248062 -16.273272)
		(end 174.426372 -15.932658)
		(width 0.1778)
		(layer "B.Cu")
		(net "SAS_BLAD1_TX4_P")
	)
	(segment
		(start 177.26533 -18.02003)
		(end 177.04943 -18.02003)
		(width 0.1778)
		(layer "B.Cu")
		(net "SAS_BLAD1_TX4_P")
	)
	(segment
		(start 171.905676 -11.180064)
		(end 171.905422 -11.17981)
		(width 0.1778)
		(layer "B.Cu")
		(net "SAS_BLAD1_TX4_P")
	)
	(segment
		(start 180.870606 -20.698206)
		(end 179.72024 -19.54784)
		(width 0.1778)
		(layer "B.Cu")
		(net "SAS_BLAD1_TX4_P")
	)
	(segment
		(start 182.13832 -26.042366)
		(end 182.13832 -25.508966)
		(width 0.1778)
		(layer "B.Cu")
		(net "SAS_BLAD1_TX4_P")
	)
	(segment
		(start 171.53128 -11.02487)
		(end 170.999404 -11.02487)
		(width 0.1778)
		(layer "B.Cu")
		(net "SAS_BLAD1_TX4_P")
	)
	(segment
		(start 183.015636 -27.796236)
		(end 182.114444 -26.895044)
		(width 0.1778)
		(layer "B.Cu")
		(net "SAS_BLAD1_TX4_P")
	)
	(segment
		(start 181.9656 -23.913846)
		(end 181.9656 -23.341076)
		(width 0.1778)
		(layer "B.Cu")
		(net "SAS_BLAD1_TX4_P")
	)
	(segment
		(start 179.555648 -19.437858)
		(end 178.776376 -19.11477)
		(width 0.1778)
		(layer "B.Cu")
		(net "SAS_BLAD1_TX4_P")
	)
	(segment
		(start 172.250862 -14.364462)
		(end 172.061124 -13.906246)
		(width 0.1778)
		(layer "B.Cu")
		(net "SAS_BLAD1_TX4_P")
	)
	(segment
		(start 170.88993 -10.915396)
		(end 170.88993 -10.500106)
		(width 0.1778)
		(layer "B.Cu")
		(net "SAS_BLAD1_TX4_P")
	)
	(segment
		(start 183.9976 -26.8224)
		(end 184.45734 -27.28214)
		(width 0.1778)
		(layer "B.Cu")
		(net "SAS_BLAD1_TX4_P")
	)
	(segment
		(start 178.60391 -19.08048)
		(end 178.320192 -19.08048)
		(width 0.1778)
		(layer "B.Cu")
		(net "SAS_BLAD1_TX4_P")
	)
	(segment
		(start 181.9656 -25.336246)
		(end 181.9656 -24.792686)
		(width 0.1778)
		(layer "B.Cu")
		(net "SAS_BLAD1_TX4_P")
	)
	(segment
		(start 184.092088 -27.94508)
		(end 183.374792 -27.94508)
		(width 0.1778)
		(layer "B.Cu")
		(net "SAS_BLAD1_TX4_P")
	)
	(segment
		(start 173.637956 -15.751556)
		(end 172.250862 -14.364462)
		(width 0.1778)
		(layer "B.Cu")
		(net "SAS_BLAD1_TX4_P")
	)
	(segment
		(start 181.9656 -26.535888)
		(end 181.9656 -26.215086)
		(width 0.1778)
		(layer "B.Cu")
		(net "SAS_BLAD1_TX4_P")
	)
	(segment
		(start 172.061124 -13.906246)
		(end 172.061124 -11.554968)
		(width 0.1778)
		(layer "B.Cu")
		(net "SAS_BLAD1_TX4_P")
	)
	(segment
		(start 182.13832 -24.086566)
		(end 181.9656 -23.913846)
		(width 0.1778)
		(layer "B.Cu")
		(net "SAS_BLAD1_TX4_P")
	)
	(segment
		(start 177.961036 -18.931636)
		(end 177.64252 -18.61312)
		(width 0.1778)
		(layer "B.Cu")
		(net "SAS_BLAD1_TX4_P")
	)
	(segment
		(start 177.04943 -18.02003)
		(end 175.412654 -16.383254)
		(width 0.1778)
		(layer "B.Cu")
		(net "SAS_BLAD1_TX4_P")
	)
	(segment
		(start 174.264066 -15.9004)
		(end 173.997112 -15.9004)
		(width 0.1778)
		(layer "B.Cu")
		(net "SAS_BLAD1_TX4_P")
	)
	(segment
		(start 177.64252 -18.39722)
		(end 177.26533 -18.02003)
		(width 0.1778)
		(layer "B.Cu")
		(net "SAS_BLAD1_TX4_P")
	)
	(segment
		(start 181.926992 -23.146512)
		(end 180.980588 -20.862798)
		(width 0.1778)
		(layer "B.Cu")
		(net "SAS_BLAD1_TX4_P")
	)
	(segment
		(start 181.9656 -26.215086)
		(end 182.13832 -26.042366)
		(width 0.1778)
		(layer "B.Cu")
		(net "SAS_BLAD1_TX4_P")
	)
	(arc
		(start 172.061124 -11.554968)
		(mid 172.02067 -11.352065)
		(end 171.905676 -11.180064)
		(width 0.1778)
		(layer "B.Cu")
		(net "SAS_BLAD1_TX4_P")
	)
	(arc
		(start 178.320192 -19.08048)
		(mid 178.125803 -19.041796)
		(end 177.961036 -18.931636)
		(width 0.1778)
		(layer "B.Cu")
		(net "SAS_BLAD1_TX4_P")
	)
	(arc
		(start 178.776376 -19.11477)
		(mid 178.691831 -19.089135)
		(end 178.60391 -19.08048)
		(width 0.1778)
		(layer "B.Cu")
		(net "SAS_BLAD1_TX4_P")
	)
	(arc
		(start 179.72024 -19.54784)
		(mid 179.643348 -19.484763)
		(end 179.555648 -19.437858)
		(width 0.1778)
		(layer "B.Cu")
		(net "SAS_BLAD1_TX4_P")
	)
	(arc
		(start 180.980588 -20.862798)
		(mid 180.933696 -20.775089)
		(end 180.870606 -20.698206)
		(width 0.1778)
		(layer "B.Cu")
		(net "SAS_BLAD1_TX4_P")
	)
	(arc
		(start 184.20334 -27.898852)
		(mid 184.152326 -27.933065)
		(end 184.092088 -27.94508)
		(width 0.1778)
		(layer "B.Cu")
		(net "SAS_BLAD1_TX4_P")
	)
	(arc
		(start 181.9656 -23.341076)
		(mid 181.955874 -23.241894)
		(end 181.926992 -23.146512)
		(width 0.1778)
		(layer "B.Cu")
		(net "SAS_BLAD1_TX4_P")
	)
	(arc
		(start 184.45734 -27.579828)
		(mid 184.445322 -27.640064)
		(end 184.411112 -27.69108)
		(width 0.1778)
		(layer "B.Cu")
		(net "SAS_BLAD1_TX4_P")
	)
	(arc
		(start 173.997112 -15.9004)
		(mid 173.802723 -15.861716)
		(end 173.637956 -15.751556)
		(width 0.1778)
		(layer "B.Cu")
		(net "SAS_BLAD1_TX4_P")
	)
	(arc
		(start 175.412654 -16.383254)
		(mid 175.335762 -16.320177)
		(end 175.248062 -16.273272)
		(width 0.1778)
		(layer "B.Cu")
		(net "SAS_BLAD1_TX4_P")
	)
	(arc
		(start 183.374792 -27.94508)
		(mid 183.180403 -27.906396)
		(end 183.015636 -27.796236)
		(width 0.1778)
		(layer "B.Cu")
		(net "SAS_BLAD1_TX4_P")
	)
	(arc
		(start 182.114444 -26.895044)
		(mid 182.004286 -26.730276)
		(end 181.9656 -26.535888)
		(width 0.1778)
		(layer "B.Cu")
		(net "SAS_BLAD1_TX4_P")
	)
	(arc
		(start 174.426372 -15.932658)
		(mid 174.346806 -15.908542)
		(end 174.264066 -15.9004)
		(width 0.1778)
		(layer "B.Cu")
		(net "SAS_BLAD1_TX4_P")
	)
	(arc
		(start 171.905422 -11.17981)
		(mid 171.733778 -11.065087)
		(end 171.53128 -11.02487)
		(width 0.1778)
		(layer "B.Cu")
		(net "SAS_BLAD1_TX4_P")
	)
	(segment
		(start 190.27013 -30.135068)
		(end 190.27013 -29.72562)
		(width 0.1778)
		(layer "F.Cu")
		(net "SAS_BLAD1_RX3_P")
	)
	(segment
		(start 190.27013 -29.72562)
		(end 190.49492 -29.50083)
		(width 0.1778)
		(layer "F.Cu")
		(net "SAS_BLAD1_RX3_P")
	)
	(segment
		(start 190.49492 -29.50083)
		(end 190.49492 -28.4099)
		(width 0.1778)
		(layer "F.Cu")
		(net "SAS_BLAD1_RX3_P")
	)
	(segment
		(start 190.72987 -30.594808)
		(end 190.27013 -30.135068)
		(width 0.1778)
		(layer "F.Cu")
		(net "SAS_BLAD1_RX3_P")
	)
	(via
		(at 190.72987 -30.594808)
		(size 0.508)
		(drill 0.254)
		(layers "F.Cu" "B.Cu")
		(net "SAS_BLAD1_RX3_P")
	)
	(segment
		(start 174.54626 -13.928852)
		(end 174.112428 -13.49502)
		(width 0.1778)
		(layer "B.Cu")
		(net "SAS_BLAD1_RX3_P")
	)
	(segment
		(start 183.984646 -21.606002)
		(end 183.74614 -21.552662)
		(width 0.1778)
		(layer "B.Cu")
		(net "SAS_BLAD1_RX3_P")
	)
	(segment
		(start 188.726064 -27.410918)
		(end 188.726064 -27.166824)
		(width 0.1778)
		(layer "B.Cu")
		(net "SAS_BLAD1_RX3_P")
	)
	(segment
		(start 188.726064 -27.166824)
		(end 188.34862 -26.78938)
		(width 0.1778)
		(layer "B.Cu")
		(net "SAS_BLAD1_RX3_P")
	)
	(segment
		(start 173.139608 -3.924808)
		(end 172.889926 -3.675126)
		(width 0.1778)
		(layer "B.Cu")
		(net "SAS_BLAD1_RX3_P")
	)
	(segment
		(start 188.34862 -26.78938)
		(end 188.104526 -26.78938)
		(width 0.1778)
		(layer "B.Cu")
		(net "SAS_BLAD1_RX3_P")
	)
	(segment
		(start 184.988708 -23.50135)
		(end 184.979818 -23.499572)
		(width 0.1778)
		(layer "B.Cu")
		(net "SAS_BLAD1_RX3_P")
	)
	(segment
		(start 184.979818 -23.499572)
		(end 185.033412 -23.261066)
		(width 0.1778)
		(layer "B.Cu")
		(net "SAS_BLAD1_RX3_P")
	)
	(segment
		(start 184.50941 -22.757384)
		(end 184.511442 -22.749764)
		(width 0.1778)
		(layer "B.Cu")
		(net "SAS_BLAD1_RX3_P")
	)
	(segment
		(start 174.0662 -13.383768)
		(end 174.0662 -4.528312)
		(width 0.1778)
		(layer "B.Cu")
		(net "SAS_BLAD1_RX3_P")
	)
	(segment
		(start 190.27013 -30.135068)
		(end 190.27013 -29.165296)
		(width 0.1778)
		(layer "B.Cu")
		(net "SAS_BLAD1_RX3_P")
	)
	(segment
		(start 184.747916 -22.810724)
		(end 184.50941 -22.757384)
		(width 0.1778)
		(layer "B.Cu")
		(net "SAS_BLAD1_RX3_P")
	)
	(segment
		(start 189.734444 -28.17495)
		(end 189.357254 -27.79776)
		(width 0.1778)
		(layer "B.Cu")
		(net "SAS_BLAD1_RX3_P")
	)
	(segment
		(start 174.694088 -13.97508)
		(end 174.657512 -13.97508)
		(width 0.1778)
		(layer "B.Cu")
		(net "SAS_BLAD1_RX3_P")
	)
	(segment
		(start 183.457596 -21.090636)
		(end 183.457342 -21.09089)
		(width 0.1778)
		(layer "B.Cu")
		(net "SAS_BLAD1_RX3_P")
	)
	(segment
		(start 183.506618 -20.851876)
		(end 183.221376 -20.40128)
		(width 0.1778)
		(layer "B.Cu")
		(net "SAS_BLAD1_RX3_P")
	)
	(segment
		(start 182.220108 -19.142202)
		(end 181.8386 -18.54073)
		(width 0.1778)
		(layer "B.Cu")
		(net "SAS_BLAD1_RX3_P")
	)
	(segment
		(start 189.734444 -28.419298)
		(end 189.734444 -28.17495)
		(width 0.1778)
		(layer "B.Cu")
		(net "SAS_BLAD1_RX3_P")
	)
	(segment
		(start 182.457852 -19.196812)
		(end 182.2196 -19.143472)
		(width 0.1778)
		(layer "B.Cu")
		(net "SAS_BLAD1_RX3_P")
	)
	(segment
		(start 182.2196 -19.143472)
		(end 182.220108 -19.142202)
		(width 0.1778)
		(layer "B.Cu")
		(net "SAS_BLAD1_RX3_P")
	)
	(segment
		(start 183.74741 -21.547328)
		(end 183.74741 -21.547074)
		(width 0.1778)
		(layer "B.Cu")
		(net "SAS_BLAD1_RX3_P")
	)
	(segment
		(start 182.690008 -19.88566)
		(end 182.743602 -19.647408)
		(width 0.1778)
		(layer "B.Cu")
		(net "SAS_BLAD1_RX3_P")
	)
	(segment
		(start 182.743602 -19.647408)
		(end 182.457852 -19.196812)
		(width 0.1778)
		(layer "B.Cu")
		(net "SAS_BLAD1_RX3_P")
	)
	(segment
		(start 182.691532 -19.884898)
		(end 182.690008 -19.88566)
		(width 0.1778)
		(layer "B.Cu")
		(net "SAS_BLAD1_RX3_P")
	)
	(segment
		(start 179.320952 -16.988536)
		(end 175.897286 -14.228318)
		(width 0.1778)
		(layer "B.Cu")
		(net "SAS_BLAD1_RX3_P")
	)
	(segment
		(start 185.682636 -24.594058)
		(end 184.988708 -23.50135)
		(width 0.1778)
		(layer "B.Cu")
		(net "SAS_BLAD1_RX3_P")
	)
	(segment
		(start 184.511442 -22.749764)
		(end 184.223152 -22.295866)
		(width 0.1778)
		(layer "B.Cu")
		(net "SAS_BLAD1_RX3_P")
	)
	(segment
		(start 182.98287 -20.347686)
		(end 182.983632 -20.344892)
		(width 0.1778)
		(layer "B.Cu")
		(net "SAS_BLAD1_RX3_P")
	)
	(segment
		(start 175.897286 -14.228318)
		(end 174.694088 -13.97508)
		(width 0.1778)
		(layer "B.Cu")
		(net "SAS_BLAD1_RX3_P")
	)
	(segment
		(start 183.74741 -21.547074)
		(end 183.457596 -21.090636)
		(width 0.1778)
		(layer "B.Cu")
		(net "SAS_BLAD1_RX3_P")
	)
	(segment
		(start 189.112906 -27.79776)
		(end 188.726064 -27.410918)
		(width 0.1778)
		(layer "B.Cu")
		(net "SAS_BLAD1_RX3_P")
	)
	(segment
		(start 173.462696 -3.924808)
		(end 173.139608 -3.924808)
		(width 0.1778)
		(layer "B.Cu")
		(net "SAS_BLAD1_RX3_P")
	)
	(segment
		(start 190.121286 -28.80614)
		(end 189.734444 -28.419298)
		(width 0.1778)
		(layer "B.Cu")
		(net "SAS_BLAD1_RX3_P")
	)
	(segment
		(start 190.72987 -30.594808)
		(end 190.27013 -30.135068)
		(width 0.1778)
		(layer "B.Cu")
		(net "SAS_BLAD1_RX3_P")
	)
	(segment
		(start 183.74614 -21.552662)
		(end 183.74741 -21.547328)
		(width 0.1778)
		(layer "B.Cu")
		(net "SAS_BLAD1_RX3_P")
	)
	(segment
		(start 183.453024 -21.090128)
		(end 183.506618 -20.851876)
		(width 0.1778)
		(layer "B.Cu")
		(net "SAS_BLAD1_RX3_P")
	)
	(segment
		(start 181.8386 -18.54073)
		(end 179.320952 -16.988536)
		(width 0.1778)
		(layer "B.Cu")
		(net "SAS_BLAD1_RX3_P")
	)
	(segment
		(start 184.270142 -22.056598)
		(end 183.984646 -21.606002)
		(width 0.1778)
		(layer "B.Cu")
		(net "SAS_BLAD1_RX3_P")
	)
	(segment
		(start 187.809632 -26.495756)
		(end 185.682636 -24.594058)
		(width 0.1778)
		(layer "B.Cu")
		(net "SAS_BLAD1_RX3_P")
	)
	(segment
		(start 185.033412 -23.261066)
		(end 184.747916 -22.810724)
		(width 0.1778)
		(layer "B.Cu")
		(net "SAS_BLAD1_RX3_P")
	)
	(segment
		(start 172.889926 -3.675126)
		(end 172.889926 -3.400044)
		(width 0.1778)
		(layer "B.Cu")
		(net "SAS_BLAD1_RX3_P")
	)
	(segment
		(start 184.223152 -22.295866)
		(end 184.216548 -22.29485)
		(width 0.1778)
		(layer "B.Cu")
		(net "SAS_BLAD1_RX3_P")
	)
	(segment
		(start 184.216548 -22.29485)
		(end 184.270142 -22.056598)
		(width 0.1778)
		(layer "B.Cu")
		(net "SAS_BLAD1_RX3_P")
	)
	(segment
		(start 173.917102 -4.168902)
		(end 173.821852 -4.073652)
		(width 0.1778)
		(layer "B.Cu")
		(net "SAS_BLAD1_RX3_P")
	)
	(segment
		(start 182.983632 -20.344892)
		(end 182.691532 -19.884898)
		(width 0.1778)
		(layer "B.Cu")
		(net "SAS_BLAD1_RX3_P")
	)
	(segment
		(start 188.104526 -26.78938)
		(end 187.830206 -26.51506)
		(width 0.1778)
		(layer "B.Cu")
		(net "SAS_BLAD1_RX3_P")
	)
	(segment
		(start 183.221376 -20.40128)
		(end 182.98287 -20.347686)
		(width 0.1778)
		(layer "B.Cu")
		(net "SAS_BLAD1_RX3_P")
	)
	(segment
		(start 183.457342 -21.09089)
		(end 183.453024 -21.090128)
		(width 0.1778)
		(layer "B.Cu")
		(net "SAS_BLAD1_RX3_P")
	)
	(segment
		(start 189.357254 -27.79776)
		(end 189.112906 -27.79776)
		(width 0.1778)
		(layer "B.Cu")
		(net "SAS_BLAD1_RX3_P")
	)
	(arc
		(start 190.27013 -29.165296)
		(mid 190.231446 -28.970907)
		(end 190.121286 -28.80614)
		(width 0.1778)
		(layer "B.Cu")
		(net "SAS_BLAD1_RX3_P")
	)
	(arc
		(start 174.112428 -13.49502)
		(mid 174.078215 -13.444006)
		(end 174.0662 -13.383768)
		(width 0.1778)
		(layer "B.Cu")
		(net "SAS_BLAD1_RX3_P")
	)
	(arc
		(start 174.0662 -4.528312)
		(mid 174.027447 -4.333757)
		(end 173.917102 -4.168902)
		(width 0.1778)
		(layer "B.Cu")
		(net "SAS_BLAD1_RX3_P")
	)
	(arc
		(start 174.657512 -13.97508)
		(mid 174.597276 -13.963062)
		(end 174.54626 -13.928852)
		(width 0.1778)
		(layer "B.Cu")
		(net "SAS_BLAD1_RX3_P")
	)
	(arc
		(start 173.821852 -4.073652)
		(mid 173.657084 -3.963494)
		(end 173.462696 -3.924808)
		(width 0.1778)
		(layer "B.Cu")
		(net "SAS_BLAD1_RX3_P")
	)
	(arc
		(start 187.830206 -26.51506)
		(mid 187.820051 -26.505267)
		(end 187.809632 -26.495756)
		(width 0.1778)
		(layer "B.Cu")
		(net "SAS_BLAD1_RX3_P")
	)
	(segment
		(start 189.69482 -29.50083)
		(end 189.69482 -28.4099)
		(width 0.1778)
		(layer "F.Cu")
		(net "SAS_BLAD1_RX3_N")
	)
	(segment
		(start 189.91961 -29.72562)
		(end 189.69482 -29.50083)
		(width 0.1778)
		(layer "F.Cu")
		(net "SAS_BLAD1_RX3_N")
	)
	(segment
		(start 189.45987 -30.594808)
		(end 189.91961 -30.135068)
		(width 0.1778)
		(layer "F.Cu")
		(net "SAS_BLAD1_RX3_N")
	)
	(segment
		(start 189.91961 -30.135068)
		(end 189.91961 -29.72562)
		(width 0.1778)
		(layer "F.Cu")
		(net "SAS_BLAD1_RX3_N")
	)
	(via
		(at 189.45987 -30.594808)
		(size 0.508)
		(drill 0.254)
		(layers "F.Cu" "B.Cu")
		(net "SAS_BLAD1_RX3_N")
	)
	(segment
		(start 173.669452 -4.41706)
		(end 173.573948 -4.321556)
		(width 0.1778)
		(layer "B.Cu")
		(net "SAS_BLAD1_RX3_N")
	)
	(segment
		(start 173.71568 -13.383768)
		(end 173.71568 -4.528312)
		(width 0.1778)
		(layer "B.Cu")
		(net "SAS_BLAD1_RX3_N")
	)
	(segment
		(start 174.298102 -14.176502)
		(end 173.864524 -13.742924)
		(width 0.1778)
		(layer "B.Cu")
		(net "SAS_BLAD1_RX3_N")
	)
	(segment
		(start 179.10937 -17.268698)
		(end 175.7426 -14.5542)
		(width 0.1778)
		(layer "B.Cu")
		(net "SAS_BLAD1_RX3_N")
	)
	(segment
		(start 173.462696 -4.275328)
		(end 173.0756 -4.275328)
		(width 0.1778)
		(layer "B.Cu")
		(net "SAS_BLAD1_RX3_N")
	)
	(segment
		(start 187.576206 -26.75763)
		(end 185.414666 -24.82469)
		(width 0.1778)
		(layer "B.Cu")
		(net "SAS_BLAD1_RX3_N")
	)
	(segment
		(start 185.412888 -24.823166)
		(end 181.5846 -18.796254)
		(width 0.1778)
		(layer "B.Cu")
		(net "SAS_BLAD1_RX3_N")
	)
	(segment
		(start 187.576714 -26.758138)
		(end 187.576206 -26.75763)
		(width 0.1778)
		(layer "B.Cu")
		(net "SAS_BLAD1_RX3_N")
	)
	(segment
		(start 179.118006 -17.275556)
		(end 179.112418 -17.271238)
		(width 0.1778)
		(layer "B.Cu")
		(net "SAS_BLAD1_RX3_N")
	)
	(segment
		(start 172.889926 -4.461002)
		(end 172.889926 -4.800092)
		(width 0.1778)
		(layer "B.Cu")
		(net "SAS_BLAD1_RX3_N")
	)
	(segment
		(start 189.45987 -30.594808)
		(end 189.91961 -30.135068)
		(width 0.1778)
		(layer "B.Cu")
		(net "SAS_BLAD1_RX3_N")
	)
	(segment
		(start 185.414666 -24.82469)
		(end 185.412888 -24.823166)
		(width 0.1778)
		(layer "B.Cu")
		(net "SAS_BLAD1_RX3_N")
	)
	(segment
		(start 181.5846 -18.796254)
		(end 179.118006 -17.275556)
		(width 0.1778)
		(layer "B.Cu")
		(net "SAS_BLAD1_RX3_N")
	)
	(segment
		(start 189.91961 -30.135068)
		(end 189.91961 -29.165296)
		(width 0.1778)
		(layer "B.Cu")
		(net "SAS_BLAD1_RX3_N")
	)
	(segment
		(start 189.873382 -29.054044)
		(end 187.58281 -26.763726)
		(width 0.1778)
		(layer "B.Cu")
		(net "SAS_BLAD1_RX3_N")
	)
	(segment
		(start 173.0756 -4.275328)
		(end 172.889926 -4.461002)
		(width 0.1778)
		(layer "B.Cu")
		(net "SAS_BLAD1_RX3_N")
	)
	(segment
		(start 175.7426 -14.5542)
		(end 174.657512 -14.3256)
		(width 0.1778)
		(layer "B.Cu")
		(net "SAS_BLAD1_RX3_N")
	)
	(arc
		(start 173.864524 -13.742924)
		(mid 173.754366 -13.578156)
		(end 173.71568 -13.383768)
		(width 0.1778)
		(layer "B.Cu")
		(net "SAS_BLAD1_RX3_N")
	)
	(arc
		(start 187.58281 -26.763726)
		(mid 187.579799 -26.760892)
		(end 187.576714 -26.758138)
		(width 0.1778)
		(layer "B.Cu")
		(net "SAS_BLAD1_RX3_N")
	)
	(arc
		(start 173.573948 -4.321556)
		(mid 173.522934 -4.287343)
		(end 173.462696 -4.275328)
		(width 0.1778)
		(layer "B.Cu")
		(net "SAS_BLAD1_RX3_N")
	)
	(arc
		(start 189.91961 -29.165296)
		(mid 189.907592 -29.10506)
		(end 189.873382 -29.054044)
		(width 0.1778)
		(layer "B.Cu")
		(net "SAS_BLAD1_RX3_N")
	)
	(arc
		(start 173.71568 -4.528312)
		(mid 173.703662 -4.468076)
		(end 173.669452 -4.41706)
		(width 0.1778)
		(layer "B.Cu")
		(net "SAS_BLAD1_RX3_N")
	)
	(arc
		(start 174.657512 -14.3256)
		(mid 174.462957 -14.286847)
		(end 174.298102 -14.176502)
		(width 0.1778)
		(layer "B.Cu")
		(net "SAS_BLAD1_RX3_N")
	)
	(arc
		(start 179.112418 -17.271238)
		(mid 179.110886 -17.269977)
		(end 179.10937 -17.268698)
		(width 0.1778)
		(layer "B.Cu")
		(net "SAS_BLAD1_RX3_N")
	)
	(segment
		(start 171.485052 -28.4099)
		(end 171.485052 -29.50083)
		(width 0.1778)
		(layer "F.Cu")
		(net "SAS_BLAD1_RX7_P")
	)
	(segment
		(start 171.485052 -29.50083)
		(end 171.260262 -29.72562)
		(width 0.1778)
		(layer "F.Cu")
		(net "SAS_BLAD1_RX7_P")
	)
	(segment
		(start 171.260262 -31.52648)
		(end 171.720002 -31.98622)
		(width 0.1778)
		(layer "F.Cu")
		(net "SAS_BLAD1_RX7_P")
	)
	(segment
		(start 171.260262 -29.72562)
		(end 171.260262 -31.52648)
		(width 0.1778)
		(layer "F.Cu")
		(net "SAS_BLAD1_RX7_P")
	)
	(via
		(at 171.720002 -31.98622)
		(size 0.508)
		(drill 0.254)
		(layers "F.Cu" "B.Cu")
		(net "SAS_BLAD1_RX7_P")
	)
	(segment
		(start 166.0906 -28.759912)
		(end 166.0906 -30.244288)
		(width 0.1524)
		(layer "In5.Cu")
		(net "SAS_BLAD1_RX7_P")
	)
	(segment
		(start 163.195 -13.044424)
		(end 163.195 -16.309086)
		(width 0.1524)
		(layer "In5.Cu")
		(net "SAS_BLAD1_RX7_P")
	)
	(segment
		(start 171.014644 -33.252156)
		(end 171.139358 -33.127442)
		(width 0.1524)
		(layer "In5.Cu")
		(net "SAS_BLAD1_RX7_P")
	)
	(segment
		(start 169.037 -22.740112)
		(end 169.037 -25.392888)
		(width 0.1524)
		(layer "In5.Cu")
		(net "SAS_BLAD1_RX7_P")
	)
	(segment
		(start 171.288202 -32.41802)
		(end 171.720002 -31.98622)
		(width 0.1524)
		(layer "In5.Cu")
		(net "SAS_BLAD1_RX7_P")
	)
	(segment
		(start 164.715698 -12.296902)
		(end 163.942776 -12.296902)
		(width 0.1524)
		(layer "In5.Cu")
		(net "SAS_BLAD1_RX7_P")
	)
	(segment
		(start 164.889942 -12.122658)
		(end 164.715698 -12.296902)
		(width 0.1524)
		(layer "In5.Cu")
		(net "SAS_BLAD1_RX7_P")
	)
	(segment
		(start 164.889942 -11.800078)
		(end 164.889942 -12.122658)
		(width 0.1524)
		(layer "In5.Cu")
		(net "SAS_BLAD1_RX7_P")
	)
	(segment
		(start 166.358316 -30.890972)
		(end 168.600628 -33.13303)
		(width 0.1524)
		(layer "In5.Cu")
		(net "SAS_BLAD1_RX7_P")
	)
	(segment
		(start 169.007282 -25.464516)
		(end 166.35857 -28.113228)
		(width 0.1524)
		(layer "In5.Cu")
		(net "SAS_BLAD1_RX7_P")
	)
	(segment
		(start 169.247312 -33.401)
		(end 170.655488 -33.401)
		(width 0.1524)
		(layer "In5.Cu")
		(net "SAS_BLAD1_RX7_P")
	)
	(segment
		(start 163.462716 -16.95577)
		(end 168.888156 -22.380956)
		(width 0.1524)
		(layer "In5.Cu")
		(net "SAS_BLAD1_RX7_P")
	)
	(segment
		(start 171.288202 -32.768286)
		(end 171.288202 -32.41802)
		(width 0.1524)
		(layer "In5.Cu")
		(net "SAS_BLAD1_RX7_P")
	)
	(arc
		(start 166.0906 -30.244288)
		(mid 166.160137 -30.594253)
		(end 166.358316 -30.890972)
		(width 0.1524)
		(layer "In5.Cu")
		(net "SAS_BLAD1_RX7_P")
	)
	(arc
		(start 169.037 -25.392888)
		(mid 169.02927 -25.431657)
		(end 169.007282 -25.464516)
		(width 0.1524)
		(layer "In5.Cu")
		(net "SAS_BLAD1_RX7_P")
	)
	(arc
		(start 163.942776 -12.296902)
		(mid 163.656464 -12.353759)
		(end 163.413694 -12.51585)
		(width 0.1524)
		(layer "In5.Cu")
		(net "SAS_BLAD1_RX7_P")
	)
	(arc
		(start 170.655488 -33.401)
		(mid 170.849877 -33.362316)
		(end 171.014644 -33.252156)
		(width 0.1524)
		(layer "In5.Cu")
		(net "SAS_BLAD1_RX7_P")
	)
	(arc
		(start 168.888156 -22.380956)
		(mid 168.998314 -22.545724)
		(end 169.037 -22.740112)
		(width 0.1524)
		(layer "In5.Cu")
		(net "SAS_BLAD1_RX7_P")
	)
	(arc
		(start 166.35857 -28.113228)
		(mid 166.160267 -28.409915)
		(end 166.0906 -28.759912)
		(width 0.1524)
		(layer "In5.Cu")
		(net "SAS_BLAD1_RX7_P")
	)
	(arc
		(start 163.195 -16.309086)
		(mid 163.264537 -16.659051)
		(end 163.462716 -16.95577)
		(width 0.1524)
		(layer "In5.Cu")
		(net "SAS_BLAD1_RX7_P")
	)
	(arc
		(start 171.139358 -33.127442)
		(mid 171.249516 -32.962674)
		(end 171.288202 -32.768286)
		(width 0.1524)
		(layer "In5.Cu")
		(net "SAS_BLAD1_RX7_P")
	)
	(arc
		(start 163.413694 -12.51585)
		(mid 163.251789 -12.758391)
		(end 163.195 -13.044424)
		(width 0.1524)
		(layer "In5.Cu")
		(net "SAS_BLAD1_RX7_P")
	)
	(arc
		(start 168.600628 -33.13303)
		(mid 168.897315 -33.331333)
		(end 169.247312 -33.401)
		(width 0.1524)
		(layer "In5.Cu")
		(net "SAS_BLAD1_RX7_P")
	)
	(segment
		(start 170.684952 -29.50083)
		(end 170.909742 -29.72562)
		(width 0.1778)
		(layer "F.Cu")
		(net "SAS_BLAD1_RX7_N")
	)
	(segment
		(start 170.684952 -28.4099)
		(end 170.684952 -29.50083)
		(width 0.1778)
		(layer "F.Cu")
		(net "SAS_BLAD1_RX7_N")
	)
	(segment
		(start 170.909742 -29.72562)
		(end 170.909742 -31.52648)
		(width 0.1778)
		(layer "F.Cu")
		(net "SAS_BLAD1_RX7_N")
	)
	(segment
		(start 170.909742 -31.52648)
		(end 170.450002 -31.98622)
		(width 0.1778)
		(layer "F.Cu")
		(net "SAS_BLAD1_RX7_N")
	)
	(via
		(at 170.450002 -31.98622)
		(size 0.508)
		(drill 0.254)
		(layers "F.Cu" "B.Cu")
		(net "SAS_BLAD1_RX7_N")
	)
	(segment
		(start 165.777164 -18.695162)
		(end 166.040054 -18.695162)
		(width 0.1524)
		(layer "In5.Cu")
		(net "SAS_BLAD1_RX7_N")
	)
	(segment
		(start 170.881802 -32.41802)
		(end 170.450002 -31.98622)
		(width 0.1524)
		(layer "In5.Cu")
		(net "SAS_BLAD1_RX7_N")
	)
	(segment
		(start 166.36365 -19.018758)
		(end 166.36365 -19.149822)
		(width 0.1524)
		(layer "In5.Cu")
		(net "SAS_BLAD1_RX7_N")
	)
	(segment
		(start 164.543486 -17.461484)
		(end 164.867336 -17.785334)
		(width 0.1524)
		(layer "In5.Cu")
		(net "SAS_BLAD1_RX7_N")
	)
	(segment
		(start 166.040054 -18.695162)
		(end 166.36365 -19.018758)
		(width 0.1524)
		(layer "In5.Cu")
		(net "SAS_BLAD1_RX7_N")
	)
	(segment
		(start 168.367964 -21.285962)
		(end 168.630854 -21.285962)
		(width 0.1524)
		(layer "In5.Cu")
		(net "SAS_BLAD1_RX7_N")
	)
	(segment
		(start 168.044876 -20.699984)
		(end 168.044368 -20.831302)
		(width 0.1524)
		(layer "In5.Cu")
		(net "SAS_BLAD1_RX7_N")
	)
	(segment
		(start 167.721026 -20.376134)
		(end 168.044876 -20.699984)
		(width 0.1524)
		(layer "In5.Cu")
		(net "SAS_BLAD1_RX7_N")
	)
	(segment
		(start 163.750244 -16.668242)
		(end 163.957508 -16.875506)
		(width 0.1524)
		(layer "In5.Cu")
		(net "SAS_BLAD1_RX7_N")
	)
	(segment
		(start 167.458136 -20.376134)
		(end 167.721026 -20.376134)
		(width 0.1524)
		(layer "In5.Cu")
		(net "SAS_BLAD1_RX7_N")
	)
	(segment
		(start 168.044368 -20.831302)
		(end 168.044368 -20.962366)
		(width 0.1524)
		(layer "In5.Cu")
		(net "SAS_BLAD1_RX7_N")
	)
	(segment
		(start 165.453822 -18.239994)
		(end 165.453314 -18.371312)
		(width 0.1524)
		(layer "In5.Cu")
		(net "SAS_BLAD1_RX7_N")
	)
	(segment
		(start 165.453314 -18.371312)
		(end 165.777164 -18.695162)
		(width 0.1524)
		(layer "In5.Cu")
		(net "SAS_BLAD1_RX7_N")
	)
	(segment
		(start 166.363142 -19.28114)
		(end 167.458136 -20.376134)
		(width 0.1524)
		(layer "In5.Cu")
		(net "SAS_BLAD1_RX7_N")
	)
	(segment
		(start 163.957508 -16.875506)
		(end 164.220398 -16.875506)
		(width 0.1524)
		(layer "In5.Cu")
		(net "SAS_BLAD1_RX7_N")
	)
	(segment
		(start 164.220398 -16.875506)
		(end 164.543994 -17.199102)
		(width 0.1524)
		(layer "In5.Cu")
		(net "SAS_BLAD1_RX7_N")
	)
	(segment
		(start 168.044368 -20.962366)
		(end 168.367964 -21.285962)
		(width 0.1524)
		(layer "In5.Cu")
		(net "SAS_BLAD1_RX7_N")
	)
	(segment
		(start 164.543994 -17.330166)
		(end 164.543486 -17.461484)
		(width 0.1524)
		(layer "In5.Cu")
		(net "SAS_BLAD1_RX7_N")
	)
	(segment
		(start 165.453822 -18.10893)
		(end 165.453822 -18.239994)
		(width 0.1524)
		(layer "In5.Cu")
		(net "SAS_BLAD1_RX7_N")
	)
	(segment
		(start 169.294556 -25.752044)
		(end 166.645844 -28.400756)
		(width 0.1524)
		(layer "In5.Cu")
		(net "SAS_BLAD1_RX7_N")
	)
	(segment
		(start 166.645844 -30.603444)
		(end 168.888156 -32.845756)
		(width 0.1524)
		(layer "In5.Cu")
		(net "SAS_BLAD1_RX7_N")
	)
	(segment
		(start 164.889942 -12.896342)
		(end 164.696902 -12.703302)
		(width 0.1524)
		(layer "In5.Cu")
		(net "SAS_BLAD1_RX7_N")
	)
	(segment
		(start 170.881802 -32.768286)
		(end 170.881802 -32.41802)
		(width 0.1524)
		(layer "In5.Cu")
		(net "SAS_BLAD1_RX7_N")
	)
	(segment
		(start 168.954704 -21.609812)
		(end 168.954196 -21.74113)
		(width 0.1524)
		(layer "In5.Cu")
		(net "SAS_BLAD1_RX7_N")
	)
	(segment
		(start 164.889942 -13.200126)
		(end 164.889942 -12.896342)
		(width 0.1524)
		(layer "In5.Cu")
		(net "SAS_BLAD1_RX7_N")
	)
	(segment
		(start 165.130226 -17.785334)
		(end 165.453822 -18.10893)
		(width 0.1524)
		(layer "In5.Cu")
		(net "SAS_BLAD1_RX7_N")
	)
	(segment
		(start 168.954196 -21.872194)
		(end 169.17543 -22.093428)
		(width 0.1524)
		(layer "In5.Cu")
		(net "SAS_BLAD1_RX7_N")
	)
	(segment
		(start 170.727116 -32.964882)
		(end 170.852084 -32.839914)
		(width 0.1524)
		(layer "In5.Cu")
		(net "SAS_BLAD1_RX7_N")
	)
	(segment
		(start 169.4434 -22.740112)
		(end 169.4434 -25.392888)
		(width 0.1524)
		(layer "In5.Cu")
		(net "SAS_BLAD1_RX7_N")
	)
	(segment
		(start 168.954196 -21.74113)
		(end 168.954196 -21.872194)
		(width 0.1524)
		(layer "In5.Cu")
		(net "SAS_BLAD1_RX7_N")
	)
	(segment
		(start 164.696902 -12.703302)
		(end 163.942776 -12.703302)
		(width 0.1524)
		(layer "In5.Cu")
		(net "SAS_BLAD1_RX7_N")
	)
	(segment
		(start 168.630854 -21.285962)
		(end 168.954704 -21.609812)
		(width 0.1524)
		(layer "In5.Cu")
		(net "SAS_BLAD1_RX7_N")
	)
	(segment
		(start 166.497 -28.759912)
		(end 166.497 -30.244288)
		(width 0.1524)
		(layer "In5.Cu")
		(net "SAS_BLAD1_RX7_N")
	)
	(segment
		(start 166.36365 -19.149822)
		(end 166.363142 -19.28114)
		(width 0.1524)
		(layer "In5.Cu")
		(net "SAS_BLAD1_RX7_N")
	)
	(segment
		(start 164.543994 -17.199102)
		(end 164.543994 -17.330166)
		(width 0.1524)
		(layer "In5.Cu")
		(net "SAS_BLAD1_RX7_N")
	)
	(segment
		(start 163.6014 -13.044424)
		(end 163.6014 -16.309086)
		(width 0.1524)
		(layer "In5.Cu")
		(net "SAS_BLAD1_RX7_N")
	)
	(segment
		(start 164.867336 -17.785334)
		(end 165.130226 -17.785334)
		(width 0.1524)
		(layer "In5.Cu")
		(net "SAS_BLAD1_RX7_N")
	)
	(segment
		(start 169.247312 -32.9946)
		(end 170.655488 -32.9946)
		(width 0.1524)
		(layer "In5.Cu")
		(net "SAS_BLAD1_RX7_N")
	)
	(arc
		(start 169.17543 -22.093428)
		(mid 169.373733 -22.390115)
		(end 169.4434 -22.740112)
		(width 0.1524)
		(layer "In5.Cu")
		(net "SAS_BLAD1_RX7_N")
	)
	(arc
		(start 163.701222 -12.803378)
		(mid 163.627326 -12.913971)
		(end 163.6014 -13.044424)
		(width 0.1524)
		(layer "In5.Cu")
		(net "SAS_BLAD1_RX7_N")
	)
	(arc
		(start 166.645844 -28.400756)
		(mid 166.535686 -28.565524)
		(end 166.497 -28.759912)
		(width 0.1524)
		(layer "In5.Cu")
		(net "SAS_BLAD1_RX7_N")
	)
	(arc
		(start 170.852084 -32.839914)
		(mid 170.874096 -32.807065)
		(end 170.881802 -32.768286)
		(width 0.1524)
		(layer "In5.Cu")
		(net "SAS_BLAD1_RX7_N")
	)
	(arc
		(start 170.655488 -32.9946)
		(mid 170.694257 -32.98687)
		(end 170.727116 -32.964882)
		(width 0.1524)
		(layer "In5.Cu")
		(net "SAS_BLAD1_RX7_N")
	)
	(arc
		(start 166.497 -30.244288)
		(mid 166.535684 -30.438677)
		(end 166.645844 -30.603444)
		(width 0.1524)
		(layer "In5.Cu")
		(net "SAS_BLAD1_RX7_N")
	)
	(arc
		(start 163.6014 -16.309086)
		(mid 163.640084 -16.503475)
		(end 163.750244 -16.668242)
		(width 0.1524)
		(layer "In5.Cu")
		(net "SAS_BLAD1_RX7_N")
	)
	(arc
		(start 169.4434 -25.392888)
		(mid 169.404716 -25.587277)
		(end 169.294556 -25.752044)
		(width 0.1524)
		(layer "In5.Cu")
		(net "SAS_BLAD1_RX7_N")
	)
	(arc
		(start 168.888156 -32.845756)
		(mid 169.052924 -32.955914)
		(end 169.247312 -32.9946)
		(width 0.1524)
		(layer "In5.Cu")
		(net "SAS_BLAD1_RX7_N")
	)
	(arc
		(start 163.942776 -12.703302)
		(mid 163.81204 -12.729307)
		(end 163.701222 -12.803378)
		(width 0.1524)
		(layer "In5.Cu")
		(net "SAS_BLAD1_RX7_N")
	)
	(segment
		(start 190.31966 -24.584152)
		(end 190.31966 -24.03856)
		(width 0.1778)
		(layer "F.Cu")
		(net "SAS_BLAD1_TX3_N")
	)
	(segment
		(start 190.09487 -24.808942)
		(end 190.31966 -24.584152)
		(width 0.1778)
		(layer "F.Cu")
		(net "SAS_BLAD1_TX3_N")
	)
	(segment
		(start 190.09487 -25.899872)
		(end 190.09487 -24.808942)
		(width 0.1778)
		(layer "F.Cu")
		(net "SAS_BLAD1_TX3_N")
	)
	(segment
		(start 190.31966 -24.03856)
		(end 189.85992 -23.57882)
		(width 0.1778)
		(layer "F.Cu")
		(net "SAS_BLAD1_TX3_N")
	)
	(via
		(at 189.85992 -23.57882)
		(size 0.508)
		(drill 0.254)
		(layers "F.Cu" "B.Cu")
		(net "SAS_BLAD1_TX3_N")
	)
	(segment
		(start 173.119796 -8.503158)
		(end 172.889926 -8.733028)
		(width 0.1524)
		(layer "In5.Cu")
		(net "SAS_BLAD1_TX3_N")
	)
	(segment
		(start 174.137828 -14.108684)
		(end 173.95952 -13.930122)
		(width 0.1524)
		(layer "In5.Cu")
		(net "SAS_BLAD1_TX3_N")
	)
	(segment
		(start 173.49724 -8.503158)
		(end 173.119796 -8.503158)
		(width 0.1524)
		(layer "In5.Cu")
		(net "SAS_BLAD1_TX3_N")
	)
	(segment
		(start 190.29172 -23.14702)
		(end 190.29172 -22.531832)
		(width 0.1524)
		(layer "In5.Cu")
		(net "SAS_BLAD1_TX3_N")
	)
	(segment
		(start 182.136288 -14.3764)
		(end 174.784512 -14.3764)
		(width 0.1524)
		(layer "In5.Cu")
		(net "SAS_BLAD1_TX3_N")
	)
	(segment
		(start 172.889926 -8.733028)
		(end 172.889926 -8.999982)
		(width 0.1524)
		(layer "In5.Cu")
		(net "SAS_BLAD1_TX3_N")
	)
	(segment
		(start 190.142876 -22.172676)
		(end 182.495444 -14.525244)
		(width 0.1524)
		(layer "In5.Cu")
		(net "SAS_BLAD1_TX3_N")
	)
	(segment
		(start 189.85992 -23.57882)
		(end 190.29172 -23.14702)
		(width 0.1524)
		(layer "In5.Cu")
		(net "SAS_BLAD1_TX3_N")
	)
	(segment
		(start 173.69155 -13.283438)
		(end 173.69155 -8.697214)
		(width 0.1524)
		(layer "In5.Cu")
		(net "SAS_BLAD1_TX3_N")
	)
	(arc
		(start 174.784512 -14.3764)
		(mid 174.434547 -14.306863)
		(end 174.137828 -14.108684)
		(width 0.1524)
		(layer "In5.Cu")
		(net "SAS_BLAD1_TX3_N")
	)
	(arc
		(start 182.495444 -14.525244)
		(mid 182.330676 -14.415086)
		(end 182.136288 -14.3764)
		(width 0.1524)
		(layer "In5.Cu")
		(net "SAS_BLAD1_TX3_N")
	)
	(arc
		(start 190.29172 -22.531832)
		(mid 190.253036 -22.337443)
		(end 190.142876 -22.172676)
		(width 0.1524)
		(layer "In5.Cu")
		(net "SAS_BLAD1_TX3_N")
	)
	(arc
		(start 173.634654 -8.560054)
		(mid 173.571608 -8.517928)
		(end 173.49724 -8.503158)
		(width 0.1524)
		(layer "In5.Cu")
		(net "SAS_BLAD1_TX3_N")
	)
	(arc
		(start 173.95952 -13.930122)
		(mid 173.761217 -13.633435)
		(end 173.69155 -13.283438)
		(width 0.1524)
		(layer "In5.Cu")
		(net "SAS_BLAD1_TX3_N")
	)
	(arc
		(start 173.69155 -8.697214)
		(mid 173.676711 -8.622991)
		(end 173.634654 -8.560054)
		(width 0.1524)
		(layer "In5.Cu")
		(net "SAS_BLAD1_TX3_N")
	)
	(segment
		(start 190.89497 -25.899872)
		(end 190.89497 -24.808942)
		(width 0.1778)
		(layer "F.Cu")
		(net "SAS_BLAD1_TX3_P")
	)
	(segment
		(start 190.89497 -24.808942)
		(end 190.67018 -24.584152)
		(width 0.1778)
		(layer "F.Cu")
		(net "SAS_BLAD1_TX3_P")
	)
	(segment
		(start 190.67018 -24.03856)
		(end 191.12992 -23.57882)
		(width 0.1778)
		(layer "F.Cu")
		(net "SAS_BLAD1_TX3_P")
	)
	(segment
		(start 190.67018 -24.584152)
		(end 190.67018 -24.03856)
		(width 0.1778)
		(layer "F.Cu")
		(net "SAS_BLAD1_TX3_P")
	)
	(via
		(at 191.12992 -23.57882)
		(size 0.508)
		(drill 0.254)
		(layers "F.Cu" "B.Cu")
		(net "SAS_BLAD1_TX3_P")
	)
	(segment
		(start 181.130194 -13.8176)
		(end 180.977794 -13.97)
		(width 0.1524)
		(layer "In5.Cu")
		(net "SAS_BLAD1_TX3_P")
	)
	(segment
		(start 174.09795 -13.283438)
		(end 174.09795 -8.697468)
		(width 0.1524)
		(layer "In5.Cu")
		(net "SAS_BLAD1_TX3_P")
	)
	(segment
		(start 182.136288 -13.97)
		(end 181.739794 -13.97)
		(width 0.1524)
		(layer "In5.Cu")
		(net "SAS_BLAD1_TX3_P")
	)
	(segment
		(start 176.710594 -13.8176)
		(end 176.253394 -13.8176)
		(width 0.1524)
		(layer "In5.Cu")
		(net "SAS_BLAD1_TX3_P")
	)
	(segment
		(start 176.862994 -13.97)
		(end 176.710594 -13.8176)
		(width 0.1524)
		(layer "In5.Cu")
		(net "SAS_BLAD1_TX3_P")
	)
	(segment
		(start 181.587394 -13.8176)
		(end 181.130194 -13.8176)
		(width 0.1524)
		(layer "In5.Cu")
		(net "SAS_BLAD1_TX3_P")
	)
	(segment
		(start 176.100994 -13.97)
		(end 174.784512 -13.97)
		(width 0.1524)
		(layer "In5.Cu")
		(net "SAS_BLAD1_TX3_P")
	)
	(segment
		(start 178.691794 -13.8176)
		(end 178.539394 -13.97)
		(width 0.1524)
		(layer "In5.Cu")
		(net "SAS_BLAD1_TX3_P")
	)
	(segment
		(start 180.368194 -13.8176)
		(end 179.910994 -13.8176)
		(width 0.1524)
		(layer "In5.Cu")
		(net "SAS_BLAD1_TX3_P")
	)
	(segment
		(start 177.929794 -13.8176)
		(end 177.472594 -13.8176)
		(width 0.1524)
		(layer "In5.Cu")
		(net "SAS_BLAD1_TX3_P")
	)
	(segment
		(start 181.739794 -13.97)
		(end 181.587394 -13.8176)
		(width 0.1524)
		(layer "In5.Cu")
		(net "SAS_BLAD1_TX3_P")
	)
	(segment
		(start 178.539394 -13.97)
		(end 178.082194 -13.97)
		(width 0.1524)
		(layer "In5.Cu")
		(net "SAS_BLAD1_TX3_P")
	)
	(segment
		(start 190.430404 -21.885148)
		(end 182.782972 -14.23797)
		(width 0.1524)
		(layer "In5.Cu")
		(net "SAS_BLAD1_TX3_P")
	)
	(segment
		(start 179.301394 -13.97)
		(end 179.148994 -13.8176)
		(width 0.1524)
		(layer "In5.Cu")
		(net "SAS_BLAD1_TX3_P")
	)
	(segment
		(start 179.758594 -13.97)
		(end 179.301394 -13.97)
		(width 0.1524)
		(layer "In5.Cu")
		(net "SAS_BLAD1_TX3_P")
	)
	(segment
		(start 173.094396 -8.096758)
		(end 172.889926 -7.892288)
		(width 0.1524)
		(layer "In5.Cu")
		(net "SAS_BLAD1_TX3_P")
	)
	(segment
		(start 180.520594 -13.97)
		(end 180.368194 -13.8176)
		(width 0.1524)
		(layer "In5.Cu")
		(net "SAS_BLAD1_TX3_P")
	)
	(segment
		(start 178.082194 -13.97)
		(end 177.929794 -13.8176)
		(width 0.1524)
		(layer "In5.Cu")
		(net "SAS_BLAD1_TX3_P")
	)
	(segment
		(start 190.69812 -23.14702)
		(end 190.69812 -22.531832)
		(width 0.1524)
		(layer "In5.Cu")
		(net "SAS_BLAD1_TX3_P")
	)
	(segment
		(start 179.148994 -13.8176)
		(end 178.691794 -13.8176)
		(width 0.1524)
		(layer "In5.Cu")
		(net "SAS_BLAD1_TX3_P")
	)
	(segment
		(start 176.253394 -13.8176)
		(end 176.100994 -13.97)
		(width 0.1524)
		(layer "In5.Cu")
		(net "SAS_BLAD1_TX3_P")
	)
	(segment
		(start 177.320194 -13.97)
		(end 176.862994 -13.97)
		(width 0.1524)
		(layer "In5.Cu")
		(net "SAS_BLAD1_TX3_P")
	)
	(segment
		(start 191.12992 -23.57882)
		(end 190.69812 -23.14702)
		(width 0.1524)
		(layer "In5.Cu")
		(net "SAS_BLAD1_TX3_P")
	)
	(segment
		(start 174.425356 -13.821156)
		(end 174.246794 -13.642594)
		(width 0.1524)
		(layer "In5.Cu")
		(net "SAS_BLAD1_TX3_P")
	)
	(segment
		(start 172.889926 -7.892288)
		(end 172.889926 -7.600188)
		(width 0.1524)
		(layer "In5.Cu")
		(net "SAS_BLAD1_TX3_P")
	)
	(segment
		(start 179.910994 -13.8176)
		(end 179.758594 -13.97)
		(width 0.1524)
		(layer "In5.Cu")
		(net "SAS_BLAD1_TX3_P")
	)
	(segment
		(start 180.977794 -13.97)
		(end 180.520594 -13.97)
		(width 0.1524)
		(layer "In5.Cu")
		(net "SAS_BLAD1_TX3_P")
	)
	(segment
		(start 177.472594 -13.8176)
		(end 177.320194 -13.97)
		(width 0.1524)
		(layer "In5.Cu")
		(net "SAS_BLAD1_TX3_P")
	)
	(segment
		(start 173.49724 -8.096758)
		(end 173.094396 -8.096758)
		(width 0.1524)
		(layer "In5.Cu")
		(net "SAS_BLAD1_TX3_P")
	)
	(arc
		(start 190.69812 -22.531832)
		(mid 190.628583 -22.181867)
		(end 190.430404 -21.885148)
		(width 0.1524)
		(layer "In5.Cu")
		(net "SAS_BLAD1_TX3_P")
	)
	(arc
		(start 182.782972 -14.23797)
		(mid 182.486285 -14.039667)
		(end 182.136288 -13.97)
		(width 0.1524)
		(layer "In5.Cu")
		(net "SAS_BLAD1_TX3_P")
	)
	(arc
		(start 174.246794 -13.642594)
		(mid 174.136636 -13.477826)
		(end 174.09795 -13.283438)
		(width 0.1524)
		(layer "In5.Cu")
		(net "SAS_BLAD1_TX3_P")
	)
	(arc
		(start 174.784512 -13.97)
		(mid 174.590123 -13.931316)
		(end 174.425356 -13.821156)
		(width 0.1524)
		(layer "In5.Cu")
		(net "SAS_BLAD1_TX3_P")
	)
	(arc
		(start 173.922182 -8.272526)
		(mid 173.727188 -8.142391)
		(end 173.49724 -8.096758)
		(width 0.1524)
		(layer "In5.Cu")
		(net "SAS_BLAD1_TX3_P")
	)
	(arc
		(start 174.09795 -8.697468)
		(mid 174.052322 -8.467518)
		(end 173.922182 -8.272526)
		(width 0.1524)
		(layer "In5.Cu")
		(net "SAS_BLAD1_TX3_P")
	)
	(zone
		(layer "F.Cu")
		(hatch none 0.5)
		(connect_pads
			(clearance 0)
		)
		(min_thickness 0.25)
		(keepout
			(tracks allowed)
			(vias allowed)
			(pads allowed)
			(copperpour allowed)
			(footprints allowed)
		)
		(placement
			(enabled no)
			(sheetname "")
		)
		(fill
			(thermal_gap 0.5)
			(thermal_bridge_width 0.5)
			(island_removal_mode 0)
		)
		(polygon
			(pts
				(xy 412.2674 -21.3868) (xy 412.2674 -18.7198) (xy 415.798 -18.7198) (xy 415.798 -21.3868)
			)
		)
	)
	(zone
		(layer "F.Cu")
		(hatch none 0.5)
		(connect_pads
			(clearance 0)
		)
		(min_thickness 0.25)
		(keepout
			(tracks allowed)
			(vias allowed)
			(pads allowed)
			(copperpour allowed)
			(footprints allowed)
		)
		(placement
			(enabled no)
			(sheetname "")
		)
		(fill
			(thermal_gap 0.5)
			(thermal_bridge_width 0.5)
			(island_removal_mode 0)
		)
		(polygon
			(pts
				(xy 393.5476 -22.7838) (xy 393.5476 -17.8054) (xy 396.2146 -17.8054) (xy 396.2146 -22.7838)
			)
		)
	)
	(zone
		(layer "F.Cu")
		(hatch none 0.5)
		(connect_pads
			(clearance 0)
		)
		(min_thickness 0.25)
		(keepout
			(tracks allowed)
			(vias allowed)
			(pads allowed)
			(copperpour allowed)
			(footprints allowed)
		)
		(placement
			(enabled no)
			(sheetname "")
		)
		(fill
			(thermal_gap 0.5)
			(thermal_bridge_width 0.5)
			(island_removal_mode 0)
		)
		(polygon
			(pts
				(xy 388.0358 -26.5684) (xy 388.0358 -23.3934) (xy 399.3388 -23.3934) (xy 399.3388 -26.5684)
			)
		)
	)
	(zone
		(layer "F.Cu")
		(hatch none 0.5)
		(connect_pads
			(clearance 0)
		)
		(min_thickness 0.25)
		(keepout
			(tracks not_allowed)
			(vias allowed)
			(pads allowed)
			(copperpour not_allowed)
			(footprints allowed)
		)
		(placement
			(enabled no)
			(sheetname "")
		)
		(fill
			(thermal_gap 0.5)
			(thermal_bridge_width 0.5)
			(island_removal_mode 0)
		)
		(polygon
			(pts
				(arc
					(start 4.500118 3.299968)
					(mid -1.156725 0.956827)
					(end -3.499866 -4.700016)
				)
				(arc
					(start -3.499866 -4.700016)
					(mid -2.302954 -8.909286)
					(end 0.92964 -11.859006)
				)
				(xy 1.066546 -11.859006) (xy 1.066546 -11.902694)
				(arc
					(start 1.01854 -11.902694)
					(mid 2.714266 -12.498118)
					(end 4.500118 -12.7)
				)
				(arc
					(start 4.500118 -9.462516)
					(mid -0.262382 -4.700016)
					(end 4.500118 0.062484)
				)
			)
		)
	)
	(zone
		(layer "F.Cu")
		(hatch none 0.5)
		(connect_pads
			(clearance 0)
		)
		(min_thickness 0.25)
		(keepout
			(tracks not_allowed)
			(vias allowed)
			(pads allowed)
			(copperpour not_allowed)
			(footprints allowed)
		)
		(placement
			(enabled no)
			(sheetname "")
		)
		(fill
			(thermal_gap 0.5)
			(thermal_bridge_width 0.5)
			(island_removal_mode 0)
		)
		(polygon
			(pts
				(arc
					(start 424.310048 3.299968)
					(mid 420.22201 2.176588)
					(end 417.282122 -0.878078)
				)
				(xy 417.282122 -1.022858)
				(arc
					(start 417.20516 -1.022858)
					(mid 416.53706 -2.807748)
					(end 416.310064 -4.700016)
				)
				(arc
					(start 416.310064 -4.700016)
					(mid 418.653205 -10.356859)
					(end 424.310048 -12.7)
				)
				(arc
					(start 424.310048 -9.462516)
					(mid 419.547548 -4.700016)
					(end 424.310048 0.062484)
				)
			)
		)
	)
	(zone
		(layer "F.Cu")
		(hatch none 0.5)
		(connect_pads
			(clearance 0)
		)
		(min_thickness 0.25)
		(keepout
			(tracks allowed)
			(vias allowed)
			(pads allowed)
			(copperpour allowed)
			(footprints allowed)
		)
		(placement
			(enabled no)
			(sheetname "")
		)
		(fill
			(thermal_gap 0.5)
			(thermal_bridge_width 0.5)
			(island_removal_mode 0)
		)
		(polygon
			(pts
				(xy 191.0334 -22.0726) (xy 191.0334 -18.1356) (xy 194.945 -18.1356) (xy 194.945 -22.0726)
			)
		)
	)
	(zone
		(layer "F.Cu")
		(hatch none 0.5)
		(connect_pads
			(clearance 0)
		)
		(min_thickness 0.25)
		(keepout
			(tracks allowed)
			(vias allowed)
			(pads allowed)
			(copperpour allowed)
			(footprints allowed)
		)
		(placement
			(enabled no)
			(sheetname "")
		)
		(fill
			(thermal_gap 0.5)
			(thermal_bridge_width 0.5)
			(island_removal_mode 0)
		)
		(polygon
			(pts
				(xy 407.1366 -26.1874) (xy 407.1366 -23.368) (xy 418.465 -23.368) (xy 418.465 -26.1874)
			)
		)
	)
	(zone
		(layer "F.Cu")
		(hatch none 0.5)
		(connect_pads
			(clearance 0)
		)
		(min_thickness 0.25)
		(keepout
			(tracks allowed)
			(vias allowed)
			(pads allowed)
			(copperpour allowed)
			(footprints allowed)
		)
		(placement
			(enabled no)
			(sheetname "")
		)
		(fill
			(thermal_gap 0.5)
			(thermal_bridge_width 0.5)
			(island_removal_mode 0)
		)
		(polygon
			(pts
				(xy 100.965 -11.8618) (xy 100.965 -8.6106) (xy 108.7882 -8.6106) (xy 108.7882 -11.8618)
			)
		)
	)
	(zone
		(layer "F.Cu")
		(hatch none 0.5)
		(connect_pads
			(clearance 0)
		)
		(min_thickness 0.25)
		(keepout
			(tracks allowed)
			(vias allowed)
			(pads allowed)
			(copperpour allowed)
			(footprints allowed)
		)
		(placement
			(enabled no)
			(sheetname "")
		)
		(fill
			(thermal_gap 0.5)
			(thermal_bridge_width 0.5)
			(island_removal_mode 0)
		)
		(polygon
			(pts
				(xy 359.8672 -11.8872) (xy 359.8672 -8.636) (xy 367.5634 -8.636) (xy 367.5634 -11.8872)
			)
		)
	)
	(zone
		(layer "F.Cu")
		(hatch none 0.5)
		(connect_pads
			(clearance 0)
		)
		(min_thickness 0.25)
		(keepout
			(tracks allowed)
			(vias allowed)
			(pads allowed)
			(copperpour allowed)
			(footprints allowed)
		)
		(placement
			(enabled no)
			(sheetname "")
		)
		(fill
			(thermal_gap 0.5)
			(thermal_bridge_width 0.5)
			(island_removal_mode 0)
		)
		(polygon
			(pts
				(xy 186.1566 -26.8986) (xy 186.1566 -23.4188) (xy 197.5612 -23.4188) (xy 197.5612 -26.8986)
			)
		)
	)
	(zone
		(layer "F.Cu")
		(hatch none 0.5)
		(connect_pads
			(clearance 0)
		)
		(min_thickness 0.25)
		(keepout
			(tracks allowed)
			(vias allowed)
			(pads allowed)
			(copperpour allowed)
			(footprints allowed)
		)
		(placement
			(enabled no)
			(sheetname "")
		)
		(fill
			(thermal_gap 0.5)
			(thermal_bridge_width 0.5)
			(island_removal_mode 0)
		)
		(polygon
			(pts
				(xy 185.2422 -30.8356) (xy 185.2422 -27.7876) (xy 196.6468 -27.7876) (xy 196.6468 -30.8356)
			)
		)
	)
	(zone
		(layer "F.Cu")
		(hatch none 0.5)
		(connect_pads
			(clearance 0)
		)
		(min_thickness 0.25)
		(keepout
			(tracks allowed)
			(vias allowed)
			(pads allowed)
			(copperpour allowed)
			(footprints allowed)
		)
		(placement
			(enabled no)
			(sheetname "")
		)
		(fill
			(thermal_gap 0.5)
			(thermal_bridge_width 0.5)
			(island_removal_mode 0)
		)
		(polygon
			(pts
				(xy 138.8872 -11.811) (xy 138.8872 -8.6106) (xy 146.558 -8.6106) (xy 146.558 -11.811)
			)
		)
	)
	(zone
		(layer "F.Cu")
		(hatch none 0.5)
		(connect_pads
			(clearance 0)
		)
		(min_thickness 0.25)
		(keepout
			(tracks allowed)
			(vias allowed)
			(pads allowed)
			(copperpour allowed)
			(footprints allowed)
		)
		(placement
			(enabled no)
			(sheetname "")
		)
		(fill
			(thermal_gap 0.5)
			(thermal_bridge_width 0.5)
			(island_removal_mode 0)
		)
		(polygon
			(pts
				(xy 321.8688 -11.684) (xy 321.8688 -8.6106) (xy 329.5904 -8.6106) (xy 329.5904 -11.684)
			)
		)
	)
	(zone
		(layer "F.Cu")
		(hatch none 0.5)
		(connect_pads
			(clearance 0)
		)
		(min_thickness 0.25)
		(keepout
			(tracks allowed)
			(vias allowed)
			(pads allowed)
			(copperpour allowed)
			(footprints allowed)
		)
		(placement
			(enabled no)
			(sheetname "")
		)
		(fill
			(thermal_gap 0.5)
			(thermal_bridge_width 0.5)
			(island_removal_mode 0)
		)
		(polygon
			(pts
				(xy 388.1628 -31.4452) (xy 388.1628 -28.1686) (xy 398.3482 -28.1686) (xy 398.3482 -31.4452)
			)
		)
	)
	(zone
		(layer "F.Cu")
		(hatch none 0.5)
		(connect_pads
			(clearance 0)
		)
		(min_thickness 0.25)
		(keepout
			(tracks allowed)
			(vias allowed)
			(pads allowed)
			(copperpour allowed)
			(footprints allowed)
		)
		(placement
			(enabled no)
			(sheetname "")
		)
		(fill
			(thermal_gap 0.5)
			(thermal_bridge_width 0.5)
			(island_removal_mode 0)
		)
		(polygon
			(pts
				(xy 172.466 -23.2156) (xy 172.466 -18.6182) (xy 175.4378 -18.6182) (xy 175.4378 -23.2156)
			)
		)
	)
	(zone
		(layer "F.Cu")
		(hatch none 0.5)
		(connect_pads
			(clearance 0)
		)
		(min_thickness 0.25)
		(keepout
			(tracks allowed)
			(vias allowed)
			(pads allowed)
			(copperpour allowed)
			(footprints allowed)
		)
		(placement
			(enabled no)
			(sheetname "")
		)
		(fill
			(thermal_gap 0.5)
			(thermal_bridge_width 0.5)
			(island_removal_mode 0)
		)
		(polygon
			(pts
				(xy 167.2336 -31.4706) (xy 167.2336 -23.495) (xy 178.4858 -23.495) (xy 178.4858 -31.4706)
			)
		)
	)
	(zone
		(layer "F.Cu")
		(hatch none 0.5)
		(connect_pads
			(clearance 0)
		)
		(min_thickness 0.25)
		(keepout
			(tracks allowed)
			(vias allowed)
			(pads allowed)
			(copperpour allowed)
			(footprints allowed)
		)
		(placement
			(enabled no)
			(sheetname "")
		)
		(fill
			(thermal_gap 0.5)
			(thermal_bridge_width 0.5)
			(island_removal_mode 0)
		)
		(polygon
			(pts
				(xy 406.781 -31.2928) (xy 406.781 -28.2448) (xy 417.2712 -28.2448) (xy 417.2712 -31.2928)
			)
		)
	)
	(zone
		(layers "F.Cu" "B.Cu")
		(hatch none 0.5)
		(connect_pads
			(clearance 0)
		)
		(min_thickness 0.25)
		(keepout
			(tracks allowed)
			(vias allowed)
			(pads allowed)
			(copperpour allowed)
			(footprints not_allowed)
		)
		(placement
			(enabled no)
			(sheetname "")
		)
		(fill yes
			(thermal_gap 0.5)
			(thermal_bridge_width 0.5)
			(island_removal_mode 0)
		)
		(polygon
			(pts
				(arc
					(start 425.61002 -49.390046)
					(mid 426.317125 -49.097153)
					(end 426.610018 -48.390048)
				)
				(xy 426.610018 -42.500042)
				(arc
					(start 425.509944 -42.500042)
					(mid 424.449286 -42.06065)
					(end 424.010074 -40.999918)
				)
				(arc
					(start 424.010074 -31.999936)
					(mid 424.449376 -30.939368)
					(end 425.509944 -30.500066)
				)
				(xy 426.610018 -30.500066)
				(arc
					(start 426.610018 -10.999978)
					(mid 426.948099 -10.051371)
					(end 427.809914 -9.530334)
				)
				(arc
					(start 427.809914 -1.999996)
					(mid 427.517021 -1.292891)
					(end 426.809916 -0.999998)
				)
				(arc
					(start 1.999996 -0.999998)
					(mid 1.292891 -1.292891)
					(end 0.999998 -1.999996)
				)
				(xy 0.999998 -51.385724) (xy 1.414272 -51.799998) (xy 9.035796 -51.799998) (xy 9.45007 -51.385724)
				(arc
					(start 9.45007 -42.649902)
					(mid 10.80008 -41.299892)
					(end 12.15009 -42.649902)
				)
				(xy 12.15009 -51.385724) (xy 12.56411 -51.799998) (xy 50.665888 -51.799998) (xy 51.079908 -51.385724)
				(arc
					(start 51.079908 -43.319954)
					(mid 51.665693 -41.905743)
					(end 53.079904 -41.319958)
				)
				(arc
					(start 55.0799 -41.319958)
					(mid 56.494111 -41.905743)
					(end 57.079896 -43.319954)
				)
				(arc
					(start 57.079896 -50.31994)
					(mid 57.372789 -51.027045)
					(end 58.079894 -51.319938)
				)
				(xy 95.069914 -51.319938)
				(arc
					(start 95.069914 -50.8)
					(mid 95.655699 -49.385789)
					(end 97.06991 -48.800004)
				)
				(arc
					(start 112.06988 -48.800004)
					(mid 113.484091 -49.385789)
					(end 114.069876 -50.8)
				)
				(xy 114.069876 -51.319938) (xy 132.990082 -51.319938)
				(arc
					(start 132.990082 -50.8)
					(mid 133.575867 -49.385789)
					(end 134.990078 -48.800004)
				)
				(arc
					(start 149.990048 -48.800004)
					(mid 151.404259 -49.385789)
					(end 151.990044 -50.8)
				)
				(xy 151.990044 -51.319938)
				(arc
					(start 158.99003 -51.319938)
					(mid 159.600174 -49.950983)
					(end 160.990026 -49.390046)
				)
				(arc
					(start 202.989942 -49.390046)
					(mid 204.379146 -49.951259)
					(end 204.988668 -51.319938)
				)
				(xy 316.06998 -51.319938)
				(arc
					(start 316.06998 -50.8)
					(mid 316.655765 -49.385789)
					(end 318.069976 -48.800004)
				)
				(arc
					(start 333.069946 -48.800004)
					(mid 334.484157 -49.385789)
					(end 335.069942 -50.8)
				)
				(xy 335.069942 -51.319938) (xy 353.989894 -51.319938)
				(arc
					(start 353.989894 -50.8)
					(mid 354.575679 -49.385789)
					(end 355.98989 -48.800004)
				)
				(arc
					(start 370.990114 -48.800004)
					(mid 372.404325 -49.385789)
					(end 372.99011 -50.8)
				)
				(xy 372.99011 -51.319938)
				(arc
					(start 379.990096 -51.319938)
					(mid 380.60024 -49.950983)
					(end 381.990092 -49.390046)
				)
			)
		)
	)
	(zone
		(layers "F.Cu" "B.Cu" "In1.Cu" "In2.Cu" "In3.Cu" "In4.Cu" "In5.Cu" "In6.Cu")
		(name "Package Keepin")
		(hatch none 0.5)
		(connect_pads
			(clearance 0)
		)
		(min_thickness 0.25)
		(keepout
			(tracks allowed)
			(vias allowed)
			(pads allowed)
			(copperpour allowed)
			(footprints allowed)
		)
		(placement
			(enabled no)
			(sheetname "")
		)
		(fill
			(thermal_gap 0.5)
			(thermal_bridge_width 0.5)
			(island_removal_mode 0)
		)
		(polygon
			(pts
				(arc
					(start 425.61002 -49.374044)
					(mid 426.30581 -49.085838)
					(end 426.594016 -48.390048)
				)
				(xy 426.594016 -42.516044)
				(arc
					(start 425.509944 -42.516044)
					(mid 424.437971 -42.071966)
					(end 423.994072 -40.999918)
				)
				(arc
					(start 423.994072 -31.999936)
					(mid 424.438061 -30.928053)
					(end 425.509944 -30.484064)
				)
				(xy 426.594016 -30.484064)
				(arc
					(start 426.594016 -10.999978)
					(mid 426.931576 -10.046328)
					(end 427.793912 -9.51738)
				)
				(arc
					(start 427.793912 -1.999996)
					(mid 427.505706 -1.304206)
					(end 426.809916 -1.016)
				)
				(arc
					(start 1.999996 -1.016)
					(mid 1.304206 -1.304206)
					(end 1.016 -1.999996)
				)
				(xy 1.016 -51.37912) (xy 1.71831 -52.08143) (xy 1.920748 -52.283868) (xy 8.52932 -52.283868) (xy 8.731758 -52.08143)
				(xy 9.434068 -51.37912)
				(arc
					(start 9.434068 -42.649902)
					(mid 10.80008 -41.28389)
					(end 12.166092 -42.649902)
				)
				(xy 12.166092 -51.37912) (xy 13.07084 -52.283868) (xy 50.159158 -52.283868) (xy 51.063906 -51.37912)
				(arc
					(start 51.063906 -43.319954)
					(mid 51.654378 -41.894428)
					(end 53.079904 -41.303956)
				)
				(arc
					(start 55.0799 -41.303956)
					(mid 56.505426 -41.894428)
					(end 57.095898 -43.319954)
				)
				(arc
					(start 57.095898 -50.31994)
					(mid 57.384104 -51.01573)
					(end 58.079894 -51.303936)
				)
				(xy 95.053912 -51.303936)
				(arc
					(start 95.053912 -50.8)
					(mid 95.644384 -49.374474)
					(end 97.06991 -48.784002)
				)
				(arc
					(start 112.06988 -48.784002)
					(mid 113.495406 -49.374474)
					(end 114.085878 -50.8)
				)
				(xy 114.085878 -51.303936) (xy 132.97408 -51.303936)
				(arc
					(start 132.97408 -50.8)
					(mid 133.564552 -49.374474)
					(end 134.990078 -48.784002)
				)
				(arc
					(start 149.990048 -48.784002)
					(mid 151.415574 -49.374474)
					(end 152.006046 -50.8)
				)
				(xy 152.006046 -51.303936) (xy 158.890208 -51.303936) (xy 158.962344 -51.289712) (xy 158.99003 -51.156616)
				(xy 159.12465 -50.580036) (xy 159.562546 -49.93894) (xy 160.218882 -49.506124) (xy 160.89122 -49.374044)
				(xy 203.088748 -49.374044) (xy 203.761086 -49.506124) (xy 204.417422 -49.93894) (xy 204.855318 -50.580036)
				(xy 204.989938 -51.156616) (xy 205.017624 -51.289712) (xy 205.08976 -51.303936) (xy 316.053978 -51.303936)
				(arc
					(start 316.053978 -50.8)
					(mid 316.64445 -49.374474)
					(end 318.069976 -48.784002)
				)
				(arc
					(start 333.069946 -48.784002)
					(mid 334.495472 -49.374474)
					(end 335.085944 -50.8)
				)
				(xy 335.085944 -51.303936) (xy 353.973892 -51.303936)
				(arc
					(start 353.973892 -50.8)
					(mid 354.564364 -49.374474)
					(end 355.98989 -48.784002)
				)
				(arc
					(start 370.990114 -48.784002)
					(mid 372.41564 -49.374474)
					(end 373.006112 -50.8)
				)
				(xy 373.006112 -51.303936) (xy 379.890274 -51.303936) (xy 379.96241 -51.289712) (xy 379.990096 -51.156616)
				(xy 380.124716 -50.580036) (xy 380.562612 -49.93894) (xy 381.218948 -49.506124) (xy 381.891286 -49.374044)
			)
		)
	)
	(zone
		(layers "F.Cu" "B.Cu" "In1.Cu" "In2.Cu" "In3.Cu" "In4.Cu" "In5.Cu" "In6.Cu")
		(name "Route Keepin")
		(hatch none 0.5)
		(connect_pads
			(clearance 0)
		)
		(min_thickness 0.25)
		(keepout
			(tracks allowed)
			(vias allowed)
			(pads allowed)
			(copperpour allowed)
			(footprints allowed)
		)
		(placement
			(enabled no)
			(sheetname "")
		)
		(fill
			(thermal_gap 0.5)
			(thermal_bridge_width 0.5)
			(island_removal_mode 0)
		)
		(polygon
			(pts
				(arc
					(start 425.61002 -49.882044)
					(mid 426.66502 -49.445048)
					(end 427.102016 -48.390048)
				)
				(xy 427.102016 -42.008044)
				(arc
					(start 425.509944 -42.008044)
					(mid 424.797181 -41.712755)
					(end 424.502072 -40.999918)
				)
				(arc
					(start 424.502072 -31.999936)
					(mid 424.797271 -31.287263)
					(end 425.509944 -30.992064)
				)
				(xy 427.102016 -30.992064)
				(arc
					(start 427.102016 -10.999978)
					(mid 427.397215 -10.287305)
					(end 428.109888 -9.992106)
				)
				(xy 428.301912 -9.992106)
				(arc
					(start 428.301912 -1.999996)
					(mid 427.864916 -0.944996)
					(end 426.809916 -0.508)
				)
				(arc
					(start 1.999996 -0.508)
					(mid 0.944996 -0.944996)
					(end 0.508 -1.999996)
				)
				(xy 0.508 -51.589686) (xy 1.359154 -52.44084) (xy 1.710436 -52.791868) (xy 8.739632 -52.791868)
				(xy 9.090914 -52.44084) (xy 9.942068 -51.589686)
				(arc
					(start 9.942068 -42.649902)
					(mid 10.80008 -41.79189)
					(end 11.658092 -42.649902)
				)
				(xy 11.658092 -51.589686) (xy 12.860274 -52.791868) (xy 50.369724 -52.791868) (xy 51.571906 -51.589686)
				(arc
					(start 51.571906 -43.319954)
					(mid 52.013588 -42.253638)
					(end 53.079904 -41.811956)
				)
				(arc
					(start 55.0799 -41.811956)
					(mid 56.146216 -42.253638)
					(end 56.587898 -43.319954)
				)
				(arc
					(start 56.587898 -50.31994)
					(mid 57.024894 -51.37494)
					(end 58.079894 -51.811936)
				)
				(arc
					(start 95.069914 -51.811936)
					(mid 95.417809 -51.667833)
					(end 95.561912 -51.319938)
				)
				(arc
					(start 95.561912 -50.8)
					(mid 96.003594 -49.733684)
					(end 97.06991 -49.292002)
				)
				(arc
					(start 112.06988 -49.292002)
					(mid 113.136196 -49.733684)
					(end 113.577878 -50.8)
				)
				(arc
					(start 113.577878 -51.319938)
					(mid 113.721981 -51.667833)
					(end 114.069876 -51.811936)
				)
				(arc
					(start 132.990082 -51.811936)
					(mid 133.337977 -51.667833)
					(end 133.48208 -51.319938)
				)
				(arc
					(start 133.48208 -50.8)
					(mid 133.923762 -49.733684)
					(end 134.990078 -49.292002)
				)
				(arc
					(start 149.990048 -49.292002)
					(mid 151.056364 -49.733684)
					(end 151.498046 -50.8)
				)
				(arc
					(start 151.498046 -51.319938)
					(mid 151.642149 -51.667833)
					(end 151.990044 -51.811936)
				)
				(xy 158.939992 -51.811936) (xy 159.174434 -51.765454) (xy 159.330898 -51.660806) (xy 159.436816 -51.50231)
				(xy 159.486092 -51.266344) (xy 159.597598 -50.788062) (xy 159.925512 -50.308002) (xy 160.41497 -49.985168)
				(xy 160.940496 -49.882044) (xy 203.039472 -49.882044) (xy 203.564998 -49.985168) (xy 204.054456 -50.308002)
				(xy 204.38237 -50.788062) (xy 204.493876 -51.266344) (xy 204.543152 -51.50231) (xy 204.64907 -51.660806)
				(xy 204.805534 -51.765454) (xy 205.039976 -51.811936)
				(arc
					(start 316.06998 -51.811936)
					(mid 316.417875 -51.667833)
					(end 316.561978 -51.319938)
				)
				(arc
					(start 316.561978 -50.8)
					(mid 317.00366 -49.733684)
					(end 318.069976 -49.292002)
				)
				(arc
					(start 333.069946 -49.292002)
					(mid 334.136262 -49.733684)
					(end 334.577944 -50.8)
				)
				(arc
					(start 334.577944 -51.319938)
					(mid 334.722047 -51.667833)
					(end 335.069942 -51.811936)
				)
				(arc
					(start 353.989894 -51.811936)
					(mid 354.337789 -51.667833)
					(end 354.481892 -51.319938)
				)
				(arc
					(start 354.481892 -50.8)
					(mid 354.923574 -49.733684)
					(end 355.98989 -49.292002)
				)
				(arc
					(start 370.990114 -49.292002)
					(mid 372.05643 -49.733684)
					(end 372.498112 -50.8)
				)
				(arc
					(start 372.498112 -51.319938)
					(mid 372.642215 -51.667833)
					(end 372.99011 -51.811936)
				)
				(xy 379.940058 -51.811936) (xy 380.1745 -51.765454) (xy 380.330964 -51.660806) (xy 380.436882 -51.50231)
				(xy 380.486158 -51.266344) (xy 380.597664 -50.788062) (xy 380.925578 -50.308002) (xy 381.415036 -49.985168)
				(xy 381.940562 -49.882044)
			)
		)
	)
	(zone
		(layer "B.Cu")
		(hatch none 0.5)
		(connect_pads
			(clearance 0)
		)
		(min_thickness 0.25)
		(keepout
			(tracks not_allowed)
			(vias allowed)
			(pads allowed)
			(copperpour not_allowed)
			(footprints allowed)
		)
		(placement
			(enabled no)
			(sheetname "")
		)
		(fill
			(thermal_gap 0.5)
			(thermal_bridge_width 0.5)
			(island_removal_mode 0)
		)
		(polygon
			(pts
				(arc
					(start 424.310048 -15.707868)
					(mid 427.851232 -14.241114)
					(end 429.318166 -10.700004)
				)
				(xy 429.318166 -8.977122) (xy 429.316896 -8.975852) (xy 429.316896 -8.311642) (xy 429.318166 -8.311642)
				(arc
					(start 429.318166 -4.700016)
					(mid 427.851322 -1.158742)
					(end 424.310048 0.308102)
				)
				(arc
					(start 424.310048 -0.174498)
					(mid 427.510072 -1.499992)
					(end 428.835566 -4.700016)
				)
				(arc
					(start 428.835566 -10.700004)
					(mid 427.510072 -13.900028)
					(end 424.310048 -15.225522)
				)
			)
		)
	)
	(zone
		(layer "B.Cu")
		(hatch none 0.5)
		(connect_pads
			(clearance 0)
		)
		(min_thickness 0.25)
		(keepout
			(tracks allowed)
			(vias allowed)
			(pads allowed)
			(copperpour allowed)
			(footprints allowed)
		)
		(placement
			(enabled no)
			(sheetname "")
		)
		(fill
			(thermal_gap 0.5)
			(thermal_bridge_width 0.5)
			(island_removal_mode 0)
		)
		(polygon
			(pts
				(xy 166.2176 -12.7762) (xy 166.2176 -5.6388) (xy 175.387 -5.6388) (xy 175.387 -12.7762)
			)
		)
	)
	(zone
		(layer "B.Cu")
		(hatch none 0.5)
		(connect_pads
			(clearance 0)
		)
		(min_thickness 0.25)
		(keepout
			(tracks allowed)
			(vias allowed)
			(pads allowed)
			(copperpour allowed)
			(footprints allowed)
		)
		(placement
			(enabled no)
			(sheetname "")
		)
		(fill
			(thermal_gap 0.5)
			(thermal_bridge_width 0.5)
			(island_removal_mode 0)
		)
		(polygon
			(pts
				(xy 387.4516 -12.7) (xy 387.4516 -5.6642) (xy 396.494 -5.6642) (xy 396.494 -12.7)
			)
		)
	)
	(zone
		(layer "In3.Cu")
		(hatch none 0.5)
		(connect_pads
			(clearance 0)
		)
		(min_thickness 0.25)
		(keepout
			(tracks not_allowed)
			(vias allowed)
			(pads allowed)
			(copperpour not_allowed)
			(footprints allowed)
		)
		(placement
			(enabled no)
			(sheetname "")
		)
		(fill
			(thermal_gap 0.5)
			(thermal_bridge_width 0.5)
			(island_removal_mode 0)
		)
		(polygon
			(pts
				(arc
					(start 8.660892 -4.700016)
					(mid 0.339344 -4.700016)
					(end 8.660892 -4.700016)
				)
			)
		)
	)
	(zone
		(layer "In3.Cu")
		(hatch none 0.5)
		(connect_pads
			(clearance 0)
		)
		(min_thickness 0.25)
		(keepout
			(tracks not_allowed)
			(vias allowed)
			(pads allowed)
			(copperpour not_allowed)
			(footprints allowed)
		)
		(placement
			(enabled no)
			(sheetname "")
		)
		(fill
			(thermal_gap 0.5)
			(thermal_bridge_width 0.5)
			(island_removal_mode 0)
		)
		(polygon
			(pts
				(arc
					(start 428.449232 -4.700016)
					(mid 420.170864 -4.700016)
					(end 428.449232 -4.700016)
				)
			)
		)
	)
	(zone
		(layer "In4.Cu")
		(hatch none 0.5)
		(connect_pads
			(clearance 0)
		)
		(min_thickness 0.25)
		(keepout
			(tracks not_allowed)
			(vias allowed)
			(pads allowed)
			(copperpour not_allowed)
			(footprints allowed)
		)
		(placement
			(enabled no)
			(sheetname "")
		)
		(fill
			(thermal_gap 0.5)
			(thermal_bridge_width 0.5)
			(island_removal_mode 0)
		)
		(polygon
			(pts
				(arc
					(start 8.647176 -4.700016)
					(mid 0.35306 -4.700016)
					(end 8.647176 -4.700016)
				)
			)
		)
	)
	(zone
		(layer "In4.Cu")
		(hatch none 0.5)
		(connect_pads
			(clearance 0)
		)
		(min_thickness 0.25)
		(keepout
			(tracks not_allowed)
			(vias allowed)
			(pads allowed)
			(copperpour not_allowed)
			(footprints allowed)
		)
		(placement
			(enabled no)
			(sheetname "")
		)
		(fill
			(thermal_gap 0.5)
			(thermal_bridge_width 0.5)
			(island_removal_mode 0)
		)
		(polygon
			(pts
				(arc
					(start 428.424594 -4.700016)
					(mid 420.195502 -4.700016)
					(end 428.424594 -4.700016)
				)
			)
		)
	)
	(zone
		(layer "In5.Cu")
		(hatch none 0.5)
		(connect_pads
			(clearance 0)
		)
		(min_thickness 0.25)
		(keepout
			(tracks allowed)
			(vias allowed)
			(pads allowed)
			(copperpour allowed)
			(footprints allowed)
		)
		(placement
			(enabled no)
			(sheetname "")
		)
		(fill
			(thermal_gap 0.5)
			(thermal_bridge_width 0.5)
			(island_removal_mode 0)
		)
		(polygon
			(pts
				(xy 164.211 -14.5034) (xy 164.211 -1.5748) (xy 175.4632 -1.5748) (xy 175.4632 -14.5034)
			)
		)
	)
	(zone
		(layer "In5.Cu")
		(hatch none 0.5)
		(connect_pads
			(clearance 0)
		)
		(min_thickness 0.25)
		(keepout
			(tracks allowed)
			(vias allowed)
			(pads allowed)
			(copperpour allowed)
			(footprints allowed)
		)
		(placement
			(enabled no)
			(sheetname "")
		)
		(fill
			(thermal_gap 0.5)
			(thermal_bridge_width 0.5)
			(island_removal_mode 0)
		)
		(polygon
			(pts
				(xy 385.2418 -14.5796) (xy 385.2418 -1.3462) (xy 397.002 -1.3462) (xy 397.002 -14.5796)
			)
		)
	)
)
